G04 ================== begin FILE IDENTIFICATION RECORD ==================*
G04 Layout Name:  D:/<user>/Wistron_project/16342-2/gbr/16342-2.brd*
G04 Film Name:    NOTICE*
G04 File Format:  Gerber RS274X*
G04 File Origin:  Cadence Allegro 16.5-S056*
G04 Origin Date:  Mon Aug 07 11:24:33 2017*
G04 *
G04 Layer:  MANUFACTURING/THERMAL*
G04 *
G04 Offset:    (0.00 0.00)*
G04 Mirror:    No*
G04 Mode:      Positive*
G04 Rotation:  0*
G04 FullContactRelief:  No*
G04 UndefLineWidth:     6.00*
G04 ================== end FILE IDENTIFICATION RECORD ====================*
%FSLAX35Y35*MOIN*%
%IR0*IPPOS*OFA0.00000B0.00000*MIA0B0*SFA1.00000B1.00000*%
%ADD10C,.004*%
%ADD11C,.006*%
%ADD12C,.0033*%
%ADD13C,.008*%
%ADD14C,.0055*%
G75*
%LPD*%
G75*
G36*
G01X301800Y213890D02*
G02X352500Y214150I25558J-40503D01*
G01X341350Y192820D01*
X312850D01*
X301800Y213890D01*
G37*
G36*
G01X298620Y274980D02*
X307300D01*
G03X341410Y274970I17058J11442D01*
G01X348960D01*
X338090Y253970D01*
X309590D01*
X298620Y274980D01*
G37*
G54D10*
G01X770009Y177889D02*
X790009D01*
G01X820009Y167889D02*
X770009D01*
G01D02*
Y177889D01*
G01Y257889D02*
X790009D01*
G01X770009Y247889D02*
Y257889D01*
G01X790009Y247889D02*
X770009D01*
G01Y217889D02*
X790009D01*
G01X770009Y207889D02*
Y217889D01*
G01X790009Y207889D02*
X770009D01*
G01Y297889D02*
X810009D01*
G01X770009Y287889D02*
Y297889D01*
G01X790009Y287889D02*
X770009D01*
G01X852594Y151868D02*
Y155868D01*
G01X840009Y167889D02*
X890009D01*
G01X840009Y225249D02*
Y167889D01*
G01X859454Y153868D02*
X840594D01*
G01X852594Y155868D02*
X840594Y153868D01*
G01Y141868D02*
Y161868D01*
G01Y153868D02*
X852594Y151868D01*
G01X820594Y153868D02*
X808594Y155868D01*
G01X820009Y224740D02*
Y167889D01*
G01X820594Y161868D02*
Y141868D01*
G01X808594Y155868D02*
Y151868D01*
G01D02*
X820594Y153868D01*
G01X790009Y177889D02*
Y207889D01*
G01X796594Y153868D02*
X820594D01*
G01X845009Y225249D02*
X961000D01*
G01X850009Y297889D02*
Y235249D01*
G01D02*
X840009Y225249D01*
G01X810005Y234744D02*
X810009Y234740D01*
G01Y297889D02*
Y234740D01*
G01D02*
X820009Y224740D01*
G01X790009Y257889D02*
Y287889D01*
G01Y217889D02*
Y247889D01*
G01X850514Y319548D02*
Y299548D01*
G01Y307548D02*
X859374D01*
G01X838514Y309548D02*
Y305548D01*
G01X850514Y307548D02*
X838514Y309548D01*
G01Y305548D02*
X850514Y307548D01*
G01X890009Y297889D02*
X850009D01*
G01X810514Y319548D02*
Y299548D01*
G01X822514Y305548D02*
Y309548D01*
G01X810514Y307548D02*
X822514Y305548D01*
G01Y309548D02*
X810514Y307548D01*
G01D02*
X850514D01*
G01X890009Y167889D02*
Y177889D01*
G01X870009D02*
Y207889D01*
G01X890009Y177889D02*
X870009D01*
G01X895009Y217889D02*
X961000D01*
G01X890009Y247889D02*
Y257889D01*
G01Y207889D02*
X890000Y217800D01*
G01X870009Y257889D02*
Y287889D01*
G01X890009Y257889D02*
X870009D01*
G01Y247889D02*
X890009D01*
G01X870009Y217889D02*
Y247889D01*
G01X890009Y217889D02*
X870009D01*
G01Y207889D02*
X890009D01*
G01Y287889D02*
Y297889D01*
G01X870009Y287889D02*
X890009D01*
G01X958000Y205889D02*
X956000Y217889D01*
X954000Y205889D01*
X958000D01*
G01X956000Y193889D02*
Y217889D01*
G01X954000Y237249D02*
X956000Y225249D01*
X958000Y237249D01*
X954000D01*
G01X956000Y249249D02*
Y225249D01*
G01X1121654Y169388D02*
Y232028D01*
G01X1133654Y149388D02*
Y153388D01*
G01X1121654Y151388D02*
X1133654Y149388D01*
G01Y153388D02*
X1121654Y151388D01*
G01D02*
X1161654D01*
G01X1121654Y163388D02*
Y143388D01*
G01X1101654Y209388D02*
Y179388D01*
G01D02*
X1081654D01*
G01Y169388D02*
X1121654D01*
G01X1081654Y179388D02*
Y169388D01*
G01X1131654Y242028D02*
Y299388D01*
G01X1121654Y232028D02*
X1131654Y242028D01*
G01X1101654Y289388D02*
Y259388D01*
G01Y249388D02*
Y219388D01*
G01X1081654Y249388D02*
X1101654D01*
G01X1081654Y259388D02*
Y249388D01*
G01X1101654Y259388D02*
X1081654D01*
G01Y209388D02*
X1101654D01*
G01X1081654Y219388D02*
Y209388D01*
G01X1101654Y219388D02*
X1081654D01*
G01X1119654Y321388D02*
Y317388D01*
G01X1131654Y319388D02*
X1119654Y321388D01*
G01Y317388D02*
X1131654Y319388D01*
G01Y327388D02*
Y307388D01*
G01X1107654Y319388D02*
X1131654D01*
G01Y299388D02*
X1081654D01*
G01Y289388D02*
X1101654D01*
G01X1081654Y299388D02*
Y289388D01*
G01X1201654Y179388D02*
Y169388D01*
G01X1181654Y179388D02*
X1201654D01*
G01X1181654Y209388D02*
Y179388D01*
G01X1161654Y169388D02*
Y232537D01*
G01X1201654Y169388D02*
X1161654D01*
G01X1149654Y153388D02*
Y149388D01*
G01X1161654Y151388D02*
X1149654Y153388D01*
G01Y149388D02*
X1161654Y151388D01*
G01D02*
X1170514D01*
G01X1161654Y163388D02*
Y143388D01*
G01X1201654Y259388D02*
Y249388D01*
G01Y219388D02*
Y209388D01*
G01Y249388D02*
X1181654D01*
G01Y259388D02*
X1201654D01*
G01X1181654Y289388D02*
Y259388D01*
G01X1201654Y209388D02*
X1181654D01*
G01Y219388D02*
X1201654D01*
G01X1181654Y249388D02*
Y219388D01*
G01X1161658Y232533D02*
X1161654Y232537D01*
G01X1151654Y242537D02*
Y299388D01*
G01X1161654Y232537D02*
X1151654Y242537D01*
G01X1201654Y299388D02*
Y289388D01*
G01X1163654Y317388D02*
Y321388D01*
G01X1201654Y289388D02*
X1181654D01*
G01X1170514Y319388D02*
X1151654D01*
G01D02*
X1163654Y317388D01*
G01Y321388D02*
X1151654Y319388D01*
G01Y307388D02*
Y327388D01*
G01Y299388D02*
X1201654D01*
G54D11*
G01X4300Y524700D02*
X4250D01*
G01X54300Y770700D02*
X54250D01*
G01X288350Y208820D02*
X283350D01*
Y182820D01*
X288350D01*
G01X285090Y269970D02*
X280090D01*
Y243970D01*
X285090D01*
G01X283590Y340830D02*
X278590D01*
Y314830D01*
X283590D01*
G01Y319830D02*
Y314830D01*
X361090D01*
Y319830D01*
G01X283590D02*
X303090D01*
X292090Y340830D01*
X283590D01*
Y345830D01*
X297090D01*
X308090Y324830D01*
X336590D01*
X347590Y345830D01*
X361090D01*
Y340830D01*
X352590D01*
X341590Y319830D01*
X361090D01*
G01X288350Y187820D02*
X307850D01*
X296850Y208820D01*
X288350D01*
Y213820D01*
X301850D01*
X312850Y192820D01*
X341350D01*
X352350Y213820D01*
X365850D01*
Y208820D01*
X357350D01*
X346350Y187820D01*
X365850D01*
G01X288350D02*
Y182820D01*
X365850D01*
Y187820D01*
G01X332370Y221310D02*
X388140D01*
G01X329290Y266000D02*
X387990D01*
G01X346210Y275010D02*
X387990D01*
G01X285090Y248970D02*
X304590D01*
X293590Y269970D01*
X285090D01*
Y274970D01*
X298590D01*
X309590Y253970D01*
X338090D01*
X349090Y274970D01*
X362590D01*
Y269970D01*
X354090D01*
X343090Y248970D01*
X362590D01*
G01X285090D02*
Y243970D01*
X362590D01*
Y248970D01*
G01X329590Y306830D02*
X341590Y308830D01*
X329590Y310830D01*
Y306830D01*
G01X339890Y308830D02*
X341590D01*
G01X315090Y310830D02*
X303090Y308830D01*
X315090Y306830D01*
Y310830D01*
G01X306290Y308830D02*
X303090D01*
G01X339590D02*
X304090D01*
G01X340590Y350830D02*
X352590Y352830D01*
X340590Y354830D01*
Y350830D01*
G01X334890Y352830D02*
X352590D01*
G01X304090Y354830D02*
X292090Y352830D01*
X304090Y350830D01*
Y354830D01*
G01X311290Y352830D02*
X292090D01*
G01X385140Y202130D02*
X383140Y214130D01*
X381140Y202130D01*
X385140D01*
G01X383140Y197250D02*
Y214130D01*
G01X365850Y208820D02*
X370850D01*
Y182820D01*
X365850D01*
G01X385140Y233310D02*
X383140Y221310D01*
X381140Y233310D01*
X385140D01*
G01X383140Y237850D02*
Y221310D01*
G01X357370Y214130D02*
X388140D01*
G01X384990Y287010D02*
X382990Y275010D01*
X380990Y287010D01*
X384990D01*
G01X382990Y275010D02*
Y290150D01*
G01X384990Y254000D02*
X382990Y266000D01*
X380990Y254000D01*
X384990D01*
G01X382990Y250500D02*
Y266000D01*
G01X362590Y269970D02*
X367590D01*
Y243970D01*
X362590D01*
G01X361090Y340830D02*
X366090D01*
Y314830D01*
X361090D01*
G01X849500Y-12500D02*
Y59500D01*
X893500D01*
Y-12500D01*
X849500D01*
G01Y-12451D02*
X821000Y-12500D01*
G01X837503Y-14472D02*
X849500Y-12451D01*
X837497Y-10472D01*
X837503Y-14472D01*
G01X864500Y72000D02*
X849500Y69500D01*
X864500Y67000D01*
Y72000D01*
G01X893500Y69500D02*
X849500D01*
G01Y64500D02*
Y79500D01*
G01X827500Y639629D02*
X830000Y624629D01*
X832500Y639629D01*
X827500D01*
G01X830000Y661875D02*
Y624629D01*
G01X931340D02*
X820000D01*
G01X830000Y693125D02*
Y725829D01*
G01X832500Y710829D02*
X830000Y725829D01*
X827500Y710829D01*
X832500D01*
G01X846340Y725829D02*
X820000D01*
G01X903500Y-12500D02*
X944500D01*
G01X903500Y59500D02*
X944500D01*
G01X878500Y67000D02*
X893500Y69500D01*
X878500Y72000D01*
Y67000D01*
G01X901475Y69500D02*
X893500D01*
G01Y64500D02*
Y79500D01*
G01X932000Y2500D02*
X934500Y-12500D01*
X937000Y2500D01*
X932000D01*
G01X934500Y11875D02*
Y-12500D01*
G01X937000Y44500D02*
X934500Y59500D01*
X932000Y44500D01*
X937000D01*
G01X934500Y43125D02*
Y59500D01*
G01X1114953Y628479D02*
X1131500Y617000D01*
X1132500D01*
G01X1119916Y626861D02*
X1114953Y628479D01*
X1118206Y624397D01*
X1119916Y626861D01*
G01X1156654Y242537D02*
X1274500D01*
G01X1206654Y249388D02*
X1274500D01*
G01X1267500Y261388D02*
X1269500Y249388D01*
X1271500Y261388D01*
X1267500D01*
G01X1269500Y277200D02*
Y249388D01*
G01X1271500Y230537D02*
X1269500Y242537D01*
X1267500Y230537D01*
X1271500D01*
G01X1269500Y218537D02*
Y242537D01*
G01X11750Y-48833D02*
X12417Y-49250D01*
X13167Y-49500D01*
X13833D01*
X14500Y-49250D01*
X15000Y-48833D01*
X15250Y-48250D01*
X15083Y-47667D01*
X14667Y-47167D01*
X13917Y-46833D01*
X12917Y-46667D01*
X12333Y-46333D01*
X12083Y-45750D01*
X12250Y-45167D01*
X12667Y-44750D01*
X13250Y-44500D01*
X13833D01*
X14417Y-44667D01*
X14917Y-45083D01*
G01X19100Y-46167D02*
Y-49500D01*
G01Y-44833D02*
X18933Y-44750D01*
Y-44583D01*
X19100Y-44500D01*
X19267Y-44583D01*
Y-44750D01*
X19100Y-44833D01*
G01X24700Y-49500D02*
Y-44500D01*
G01X28883Y-49500D02*
Y-44500D01*
G01X31550Y-46167D02*
X28883Y-48083D01*
G01X29967Y-47333D02*
X31717Y-49500D01*
G01X34650Y-48917D02*
X35067Y-49250D01*
X35650Y-49500D01*
X36150D01*
X36650Y-49333D01*
X36983Y-49083D01*
X37150Y-48750D01*
X37067Y-48250D01*
X36733Y-48000D01*
X35233Y-47500D01*
X34900Y-46917D01*
X35067Y-46500D01*
X35400Y-46250D01*
X35900Y-46167D01*
X36400Y-46250D01*
X36900Y-46500D01*
G01X42833Y-46583D02*
X42250Y-46250D01*
X41750Y-46167D01*
X41083Y-46333D01*
X40583Y-46667D01*
X40250Y-47250D01*
X40167Y-47833D01*
X40250Y-48417D01*
X40583Y-48917D01*
X41083Y-49333D01*
X41750Y-49500D01*
X42333Y-49333D01*
X42833Y-49000D01*
G01X45933Y-49500D02*
Y-46167D01*
G01Y-46833D02*
X46350Y-46500D01*
X46767Y-46250D01*
X47350Y-46167D01*
X47767Y-46250D01*
X48267Y-46500D01*
G01X51450Y-47250D02*
X54117D01*
X53867Y-46667D01*
X53450Y-46333D01*
X52867Y-46167D01*
X52283Y-46250D01*
X51783Y-46500D01*
X51450Y-47083D01*
X51283Y-47583D01*
Y-48083D01*
X51450Y-48583D01*
X51867Y-49083D01*
X52367Y-49417D01*
X52950Y-49500D01*
X53533Y-49333D01*
X54117Y-48833D01*
G01X57050Y-47250D02*
X59717D01*
X59467Y-46667D01*
X59050Y-46333D01*
X58467Y-46167D01*
X57883Y-46250D01*
X57383Y-46500D01*
X57050Y-47083D01*
X56883Y-47583D01*
Y-48083D01*
X57050Y-48583D01*
X57467Y-49083D01*
X57967Y-49417D01*
X58550Y-49500D01*
X59133Y-49333D01*
X59717Y-48833D01*
G01X62483Y-49500D02*
Y-46167D01*
G01Y-47000D02*
X62817Y-46583D01*
X63317Y-46250D01*
X63983Y-46167D01*
X64567Y-46250D01*
X65067Y-46583D01*
X65317Y-47167D01*
Y-49500D01*
G01X0Y-24500D02*
X694500D01*
G01X0Y716000D02*
Y-69500D01*
G01D02*
X694500D01*
G01X11750Y-3833D02*
X12417Y-4250D01*
X13167Y-4500D01*
X13833D01*
X14500Y-4250D01*
X15000Y-3833D01*
X15250Y-3250D01*
X15083Y-2667D01*
X14667Y-2167D01*
X13917Y-1833D01*
X12917Y-1667D01*
X12333Y-1333D01*
X12083Y-750D01*
X12250Y-167D01*
X12667Y250D01*
X13250Y500D01*
X13833D01*
X14417Y333D01*
X14917Y-83D01*
G01X19100Y-4500D02*
X18600Y-4417D01*
X18100Y-4083D01*
X17767Y-3500D01*
X17600Y-2833D01*
X17767Y-2167D01*
X18100Y-1583D01*
X18600Y-1250D01*
X19100Y-1167D01*
X19600Y-1250D01*
X20100Y-1583D01*
X20433Y-2167D01*
X20517Y-2833D01*
X20433Y-3500D01*
X20100Y-4083D01*
X19600Y-4417D01*
X19100Y-4500D01*
G01X24700D02*
Y500D01*
G01X31800D02*
Y-4500D01*
G01Y-3750D02*
X31467Y-4167D01*
X30967Y-4417D01*
X30383Y-4500D01*
X29717Y-4333D01*
X29217Y-3917D01*
X28883Y-3417D01*
X28800Y-2833D01*
X28883Y-2250D01*
X29217Y-1750D01*
X29717Y-1333D01*
X30383Y-1167D01*
X30967Y-1250D01*
X31383Y-1417D01*
X31800Y-1750D01*
G01X34650Y-2250D02*
X37317D01*
X37067Y-1667D01*
X36650Y-1333D01*
X36067Y-1167D01*
X35483Y-1250D01*
X34983Y-1500D01*
X34650Y-2083D01*
X34483Y-2583D01*
Y-3083D01*
X34650Y-3583D01*
X35067Y-4083D01*
X35567Y-4417D01*
X36150Y-4500D01*
X36733Y-4333D01*
X37317Y-3833D01*
G01X40333Y-4500D02*
Y-1167D01*
G01Y-1833D02*
X40750Y-1500D01*
X41167Y-1250D01*
X41750Y-1167D01*
X42167Y-1250D01*
X42667Y-1500D01*
G01X50200Y-4500D02*
Y-1167D01*
G01Y-2083D02*
X50450Y-1667D01*
X50867Y-1333D01*
X51450Y-1167D01*
X52033Y-1333D01*
X52450Y-1667D01*
X52700Y-2083D01*
Y-4500D01*
G01Y-2083D02*
X52950Y-1667D01*
X53367Y-1333D01*
X53950Y-1167D01*
X54533Y-1333D01*
X54950Y-1667D01*
X55200Y-2167D01*
Y-4500D01*
G01X59800D02*
Y-1167D01*
G01Y-1750D02*
X59467Y-1417D01*
X58967Y-1250D01*
X58383Y-1167D01*
X57800Y-1333D01*
X57300Y-1667D01*
X56967Y-2167D01*
X56800Y-2833D01*
X56967Y-3500D01*
X57300Y-4000D01*
X57800Y-4333D01*
X58383Y-4500D01*
X58967Y-4417D01*
X59467Y-4167D01*
X59800Y-3833D01*
G01X62650Y-3917D02*
X63067Y-4250D01*
X63650Y-4500D01*
X64150D01*
X64650Y-4333D01*
X64983Y-4083D01*
X65150Y-3750D01*
X65067Y-3250D01*
X64733Y-3000D01*
X63233Y-2500D01*
X62900Y-1917D01*
X63067Y-1500D01*
X63400Y-1250D01*
X63900Y-1167D01*
X64400Y-1250D01*
X64900Y-1500D01*
G01X68083Y-4500D02*
Y500D01*
G01X70750Y-1167D02*
X68083Y-3083D01*
G01X69167Y-2333D02*
X70917Y-4500D01*
G01X15167Y64000D02*
X11833D01*
Y69000D01*
X15167D01*
G01X13833Y66583D02*
X11833D01*
G01X19100Y69000D02*
Y64000D01*
G01X17933Y67333D02*
X20267D01*
G01X26033Y66917D02*
X25450Y67250D01*
X24950Y67333D01*
X24283Y67167D01*
X23783Y66833D01*
X23450Y66250D01*
X23367Y65667D01*
X23450Y65083D01*
X23783Y64583D01*
X24283Y64167D01*
X24950Y64000D01*
X25533Y64167D01*
X26033Y64500D01*
G01X28883Y64000D02*
Y69000D01*
G01Y66583D02*
X29300Y67000D01*
X29717Y67250D01*
X30383Y67333D01*
X30883Y67250D01*
X31467Y66917D01*
X31717Y66417D01*
Y64000D01*
G01X0Y19500D02*
X694500D01*
G01X15167Y111500D02*
X11833D01*
Y116500D01*
X15167D01*
G01X13833Y114083D02*
X11833D01*
G01X17850Y114833D02*
X20350Y111500D01*
G01Y114833D02*
X17850Y111500D01*
G01X24700Y116500D02*
Y111500D01*
G01X23533Y114833D02*
X25867D01*
G01X29050Y113750D02*
X31717D01*
X31467Y114333D01*
X31050Y114667D01*
X30467Y114833D01*
X29883Y114750D01*
X29383Y114500D01*
X29050Y113917D01*
X28883Y113417D01*
Y112917D01*
X29050Y112417D01*
X29467Y111917D01*
X29967Y111583D01*
X30550Y111500D01*
X31133Y111667D01*
X31717Y112167D01*
G01X34733Y111500D02*
Y114833D01*
G01Y114167D02*
X35150Y114500D01*
X35567Y114750D01*
X36150Y114833D01*
X36567Y114750D01*
X37067Y114500D01*
G01X40083Y111500D02*
Y114833D01*
G01Y114000D02*
X40417Y114417D01*
X40917Y114750D01*
X41583Y114833D01*
X42167Y114750D01*
X42667Y114417D01*
X42917Y113833D01*
Y111500D01*
G01X48600D02*
Y114833D01*
G01Y114250D02*
X48267Y114583D01*
X47767Y114750D01*
X47183Y114833D01*
X46600Y114667D01*
X46100Y114333D01*
X45767Y113833D01*
X45600Y113167D01*
X45767Y112500D01*
X46100Y112000D01*
X46600Y111667D01*
X47183Y111500D01*
X47767Y111583D01*
X48267Y111833D01*
X48600Y112167D01*
G01X52700Y111500D02*
Y116500D01*
G01X63900Y111500D02*
Y116500D01*
G01X71000Y111500D02*
Y114833D01*
G01Y114250D02*
X70667Y114583D01*
X70167Y114750D01*
X69583Y114833D01*
X69000Y114667D01*
X68500Y114333D01*
X68167Y113833D01*
X68000Y113167D01*
X68167Y112500D01*
X68500Y112000D01*
X69000Y111667D01*
X69583Y111500D01*
X70167Y111583D01*
X70667Y111833D01*
X71000Y112167D01*
G01X73350Y110000D02*
X73850Y109833D01*
X74517Y110000D01*
X74933Y110333D01*
X75267Y110750D01*
X75767Y112083D01*
X76850Y114833D01*
G01X74183D02*
X75767Y112083D01*
G01X79450Y113750D02*
X82117D01*
X81867Y114333D01*
X81450Y114667D01*
X80867Y114833D01*
X80283Y114750D01*
X79783Y114500D01*
X79450Y113917D01*
X79283Y113417D01*
Y112917D01*
X79450Y112417D01*
X79867Y111917D01*
X80367Y111583D01*
X80950Y111500D01*
X81533Y111667D01*
X82117Y112167D01*
G01X85133Y111500D02*
Y114833D01*
G01Y114167D02*
X85550Y114500D01*
X85967Y114750D01*
X86550Y114833D01*
X86967Y114750D01*
X87467Y114500D01*
G01X0Y105500D02*
X694500D01*
G01X0Y120500D02*
X694500D01*
G01X15333Y146083D02*
X14833Y146333D01*
X14250Y146500D01*
X13583D01*
X12833Y146250D01*
X12250Y145833D01*
X11833Y145333D01*
X11500Y144500D01*
X11417Y143750D01*
X11583Y143000D01*
X11833Y142500D01*
X12333Y142000D01*
X12917Y141667D01*
X13500Y141500D01*
X14083D01*
X14667Y141667D01*
X15167Y141917D01*
X15583Y142250D01*
G01X19100Y141500D02*
X18600Y141583D01*
X18100Y141917D01*
X17767Y142500D01*
X17600Y143167D01*
X17767Y143833D01*
X18100Y144417D01*
X18600Y144750D01*
X19100Y144833D01*
X19600Y144750D01*
X20100Y144417D01*
X20433Y143833D01*
X20517Y143167D01*
X20433Y142500D01*
X20100Y141917D01*
X19600Y141583D01*
X19100Y141500D01*
G01X23200Y139833D02*
Y144833D01*
G01Y144083D02*
X23617Y144500D01*
X24033Y144750D01*
X24700Y144833D01*
X25283Y144750D01*
X25867Y144333D01*
X26117Y143750D01*
X26200Y143167D01*
X26117Y142583D01*
X25867Y142000D01*
X25367Y141667D01*
X24700Y141500D01*
X24117Y141583D01*
X23533Y141833D01*
X23200Y142167D01*
G01X28800Y139833D02*
Y144833D01*
G01Y144083D02*
X29217Y144500D01*
X29633Y144750D01*
X30300Y144833D01*
X30883Y144750D01*
X31467Y144333D01*
X31717Y143750D01*
X31800Y143167D01*
X31717Y142583D01*
X31467Y142000D01*
X30967Y141667D01*
X30300Y141500D01*
X29717Y141583D01*
X29133Y141833D01*
X28800Y142167D01*
G01X34650Y143750D02*
X37317D01*
X37067Y144333D01*
X36650Y144667D01*
X36067Y144833D01*
X35483Y144750D01*
X34983Y144500D01*
X34650Y143917D01*
X34483Y143417D01*
Y142917D01*
X34650Y142417D01*
X35067Y141917D01*
X35567Y141583D01*
X36150Y141500D01*
X36733Y141667D01*
X37317Y142167D01*
G01X40333Y141500D02*
Y144833D01*
G01Y144167D02*
X40750Y144500D01*
X41167Y144750D01*
X41750Y144833D01*
X42167Y144750D01*
X42667Y144500D01*
G01X51033Y141500D02*
Y146500D01*
X53033D01*
X53700Y146250D01*
X54200Y145667D01*
X54367Y145000D01*
X54200Y144333D01*
X53783Y143833D01*
X53033Y143583D01*
X51033D01*
G01X58300Y141500D02*
Y146500D01*
G01X65400Y141500D02*
Y144833D01*
G01Y144250D02*
X65067Y144583D01*
X64567Y144750D01*
X63983Y144833D01*
X63400Y144667D01*
X62900Y144333D01*
X62567Y143833D01*
X62400Y143167D01*
X62567Y142500D01*
X62900Y142000D01*
X63400Y141667D01*
X63983Y141500D01*
X64567Y141583D01*
X65067Y141833D01*
X65400Y142167D01*
G01X69500Y146500D02*
Y141500D01*
G01X68333Y144833D02*
X70667D01*
G01X75100D02*
Y141500D01*
G01Y146167D02*
X74933Y146250D01*
Y146417D01*
X75100Y146500D01*
X75267Y146417D01*
Y146250D01*
X75100Y146167D01*
G01X79283Y141500D02*
Y144833D01*
G01Y144000D02*
X79617Y144417D01*
X80117Y144750D01*
X80783Y144833D01*
X81367Y144750D01*
X81867Y144417D01*
X82117Y143833D01*
Y141500D01*
G01X85133Y140250D02*
X85717Y139917D01*
X86383Y139833D01*
X86967Y139917D01*
X87467Y140333D01*
X87800Y140917D01*
Y144833D01*
G01Y144167D02*
X87467Y144500D01*
X86967Y144750D01*
X86383Y144833D01*
X85717Y144667D01*
X85300Y144333D01*
X84967Y143750D01*
X84800Y143167D01*
X84883Y142667D01*
X85217Y142083D01*
X85717Y141667D01*
X86383Y141500D01*
X86883Y141583D01*
X87467Y141917D01*
X87800Y142250D01*
G01X1500Y175500D02*
X694500D01*
G01X11667Y459000D02*
Y464000D01*
X13333D01*
X14000Y463750D01*
X14500Y463417D01*
X14917Y462917D01*
X15250Y462333D01*
X15333Y461500D01*
X15250Y460667D01*
X14917Y460083D01*
X14500Y459583D01*
X14000Y459250D01*
X13333Y459000D01*
X11667D01*
G01X17933D02*
Y462333D01*
G01Y461667D02*
X18350Y462000D01*
X18767Y462250D01*
X19350Y462333D01*
X19767Y462250D01*
X20267Y462000D01*
G01X24700Y462333D02*
Y459000D01*
G01Y463667D02*
X24533Y463750D01*
Y463917D01*
X24700Y464000D01*
X24867Y463917D01*
Y463750D01*
X24700Y463667D01*
G01X30300Y459000D02*
Y464000D01*
G01X35900Y459000D02*
Y464000D01*
G01X24960Y626740D02*
X26960D01*
G01X25960D02*
Y621740D01*
G01X24960D02*
X26960D01*
G01X30143D02*
Y625073D01*
G01Y624240D02*
X30477Y624657D01*
X30977Y624990D01*
X31643Y625073D01*
X32227Y624990D01*
X32727Y624657D01*
X32977Y624073D01*
Y621740D01*
G01X35743D02*
Y625073D01*
G01Y624240D02*
X36077Y624657D01*
X36577Y624990D01*
X37243Y625073D01*
X37827Y624990D01*
X38327Y624657D01*
X38577Y624073D01*
Y621740D01*
G01X41510Y623990D02*
X44177D01*
X43927Y624573D01*
X43510Y624907D01*
X42927Y625073D01*
X42343Y624990D01*
X41843Y624740D01*
X41510Y624157D01*
X41343Y623657D01*
Y623157D01*
X41510Y622657D01*
X41927Y622157D01*
X42427Y621823D01*
X43010Y621740D01*
X43593Y621907D01*
X44177Y622407D01*
G01X47193Y621740D02*
Y625073D01*
G01Y624407D02*
X47610Y624740D01*
X48027Y624990D01*
X48610Y625073D01*
X49027Y624990D01*
X49527Y624740D01*
G01X59560Y621740D02*
Y626740D01*
G01X66660Y621740D02*
Y625073D01*
G01Y624490D02*
X66327Y624823D01*
X65827Y624990D01*
X65243Y625073D01*
X64660Y624907D01*
X64160Y624573D01*
X63827Y624073D01*
X63660Y623407D01*
X63827Y622740D01*
X64160Y622240D01*
X64660Y621907D01*
X65243Y621740D01*
X65827Y621823D01*
X66327Y622073D01*
X66660Y622407D01*
G01X69010Y620240D02*
X69510Y620073D01*
X70177Y620240D01*
X70593Y620573D01*
X70927Y620990D01*
X71427Y622323D01*
X72510Y625073D01*
G01X69843D02*
X71427Y622323D01*
G01X75110Y623990D02*
X77777D01*
X77527Y624573D01*
X77110Y624907D01*
X76527Y625073D01*
X75943Y624990D01*
X75443Y624740D01*
X75110Y624157D01*
X74943Y623657D01*
Y623157D01*
X75110Y622657D01*
X75527Y622157D01*
X76027Y621823D01*
X76610Y621740D01*
X77193Y621907D01*
X77777Y622407D01*
G01X80793Y621740D02*
Y625073D01*
G01Y624407D02*
X81210Y624740D01*
X81627Y624990D01*
X82210Y625073D01*
X82627Y624990D01*
X83127Y624740D01*
G01X0Y599000D02*
X694500D01*
G01X9917Y693667D02*
X10417Y694167D01*
X11000Y694417D01*
X11667Y694500D01*
X12500Y694333D01*
X13083Y693917D01*
X13250Y693417D01*
X13167Y692917D01*
X12833Y692500D01*
X11167Y691667D01*
X10417Y691083D01*
X9917Y690250D01*
X9750Y689500D01*
X13250D01*
G01X17100Y689333D02*
X16933Y689417D01*
Y689583D01*
X17100Y689667D01*
X17267Y689583D01*
Y689417D01*
X17100Y689333D01*
G01X22700Y694500D02*
Y689500D01*
G01X20783Y694500D02*
X24617D01*
G01X28300Y689500D02*
X27800Y689583D01*
X27300Y689917D01*
X26967Y690500D01*
X26800Y691167D01*
X26967Y691833D01*
X27300Y692417D01*
X27800Y692750D01*
X28300Y692833D01*
X28800Y692750D01*
X29300Y692417D01*
X29633Y691833D01*
X29717Y691167D01*
X29633Y690500D01*
X29300Y689917D01*
X28800Y689583D01*
X28300Y689500D01*
G01X33900D02*
Y694500D01*
G01X38250Y691750D02*
X40917D01*
X40667Y692333D01*
X40250Y692667D01*
X39667Y692833D01*
X39083Y692750D01*
X38583Y692500D01*
X38250Y691917D01*
X38083Y691417D01*
Y690917D01*
X38250Y690417D01*
X38667Y689917D01*
X39167Y689583D01*
X39750Y689500D01*
X40333Y689667D01*
X40917Y690167D01*
G01X43933Y689500D02*
Y692833D01*
G01Y692167D02*
X44350Y692500D01*
X44767Y692750D01*
X45350Y692833D01*
X45767Y692750D01*
X46267Y692500D01*
G01X52200Y689500D02*
Y692833D01*
G01Y692250D02*
X51867Y692583D01*
X51367Y692750D01*
X50783Y692833D01*
X50200Y692667D01*
X49700Y692333D01*
X49367Y691833D01*
X49200Y691167D01*
X49367Y690500D01*
X49700Y690000D01*
X50200Y689667D01*
X50783Y689500D01*
X51367Y689583D01*
X51867Y689833D01*
X52200Y690167D01*
G01X54883Y689500D02*
Y692833D01*
G01Y692000D02*
X55217Y692417D01*
X55717Y692750D01*
X56383Y692833D01*
X56967Y692750D01*
X57467Y692417D01*
X57717Y691833D01*
Y689500D01*
G01X63233Y692417D02*
X62650Y692750D01*
X62150Y692833D01*
X61483Y692667D01*
X60983Y692333D01*
X60650Y691750D01*
X60567Y691167D01*
X60650Y690583D01*
X60983Y690083D01*
X61483Y689667D01*
X62150Y689500D01*
X62733Y689667D01*
X63233Y690000D01*
G01X66250Y691750D02*
X68917D01*
X68667Y692333D01*
X68250Y692667D01*
X67667Y692833D01*
X67083Y692750D01*
X66583Y692500D01*
X66250Y691917D01*
X66083Y691417D01*
Y690917D01*
X66250Y690417D01*
X66667Y689917D01*
X67167Y689583D01*
X67750Y689500D01*
X68333Y689667D01*
X68917Y690167D01*
G01X78700Y694500D02*
Y689500D01*
G01X77533Y692833D02*
X79867D01*
G01X85800Y689500D02*
Y692833D01*
G01Y692250D02*
X85467Y692583D01*
X84967Y692750D01*
X84383Y692833D01*
X83800Y692667D01*
X83300Y692333D01*
X82967Y691833D01*
X82800Y691167D01*
X82967Y690500D01*
X83300Y690000D01*
X83800Y689667D01*
X84383Y689500D01*
X84967Y689583D01*
X85467Y689833D01*
X85800Y690167D01*
G01X88400Y689500D02*
Y694500D01*
G01Y692000D02*
X88817Y692500D01*
X89317Y692750D01*
X89817Y692833D01*
X90567Y692667D01*
X91067Y692333D01*
X91400Y691750D01*
Y691083D01*
X91233Y690417D01*
X90900Y689917D01*
X90317Y689583D01*
X89817Y689500D01*
X89317Y689583D01*
X88817Y689833D01*
X88400Y690250D01*
G01X95500Y689500D02*
Y694500D01*
G01X99850Y691750D02*
X102517D01*
X102267Y692333D01*
X101850Y692667D01*
X101267Y692833D01*
X100683Y692750D01*
X100183Y692500D01*
X99850Y691917D01*
X99683Y691417D01*
Y690917D01*
X99850Y690417D01*
X100267Y689917D01*
X100767Y689583D01*
X101350Y689500D01*
X101933Y689667D01*
X102517Y690167D01*
G01X106700Y689333D02*
X106533Y689417D01*
Y689583D01*
X106700Y689667D01*
X106867Y689583D01*
Y689417D01*
X106700Y689333D01*
G01Y691583D02*
X106533Y691667D01*
Y691833D01*
X106700Y691917D01*
X106867Y691833D01*
Y691667D01*
X106700Y691583D01*
G01X34000Y663333D02*
Y668333D01*
G01Y667583D02*
X34417Y668000D01*
X34833Y668250D01*
X35500Y668333D01*
X36083Y668250D01*
X36667Y667833D01*
X36917Y667250D01*
X37000Y666667D01*
X36917Y666083D01*
X36667Y665500D01*
X36167Y665167D01*
X35500Y665000D01*
X34917Y665083D01*
X34333Y665333D01*
X34000Y665667D01*
G01X39933Y665000D02*
Y668333D01*
G01Y667667D02*
X40350Y668000D01*
X40767Y668250D01*
X41350Y668333D01*
X41767Y668250D01*
X42267Y668000D01*
G01X46700Y665000D02*
X46200Y665083D01*
X45700Y665417D01*
X45367Y666000D01*
X45200Y666667D01*
X45367Y667333D01*
X45700Y667917D01*
X46200Y668250D01*
X46700Y668333D01*
X47200Y668250D01*
X47700Y667917D01*
X48033Y667333D01*
X48117Y666667D01*
X48033Y666000D01*
X47700Y665417D01*
X47200Y665083D01*
X46700Y665000D01*
G01X53633Y667917D02*
X53050Y668250D01*
X52550Y668333D01*
X51883Y668167D01*
X51383Y667833D01*
X51050Y667250D01*
X50967Y666667D01*
X51050Y666083D01*
X51383Y665583D01*
X51883Y665167D01*
X52550Y665000D01*
X53133Y665167D01*
X53633Y665500D01*
G01X56650Y667250D02*
X59317D01*
X59067Y667833D01*
X58650Y668167D01*
X58067Y668333D01*
X57483Y668250D01*
X56983Y668000D01*
X56650Y667417D01*
X56483Y666917D01*
Y666417D01*
X56650Y665917D01*
X57067Y665417D01*
X57567Y665083D01*
X58150Y665000D01*
X58733Y665167D01*
X59317Y665667D01*
G01X62250Y665583D02*
X62667Y665250D01*
X63250Y665000D01*
X63750D01*
X64250Y665167D01*
X64583Y665417D01*
X64750Y665750D01*
X64667Y666250D01*
X64333Y666500D01*
X62833Y667000D01*
X62500Y667583D01*
X62667Y668000D01*
X63000Y668250D01*
X63500Y668333D01*
X64000Y668250D01*
X64500Y668000D01*
G01X67850Y665583D02*
X68267Y665250D01*
X68850Y665000D01*
X69350D01*
X69850Y665167D01*
X70183Y665417D01*
X70350Y665750D01*
X70267Y666250D01*
X69933Y666500D01*
X68433Y667000D01*
X68100Y667583D01*
X68267Y668000D01*
X68600Y668250D01*
X69100Y668333D01*
X69600Y668250D01*
X70100Y668000D01*
G01X0Y679000D02*
X694500D01*
G01X-1000Y654000D02*
X694500D01*
G01X0Y850500D02*
Y709000D01*
X694500D01*
Y850500D01*
G01X67000Y725433D02*
X66833Y725517D01*
Y725683D01*
X67000Y725767D01*
X67167Y725683D01*
Y725517D01*
X67000Y725433D01*
G01Y734433D02*
X66833Y734517D01*
Y734683D01*
X67000Y734767D01*
X67167Y734683D01*
Y734517D01*
X67000Y734433D01*
G01Y743433D02*
X66833Y743517D01*
Y743683D01*
X67000Y743767D01*
X67167Y743683D01*
Y743517D01*
X67000Y743433D01*
G01Y752433D02*
X66833Y752517D01*
Y752683D01*
X67000Y752767D01*
X67167Y752683D01*
Y752517D01*
X67000Y752433D01*
G01Y761433D02*
X66833Y761517D01*
Y761683D01*
X67000Y761767D01*
X67167Y761683D01*
Y761517D01*
X67000Y761433D01*
G01Y770433D02*
X66833Y770517D01*
Y770683D01*
X67000Y770767D01*
X67167Y770683D01*
Y770517D01*
X67000Y770433D01*
G01Y779433D02*
X66833Y779517D01*
Y779683D01*
X67000Y779767D01*
X67167Y779683D01*
Y779517D01*
X67000Y779433D01*
G01X7000Y832500D02*
Y837500D01*
X6000Y836500D01*
G01Y832500D02*
X8000D01*
G01X12600Y832333D02*
X12433Y832417D01*
Y832583D01*
X12600Y832667D01*
X12767Y832583D01*
Y832417D01*
X12600Y832333D01*
G01X16450Y833167D02*
X17117Y832750D01*
X17867Y832500D01*
X18533D01*
X19200Y832750D01*
X19700Y833167D01*
X19950Y833750D01*
X19783Y834333D01*
X19367Y834833D01*
X18617Y835167D01*
X17617Y835333D01*
X17033Y835667D01*
X16783Y836250D01*
X16950Y836833D01*
X17367Y837250D01*
X17950Y837500D01*
X18533D01*
X19117Y837333D01*
X19617Y836917D01*
G01X22300Y830833D02*
Y835833D01*
G01Y835083D02*
X22717Y835500D01*
X23133Y835750D01*
X23800Y835833D01*
X24383Y835750D01*
X24967Y835333D01*
X25217Y834750D01*
X25300Y834167D01*
X25217Y833583D01*
X24967Y833000D01*
X24467Y832667D01*
X23800Y832500D01*
X23217Y832583D01*
X22633Y832833D01*
X22300Y833167D01*
G01X28150Y834750D02*
X30817D01*
X30567Y835333D01*
X30150Y835667D01*
X29567Y835833D01*
X28983Y835750D01*
X28483Y835500D01*
X28150Y834917D01*
X27983Y834417D01*
Y833917D01*
X28150Y833417D01*
X28567Y832917D01*
X29067Y832583D01*
X29650Y832500D01*
X30233Y832667D01*
X30817Y833167D01*
G01X36333Y835417D02*
X35750Y835750D01*
X35250Y835833D01*
X34583Y835667D01*
X34083Y835333D01*
X33750Y834750D01*
X33667Y834167D01*
X33750Y833583D01*
X34083Y833083D01*
X34583Y832667D01*
X35250Y832500D01*
X35833Y832667D01*
X36333Y833000D01*
G01X40600Y835833D02*
Y832500D01*
G01Y837167D02*
X40433Y837250D01*
Y837417D01*
X40600Y837500D01*
X40767Y837417D01*
Y837250D01*
X40600Y837167D01*
G01X45700Y832500D02*
Y836750D01*
X45867Y837167D01*
X46200Y837417D01*
X46700Y837500D01*
X47200Y837333D01*
X47450Y836917D01*
G01X46450Y835500D02*
X44783D01*
G01X51800Y835833D02*
Y832500D01*
G01Y837167D02*
X51633Y837250D01*
Y837417D01*
X51800Y837500D01*
X51967Y837417D01*
Y837250D01*
X51800Y837167D01*
G01X58733Y835417D02*
X58150Y835750D01*
X57650Y835833D01*
X56983Y835667D01*
X56483Y835333D01*
X56150Y834750D01*
X56067Y834167D01*
X56150Y833583D01*
X56483Y833083D01*
X56983Y832667D01*
X57650Y832500D01*
X58233Y832667D01*
X58733Y833000D01*
G01X64500Y832500D02*
Y835833D01*
G01Y835250D02*
X64167Y835583D01*
X63667Y835750D01*
X63083Y835833D01*
X62500Y835667D01*
X62000Y835333D01*
X61667Y834833D01*
X61500Y834167D01*
X61667Y833500D01*
X62000Y833000D01*
X62500Y832667D01*
X63083Y832500D01*
X63667Y832583D01*
X64167Y832833D01*
X64500Y833167D01*
G01X68600Y837500D02*
Y832500D01*
G01X67433Y835833D02*
X69767D01*
G01X74200D02*
Y832500D01*
G01Y837167D02*
X74033Y837250D01*
Y837417D01*
X74200Y837500D01*
X74367Y837417D01*
Y837250D01*
X74200Y837167D01*
G01X79800Y832500D02*
X79300Y832583D01*
X78800Y832917D01*
X78467Y833500D01*
X78300Y834167D01*
X78467Y834833D01*
X78800Y835417D01*
X79300Y835750D01*
X79800Y835833D01*
X80300Y835750D01*
X80800Y835417D01*
X81133Y834833D01*
X81217Y834167D01*
X81133Y833500D01*
X80800Y832917D01*
X80300Y832583D01*
X79800Y832500D01*
G01X83983D02*
Y835833D01*
G01Y835000D02*
X84317Y835417D01*
X84817Y835750D01*
X85483Y835833D01*
X86067Y835750D01*
X86567Y835417D01*
X86817Y834833D01*
Y832500D01*
G01X98100Y837500D02*
Y832500D01*
G01Y833250D02*
X97767Y832833D01*
X97267Y832583D01*
X96683Y832500D01*
X96017Y832667D01*
X95517Y833083D01*
X95183Y833583D01*
X95100Y834167D01*
X95183Y834750D01*
X95517Y835250D01*
X96017Y835667D01*
X96683Y835833D01*
X97267Y835750D01*
X97683Y835583D01*
X98100Y835250D01*
G01X102200Y832500D02*
X101700Y832583D01*
X101200Y832917D01*
X100867Y833500D01*
X100700Y834167D01*
X100867Y834833D01*
X101200Y835417D01*
X101700Y835750D01*
X102200Y835833D01*
X102700Y835750D01*
X103200Y835417D01*
X103533Y834833D01*
X103617Y834167D01*
X103533Y833500D01*
X103200Y832917D01*
X102700Y832583D01*
X102200Y832500D01*
G01X109133Y835417D02*
X108550Y835750D01*
X108050Y835833D01*
X107383Y835667D01*
X106883Y835333D01*
X106550Y834750D01*
X106467Y834167D01*
X106550Y833583D01*
X106883Y833083D01*
X107383Y832667D01*
X108050Y832500D01*
X108633Y832667D01*
X109133Y833000D01*
G01X111983Y835833D02*
Y833500D01*
X112317Y832917D01*
X112817Y832583D01*
X113400Y832500D01*
X113983Y832583D01*
X114483Y832917D01*
X114817Y833500D01*
G01Y832500D02*
Y835833D01*
G01X116500Y832500D02*
Y835833D01*
G01Y834917D02*
X116750Y835333D01*
X117167Y835667D01*
X117750Y835833D01*
X118333Y835667D01*
X118750Y835333D01*
X119000Y834917D01*
Y832500D01*
G01Y834917D02*
X119250Y835333D01*
X119667Y835667D01*
X120250Y835833D01*
X120833Y835667D01*
X121250Y835333D01*
X121500Y834833D01*
Y832500D01*
G01X123350Y834750D02*
X126017D01*
X125767Y835333D01*
X125350Y835667D01*
X124767Y835833D01*
X124183Y835750D01*
X123683Y835500D01*
X123350Y834917D01*
X123183Y834417D01*
Y833917D01*
X123350Y833417D01*
X123767Y832917D01*
X124267Y832583D01*
X124850Y832500D01*
X125433Y832667D01*
X126017Y833167D01*
G01X128783Y832500D02*
Y835833D01*
G01Y835000D02*
X129117Y835417D01*
X129617Y835750D01*
X130283Y835833D01*
X130867Y835750D01*
X131367Y835417D01*
X131617Y834833D01*
Y832500D01*
G01X135800Y837500D02*
Y832500D01*
G01X134633Y835833D02*
X136967D01*
G01X141400Y832333D02*
X141233Y832417D01*
Y832583D01*
X141400Y832667D01*
X141567Y832583D01*
Y832417D01*
X141400Y832333D01*
G01Y834583D02*
X141233Y834667D01*
Y834833D01*
X141400Y834917D01*
X141567Y834833D01*
Y834667D01*
X141400Y834583D01*
G01X57000Y802500D02*
X59000D01*
G01X58000D02*
Y797500D01*
G01X57000D02*
X59000D01*
G01X63100D02*
Y801750D01*
X63267Y802167D01*
X63600Y802417D01*
X64100Y802500D01*
X64600Y802333D01*
X64850Y801917D01*
G01X63850Y800500D02*
X62183D01*
G01X74800Y802500D02*
Y797500D01*
G01X73633Y800833D02*
X75967D01*
G01X78983Y797500D02*
Y802500D01*
G01Y800083D02*
X79400Y800500D01*
X79817Y800750D01*
X80483Y800833D01*
X80983Y800750D01*
X81567Y800417D01*
X81817Y799917D01*
Y797500D01*
G01X84750Y799750D02*
X87417D01*
X87167Y800333D01*
X86750Y800667D01*
X86167Y800833D01*
X85583Y800750D01*
X85083Y800500D01*
X84750Y799917D01*
X84583Y799417D01*
Y798917D01*
X84750Y798417D01*
X85167Y797917D01*
X85667Y797583D01*
X86250Y797500D01*
X86833Y797667D01*
X87417Y798167D01*
G01X98533Y800417D02*
X97950Y800750D01*
X97450Y800833D01*
X96783Y800667D01*
X96283Y800333D01*
X95950Y799750D01*
X95867Y799167D01*
X95950Y798583D01*
X96283Y798083D01*
X96783Y797667D01*
X97450Y797500D01*
X98033Y797667D01*
X98533Y798000D01*
G01X101633Y797500D02*
Y800833D01*
G01Y800167D02*
X102050Y800500D01*
X102467Y800750D01*
X103050Y800833D01*
X103467Y800750D01*
X103967Y800500D01*
G01X108400Y800833D02*
Y797500D01*
G01Y802167D02*
X108233Y802250D01*
Y802417D01*
X108400Y802500D01*
X108567Y802417D01*
Y802250D01*
X108400Y802167D01*
G01X114000Y802500D02*
Y797500D01*
G01X112833Y800833D02*
X115167D01*
G01X118350Y799750D02*
X121017D01*
X120767Y800333D01*
X120350Y800667D01*
X119767Y800833D01*
X119183Y800750D01*
X118683Y800500D01*
X118350Y799917D01*
X118183Y799417D01*
Y798917D01*
X118350Y798417D01*
X118767Y797917D01*
X119267Y797583D01*
X119850Y797500D01*
X120433Y797667D01*
X121017Y798167D01*
G01X124033Y797500D02*
Y800833D01*
G01Y800167D02*
X124450Y800500D01*
X124867Y800750D01*
X125450Y800833D01*
X125867Y800750D01*
X126367Y800500D01*
G01X130800Y800833D02*
Y797500D01*
G01Y802167D02*
X130633Y802250D01*
Y802417D01*
X130800Y802500D01*
X130967Y802417D01*
Y802250D01*
X130800Y802167D01*
G01X137900Y797500D02*
Y800833D01*
G01Y800250D02*
X137567Y800583D01*
X137067Y800750D01*
X136483Y800833D01*
X135900Y800667D01*
X135400Y800333D01*
X135067Y799833D01*
X134900Y799167D01*
X135067Y798500D01*
X135400Y798000D01*
X135900Y797667D01*
X136483Y797500D01*
X137067Y797583D01*
X137567Y797833D01*
X137900Y798167D01*
G01X147600Y800833D02*
Y797500D01*
G01Y802167D02*
X147433Y802250D01*
Y802417D01*
X147600Y802500D01*
X147767Y802417D01*
Y802250D01*
X147600Y802167D01*
G01X151950Y798083D02*
X152367Y797750D01*
X152950Y797500D01*
X153450D01*
X153950Y797667D01*
X154283Y797917D01*
X154450Y798250D01*
X154367Y798750D01*
X154033Y799000D01*
X152533Y799500D01*
X152200Y800083D01*
X152367Y800500D01*
X152700Y800750D01*
X153200Y800833D01*
X153700Y800750D01*
X154200Y800500D01*
G01X162983Y797500D02*
Y800833D01*
G01Y800000D02*
X163317Y800417D01*
X163817Y800750D01*
X164483Y800833D01*
X165067Y800750D01*
X165567Y800417D01*
X165817Y799833D01*
Y797500D01*
G01X170000D02*
X169500Y797583D01*
X169000Y797917D01*
X168667Y798500D01*
X168500Y799167D01*
X168667Y799833D01*
X169000Y800417D01*
X169500Y800750D01*
X170000Y800833D01*
X170500Y800750D01*
X171000Y800417D01*
X171333Y799833D01*
X171417Y799167D01*
X171333Y798500D01*
X171000Y797917D01*
X170500Y797583D01*
X170000Y797500D01*
G01X175600Y802500D02*
Y797500D01*
G01X174433Y800833D02*
X176767D01*
G01X185550Y798083D02*
X185967Y797750D01*
X186550Y797500D01*
X187050D01*
X187550Y797667D01*
X187883Y797917D01*
X188050Y798250D01*
X187967Y798750D01*
X187633Y799000D01*
X186133Y799500D01*
X185800Y800083D01*
X185967Y800500D01*
X186300Y800750D01*
X186800Y800833D01*
X187300Y800750D01*
X187800Y800500D01*
G01X190900Y795833D02*
Y800833D01*
G01Y800083D02*
X191317Y800500D01*
X191733Y800750D01*
X192400Y800833D01*
X192983Y800750D01*
X193567Y800333D01*
X193817Y799750D01*
X193900Y799167D01*
X193817Y798583D01*
X193567Y798000D01*
X193067Y797667D01*
X192400Y797500D01*
X191817Y797583D01*
X191233Y797833D01*
X190900Y798167D01*
G01X196750Y799750D02*
X199417D01*
X199167Y800333D01*
X198750Y800667D01*
X198167Y800833D01*
X197583Y800750D01*
X197083Y800500D01*
X196750Y799917D01*
X196583Y799417D01*
Y798917D01*
X196750Y798417D01*
X197167Y797917D01*
X197667Y797583D01*
X198250Y797500D01*
X198833Y797667D01*
X199417Y798167D01*
G01X204933Y800417D02*
X204350Y800750D01*
X203850Y800833D01*
X203183Y800667D01*
X202683Y800333D01*
X202350Y799750D01*
X202267Y799167D01*
X202350Y798583D01*
X202683Y798083D01*
X203183Y797667D01*
X203850Y797500D01*
X204433Y797667D01*
X204933Y798000D01*
G01X209200Y800833D02*
Y797500D01*
G01Y802167D02*
X209033Y802250D01*
Y802417D01*
X209200Y802500D01*
X209367Y802417D01*
Y802250D01*
X209200Y802167D01*
G01X214300Y797500D02*
Y801750D01*
X214467Y802167D01*
X214800Y802417D01*
X215300Y802500D01*
X215800Y802333D01*
X216050Y801917D01*
G01X215050Y800500D02*
X213383D01*
G01X220400Y800833D02*
Y797500D01*
G01Y802167D02*
X220233Y802250D01*
Y802417D01*
X220400Y802500D01*
X220567Y802417D01*
Y802250D01*
X220400Y802167D01*
G01X224750Y799750D02*
X227417D01*
X227167Y800333D01*
X226750Y800667D01*
X226167Y800833D01*
X225583Y800750D01*
X225083Y800500D01*
X224750Y799917D01*
X224583Y799417D01*
Y798917D01*
X224750Y798417D01*
X225167Y797917D01*
X225667Y797583D01*
X226250Y797500D01*
X226833Y797667D01*
X227417Y798167D01*
G01X233100Y802500D02*
Y797500D01*
G01Y798250D02*
X232767Y797833D01*
X232267Y797583D01*
X231683Y797500D01*
X231017Y797667D01*
X230517Y798083D01*
X230183Y798583D01*
X230100Y799167D01*
X230183Y799750D01*
X230517Y800250D01*
X231017Y800667D01*
X231683Y800833D01*
X232267Y800750D01*
X232683Y800583D01*
X233100Y800250D01*
G01X242800Y800833D02*
Y797500D01*
G01Y802167D02*
X242633Y802250D01*
Y802417D01*
X242800Y802500D01*
X242967Y802417D01*
Y802250D01*
X242800Y802167D01*
G01X246983Y797500D02*
Y800833D01*
G01Y800000D02*
X247317Y800417D01*
X247817Y800750D01*
X248483Y800833D01*
X249067Y800750D01*
X249567Y800417D01*
X249817Y799833D01*
Y797500D01*
G01X259600Y802500D02*
Y797500D01*
G01X258433Y800833D02*
X260767D01*
G01X263783Y797500D02*
Y802500D01*
G01Y800083D02*
X264200Y800500D01*
X264617Y800750D01*
X265283Y800833D01*
X265783Y800750D01*
X266367Y800417D01*
X266617Y799917D01*
Y797500D01*
G01X269550Y799750D02*
X272217D01*
X271967Y800333D01*
X271550Y800667D01*
X270967Y800833D01*
X270383Y800750D01*
X269883Y800500D01*
X269550Y799917D01*
X269383Y799417D01*
Y798917D01*
X269550Y798417D01*
X269967Y797917D01*
X270467Y797583D01*
X271050Y797500D01*
X271633Y797667D01*
X272217Y798167D01*
G01X282000Y802500D02*
Y797500D01*
G01X280833Y800833D02*
X283167D01*
G01X289100Y797500D02*
Y800833D01*
G01Y800250D02*
X288767Y800583D01*
X288267Y800750D01*
X287683Y800833D01*
X287100Y800667D01*
X286600Y800333D01*
X286267Y799833D01*
X286100Y799167D01*
X286267Y798500D01*
X286600Y798000D01*
X287100Y797667D01*
X287683Y797500D01*
X288267Y797583D01*
X288767Y797833D01*
X289100Y798167D01*
G01X291700Y797500D02*
Y802500D01*
G01Y800000D02*
X292117Y800500D01*
X292617Y800750D01*
X293117Y800833D01*
X293867Y800667D01*
X294367Y800333D01*
X294700Y799750D01*
Y799083D01*
X294533Y798417D01*
X294200Y797917D01*
X293617Y797583D01*
X293117Y797500D01*
X292617Y797583D01*
X292117Y797833D01*
X291700Y798250D01*
G01X298800Y797500D02*
Y802500D01*
G01X303150Y799750D02*
X305817D01*
X305567Y800333D01*
X305150Y800667D01*
X304567Y800833D01*
X303983Y800750D01*
X303483Y800500D01*
X303150Y799917D01*
X302983Y799417D01*
Y798917D01*
X303150Y798417D01*
X303567Y797917D01*
X304067Y797583D01*
X304650Y797500D01*
X305233Y797667D01*
X305817Y798167D01*
G01X310000Y797333D02*
X309833Y797417D01*
Y797583D01*
X310000Y797667D01*
X310167Y797583D01*
Y797417D01*
X310000Y797333D01*
G01Y799583D02*
X309833Y799667D01*
Y799833D01*
X310000Y799917D01*
X310167Y799833D01*
Y799667D01*
X310000Y799583D01*
G01X67000Y786333D02*
X66833Y786417D01*
Y786583D01*
X67000Y786667D01*
X67167Y786583D01*
Y786417D01*
X67000Y786333D01*
G01X57833Y806500D02*
Y811500D01*
X59833D01*
X60500Y811250D01*
X61000Y810667D01*
X61167Y810000D01*
X61000Y809333D01*
X60583Y808833D01*
X59833Y808583D01*
X57833D01*
G01X65100Y806500D02*
Y811500D01*
G01X69450Y808750D02*
X72117D01*
X71867Y809333D01*
X71450Y809667D01*
X70867Y809833D01*
X70283Y809750D01*
X69783Y809500D01*
X69450Y808917D01*
X69283Y808417D01*
Y807917D01*
X69450Y807417D01*
X69867Y806917D01*
X70367Y806583D01*
X70950Y806500D01*
X71533Y806667D01*
X72117Y807167D01*
G01X77800Y806500D02*
Y809833D01*
G01Y809250D02*
X77467Y809583D01*
X76967Y809750D01*
X76383Y809833D01*
X75800Y809667D01*
X75300Y809333D01*
X74967Y808833D01*
X74800Y808167D01*
X74967Y807500D01*
X75300Y807000D01*
X75800Y806667D01*
X76383Y806500D01*
X76967Y806583D01*
X77467Y806833D01*
X77800Y807167D01*
G01X80650Y807083D02*
X81067Y806750D01*
X81650Y806500D01*
X82150D01*
X82650Y806667D01*
X82983Y806917D01*
X83150Y807250D01*
X83067Y807750D01*
X82733Y808000D01*
X81233Y808500D01*
X80900Y809083D01*
X81067Y809500D01*
X81400Y809750D01*
X81900Y809833D01*
X82400Y809750D01*
X82900Y809500D01*
G01X86250Y808750D02*
X88917D01*
X88667Y809333D01*
X88250Y809667D01*
X87667Y809833D01*
X87083Y809750D01*
X86583Y809500D01*
X86250Y808917D01*
X86083Y808417D01*
Y807917D01*
X86250Y807417D01*
X86667Y806917D01*
X87167Y806583D01*
X87750Y806500D01*
X88333Y806667D01*
X88917Y807167D01*
G01X98200Y806500D02*
Y810750D01*
X98367Y811167D01*
X98700Y811417D01*
X99200Y811500D01*
X99700Y811333D01*
X99950Y810917D01*
G01X98950Y809500D02*
X97283D01*
G01X104300Y806500D02*
X103800Y806583D01*
X103300Y806917D01*
X102967Y807500D01*
X102800Y808167D01*
X102967Y808833D01*
X103300Y809417D01*
X103800Y809750D01*
X104300Y809833D01*
X104800Y809750D01*
X105300Y809417D01*
X105633Y808833D01*
X105717Y808167D01*
X105633Y807500D01*
X105300Y806917D01*
X104800Y806583D01*
X104300Y806500D01*
G01X109900D02*
Y811500D01*
G01X115500Y806500D02*
Y811500D01*
G01X121100Y806500D02*
X120600Y806583D01*
X120100Y806917D01*
X119767Y807500D01*
X119600Y808167D01*
X119767Y808833D01*
X120100Y809417D01*
X120600Y809750D01*
X121100Y809833D01*
X121600Y809750D01*
X122100Y809417D01*
X122433Y808833D01*
X122517Y808167D01*
X122433Y807500D01*
X122100Y806917D01*
X121600Y806583D01*
X121100Y806500D01*
G01X124617Y809833D02*
X125617Y806500D01*
X126700Y809833D01*
X127783Y806500D01*
X128783Y809833D01*
G01X137900Y811500D02*
Y806500D01*
G01X136733Y809833D02*
X139067D01*
G01X142083Y806500D02*
Y811500D01*
G01Y809083D02*
X142500Y809500D01*
X142917Y809750D01*
X143583Y809833D01*
X144083Y809750D01*
X144667Y809417D01*
X144917Y808917D01*
Y806500D01*
G01X147850Y808750D02*
X150517D01*
X150267Y809333D01*
X149850Y809667D01*
X149267Y809833D01*
X148683Y809750D01*
X148183Y809500D01*
X147850Y808917D01*
X147683Y808417D01*
Y807917D01*
X147850Y807417D01*
X148267Y806917D01*
X148767Y806583D01*
X149350Y806500D01*
X149933Y806667D01*
X150517Y807167D01*
G01X159050Y807083D02*
X159467Y806750D01*
X160050Y806500D01*
X160550D01*
X161050Y806667D01*
X161383Y806917D01*
X161550Y807250D01*
X161467Y807750D01*
X161133Y808000D01*
X159633Y808500D01*
X159300Y809083D01*
X159467Y809500D01*
X159800Y809750D01*
X160300Y809833D01*
X160800Y809750D01*
X161300Y809500D01*
G01X164400Y804833D02*
Y809833D01*
G01Y809083D02*
X164817Y809500D01*
X165233Y809750D01*
X165900Y809833D01*
X166483Y809750D01*
X167067Y809333D01*
X167317Y808750D01*
X167400Y808167D01*
X167317Y807583D01*
X167067Y807000D01*
X166567Y806667D01*
X165900Y806500D01*
X165317Y806583D01*
X164733Y806833D01*
X164400Y807167D01*
G01X170250Y808750D02*
X172917D01*
X172667Y809333D01*
X172250Y809667D01*
X171667Y809833D01*
X171083Y809750D01*
X170583Y809500D01*
X170250Y808917D01*
X170083Y808417D01*
Y807917D01*
X170250Y807417D01*
X170667Y806917D01*
X171167Y806583D01*
X171750Y806500D01*
X172333Y806667D01*
X172917Y807167D01*
G01X178433Y809417D02*
X177850Y809750D01*
X177350Y809833D01*
X176683Y809667D01*
X176183Y809333D01*
X175850Y808750D01*
X175767Y808167D01*
X175850Y807583D01*
X176183Y807083D01*
X176683Y806667D01*
X177350Y806500D01*
X177933Y806667D01*
X178433Y807000D01*
G01X182700Y809833D02*
Y806500D01*
G01Y811167D02*
X182533Y811250D01*
Y811417D01*
X182700Y811500D01*
X182867Y811417D01*
Y811250D01*
X182700Y811167D01*
G01X187800Y806500D02*
Y810750D01*
X187967Y811167D01*
X188300Y811417D01*
X188800Y811500D01*
X189300Y811333D01*
X189550Y810917D01*
G01X188550Y809500D02*
X186883D01*
G01X193900Y809833D02*
Y806500D01*
G01Y811167D02*
X193733Y811250D01*
Y811417D01*
X193900Y811500D01*
X194067Y811417D01*
Y811250D01*
X193900Y811167D01*
G01X200833Y809417D02*
X200250Y809750D01*
X199750Y809833D01*
X199083Y809667D01*
X198583Y809333D01*
X198250Y808750D01*
X198167Y808167D01*
X198250Y807583D01*
X198583Y807083D01*
X199083Y806667D01*
X199750Y806500D01*
X200333Y806667D01*
X200833Y807000D01*
G01X206600Y806500D02*
Y809833D01*
G01Y809250D02*
X206267Y809583D01*
X205767Y809750D01*
X205183Y809833D01*
X204600Y809667D01*
X204100Y809333D01*
X203767Y808833D01*
X203600Y808167D01*
X203767Y807500D01*
X204100Y807000D01*
X204600Y806667D01*
X205183Y806500D01*
X205767Y806583D01*
X206267Y806833D01*
X206600Y807167D01*
G01X210700Y811500D02*
Y806500D01*
G01X209533Y809833D02*
X211867D01*
G01X216300D02*
Y806500D01*
G01Y811167D02*
X216133Y811250D01*
Y811417D01*
X216300Y811500D01*
X216467Y811417D01*
Y811250D01*
X216300Y811167D01*
G01X221900Y806500D02*
X221400Y806583D01*
X220900Y806917D01*
X220567Y807500D01*
X220400Y808167D01*
X220567Y808833D01*
X220900Y809417D01*
X221400Y809750D01*
X221900Y809833D01*
X222400Y809750D01*
X222900Y809417D01*
X223233Y808833D01*
X223317Y808167D01*
X223233Y807500D01*
X222900Y806917D01*
X222400Y806583D01*
X221900Y806500D01*
G01X226083D02*
Y809833D01*
G01Y809000D02*
X226417Y809417D01*
X226917Y809750D01*
X227583Y809833D01*
X228167Y809750D01*
X228667Y809417D01*
X228917Y808833D01*
Y806500D01*
G01X240200Y811500D02*
Y806500D01*
G01Y807250D02*
X239867Y806833D01*
X239367Y806583D01*
X238783Y806500D01*
X238117Y806667D01*
X237617Y807083D01*
X237283Y807583D01*
X237200Y808167D01*
X237283Y808750D01*
X237617Y809250D01*
X238117Y809667D01*
X238783Y809833D01*
X239367Y809750D01*
X239783Y809583D01*
X240200Y809250D01*
G01X244300Y806500D02*
X243800Y806583D01*
X243300Y806917D01*
X242967Y807500D01*
X242800Y808167D01*
X242967Y808833D01*
X243300Y809417D01*
X243800Y809750D01*
X244300Y809833D01*
X244800Y809750D01*
X245300Y809417D01*
X245633Y808833D01*
X245717Y808167D01*
X245633Y807500D01*
X245300Y806917D01*
X244800Y806583D01*
X244300Y806500D01*
G01X251233Y809417D02*
X250650Y809750D01*
X250150Y809833D01*
X249483Y809667D01*
X248983Y809333D01*
X248650Y808750D01*
X248567Y808167D01*
X248650Y807583D01*
X248983Y807083D01*
X249483Y806667D01*
X250150Y806500D01*
X250733Y806667D01*
X251233Y807000D01*
G01X254083Y809833D02*
Y807500D01*
X254417Y806917D01*
X254917Y806583D01*
X255500Y806500D01*
X256083Y806583D01*
X256583Y806917D01*
X256917Y807500D01*
G01Y806500D02*
Y809833D01*
G01X258600Y806500D02*
Y809833D01*
G01Y808917D02*
X258850Y809333D01*
X259267Y809667D01*
X259850Y809833D01*
X260433Y809667D01*
X260850Y809333D01*
X261100Y808917D01*
Y806500D01*
G01Y808917D02*
X261350Y809333D01*
X261767Y809667D01*
X262350Y809833D01*
X262933Y809667D01*
X263350Y809333D01*
X263600Y808833D01*
Y806500D01*
G01X265450Y808750D02*
X268117D01*
X267867Y809333D01*
X267450Y809667D01*
X266867Y809833D01*
X266283Y809750D01*
X265783Y809500D01*
X265450Y808917D01*
X265283Y808417D01*
Y807917D01*
X265450Y807417D01*
X265867Y806917D01*
X266367Y806583D01*
X266950Y806500D01*
X267533Y806667D01*
X268117Y807167D01*
G01X270883Y806500D02*
Y809833D01*
G01Y809000D02*
X271217Y809417D01*
X271717Y809750D01*
X272383Y809833D01*
X272967Y809750D01*
X273467Y809417D01*
X273717Y808833D01*
Y806500D01*
G01X277900Y811500D02*
Y806500D01*
G01X276733Y809833D02*
X279067D01*
G01X282250Y807083D02*
X282667Y806750D01*
X283250Y806500D01*
X283750D01*
X284250Y806667D01*
X284583Y806917D01*
X284750Y807250D01*
X284667Y807750D01*
X284333Y808000D01*
X282833Y808500D01*
X282500Y809083D01*
X282667Y809500D01*
X283000Y809750D01*
X283500Y809833D01*
X284000Y809750D01*
X284500Y809500D01*
G01X294700Y809833D02*
Y806500D01*
G01Y811167D02*
X294533Y811250D01*
Y811417D01*
X294700Y811500D01*
X294867Y811417D01*
Y811250D01*
X294700Y811167D01*
G01X298883Y806500D02*
Y809833D01*
G01Y809000D02*
X299217Y809417D01*
X299717Y809750D01*
X300383Y809833D01*
X300967Y809750D01*
X301467Y809417D01*
X301717Y808833D01*
Y806500D01*
G01X312833Y809417D02*
X312250Y809750D01*
X311750Y809833D01*
X311083Y809667D01*
X310583Y809333D01*
X310250Y808750D01*
X310167Y808167D01*
X310250Y807583D01*
X310583Y807083D01*
X311083Y806667D01*
X311750Y806500D01*
X312333Y806667D01*
X312833Y807000D01*
G01X317100Y806500D02*
Y811500D01*
G01X324200Y806500D02*
Y809833D01*
G01Y809250D02*
X323867Y809583D01*
X323367Y809750D01*
X322783Y809833D01*
X322200Y809667D01*
X321700Y809333D01*
X321367Y808833D01*
X321200Y808167D01*
X321367Y807500D01*
X321700Y807000D01*
X322200Y806667D01*
X322783Y806500D01*
X323367Y806583D01*
X323867Y806833D01*
X324200Y807167D01*
G01X327050Y807083D02*
X327467Y806750D01*
X328050Y806500D01*
X328550D01*
X329050Y806667D01*
X329383Y806917D01*
X329550Y807250D01*
X329467Y807750D01*
X329133Y808000D01*
X327633Y808500D01*
X327300Y809083D01*
X327467Y809500D01*
X327800Y809750D01*
X328300Y809833D01*
X328800Y809750D01*
X329300Y809500D01*
G01X332650Y807083D02*
X333067Y806750D01*
X333650Y806500D01*
X334150D01*
X334650Y806667D01*
X334983Y806917D01*
X335150Y807250D01*
X335067Y807750D01*
X334733Y808000D01*
X333233Y808500D01*
X332900Y809083D01*
X333067Y809500D01*
X333400Y809750D01*
X333900Y809833D01*
X334400Y809750D01*
X334900Y809500D01*
G01X343517Y810667D02*
X344017Y811167D01*
X344600Y811417D01*
X345267Y811500D01*
X346100Y811333D01*
X346683Y810917D01*
X346850Y810417D01*
X346767Y809917D01*
X346433Y809500D01*
X344767Y808667D01*
X344017Y808083D01*
X343517Y807250D01*
X343350Y806500D01*
X346850D01*
G01X357800D02*
Y809833D01*
G01Y809250D02*
X357467Y809583D01*
X356967Y809750D01*
X356383Y809833D01*
X355800Y809667D01*
X355300Y809333D01*
X354967Y808833D01*
X354800Y808167D01*
X354967Y807500D01*
X355300Y807000D01*
X355800Y806667D01*
X356383Y806500D01*
X356967Y806583D01*
X357467Y806833D01*
X357800Y807167D01*
G01X360483Y806500D02*
Y809833D01*
G01Y809000D02*
X360817Y809417D01*
X361317Y809750D01*
X361983Y809833D01*
X362567Y809750D01*
X363067Y809417D01*
X363317Y808833D01*
Y806500D01*
G01X369000Y811500D02*
Y806500D01*
G01Y807250D02*
X368667Y806833D01*
X368167Y806583D01*
X367583Y806500D01*
X366917Y806667D01*
X366417Y807083D01*
X366083Y807583D01*
X366000Y808167D01*
X366083Y808750D01*
X366417Y809250D01*
X366917Y809667D01*
X367583Y809833D01*
X368167Y809750D01*
X368583Y809583D01*
X369000Y809250D01*
G01X378700Y811500D02*
Y806500D01*
G01X377533Y809833D02*
X379867D01*
G01X382883Y806500D02*
Y811500D01*
G01Y809083D02*
X383300Y809500D01*
X383717Y809750D01*
X384383Y809833D01*
X384883Y809750D01*
X385467Y809417D01*
X385717Y808917D01*
Y806500D01*
G01X388650Y808750D02*
X391317D01*
X391067Y809333D01*
X390650Y809667D01*
X390067Y809833D01*
X389483Y809750D01*
X388983Y809500D01*
X388650Y808917D01*
X388483Y808417D01*
Y807917D01*
X388650Y807417D01*
X389067Y806917D01*
X389567Y806583D01*
X390150Y806500D01*
X390733Y806667D01*
X391317Y807167D01*
G01X401100Y806500D02*
Y811500D01*
G01X408200Y806500D02*
Y809833D01*
G01Y809250D02*
X407867Y809583D01*
X407367Y809750D01*
X406783Y809833D01*
X406200Y809667D01*
X405700Y809333D01*
X405367Y808833D01*
X405200Y808167D01*
X405367Y807500D01*
X405700Y807000D01*
X406200Y806667D01*
X406783Y806500D01*
X407367Y806583D01*
X407867Y806833D01*
X408200Y807167D01*
G01X412300Y811500D02*
Y806500D01*
G01X411133Y809833D02*
X413467D01*
G01X416650Y808750D02*
X419317D01*
X419067Y809333D01*
X418650Y809667D01*
X418067Y809833D01*
X417483Y809750D01*
X416983Y809500D01*
X416650Y808917D01*
X416483Y808417D01*
Y807917D01*
X416650Y807417D01*
X417067Y806917D01*
X417567Y806583D01*
X418150Y806500D01*
X418733Y806667D01*
X419317Y807167D01*
G01X422250Y807083D02*
X422667Y806750D01*
X423250Y806500D01*
X423750D01*
X424250Y806667D01*
X424583Y806917D01*
X424750Y807250D01*
X424667Y807750D01*
X424333Y808000D01*
X422833Y808500D01*
X422500Y809083D01*
X422667Y809500D01*
X423000Y809750D01*
X423500Y809833D01*
X424000Y809750D01*
X424500Y809500D01*
G01X429100Y811500D02*
Y806500D01*
G01X427933Y809833D02*
X430267D01*
G01X438800D02*
X440300Y806500D01*
X441800Y809833D01*
G01X444650Y808750D02*
X447317D01*
X447067Y809333D01*
X446650Y809667D01*
X446067Y809833D01*
X445483Y809750D01*
X444983Y809500D01*
X444650Y808917D01*
X444483Y808417D01*
Y807917D01*
X444650Y807417D01*
X445067Y806917D01*
X445567Y806583D01*
X446150Y806500D01*
X446733Y806667D01*
X447317Y807167D01*
G01X450333Y806500D02*
Y809833D01*
G01Y809167D02*
X450750Y809500D01*
X451167Y809750D01*
X451750Y809833D01*
X452167Y809750D01*
X452667Y809500D01*
G01X455850Y807083D02*
X456267Y806750D01*
X456850Y806500D01*
X457350D01*
X457850Y806667D01*
X458183Y806917D01*
X458350Y807250D01*
X458267Y807750D01*
X457933Y808000D01*
X456433Y808500D01*
X456100Y809083D01*
X456267Y809500D01*
X456600Y809750D01*
X457100Y809833D01*
X457600Y809750D01*
X458100Y809500D01*
G01X462700Y809833D02*
Y806500D01*
G01Y811167D02*
X462533Y811250D01*
Y811417D01*
X462700Y811500D01*
X462867Y811417D01*
Y811250D01*
X462700Y811167D01*
G01X468300Y806500D02*
X467800Y806583D01*
X467300Y806917D01*
X466967Y807500D01*
X466800Y808167D01*
X466967Y808833D01*
X467300Y809417D01*
X467800Y809750D01*
X468300Y809833D01*
X468800Y809750D01*
X469300Y809417D01*
X469633Y808833D01*
X469717Y808167D01*
X469633Y807500D01*
X469300Y806917D01*
X468800Y806583D01*
X468300Y806500D01*
G01X472483D02*
Y809833D01*
G01Y809000D02*
X472817Y809417D01*
X473317Y809750D01*
X473983Y809833D01*
X474567Y809750D01*
X475067Y809417D01*
X475317Y808833D01*
Y806500D01*
G01X485100Y809833D02*
Y806500D01*
G01Y811167D02*
X484933Y811250D01*
Y811417D01*
X485100Y811500D01*
X485267Y811417D01*
Y811250D01*
X485100Y811167D01*
G01X489450Y807083D02*
X489867Y806750D01*
X490450Y806500D01*
X490950D01*
X491450Y806667D01*
X491783Y806917D01*
X491950Y807250D01*
X491867Y807750D01*
X491533Y808000D01*
X490033Y808500D01*
X489700Y809083D01*
X489867Y809500D01*
X490200Y809750D01*
X490700Y809833D01*
X491200Y809750D01*
X491700Y809500D01*
G01X500733Y806500D02*
Y809833D01*
G01Y809167D02*
X501150Y809500D01*
X501567Y809750D01*
X502150Y809833D01*
X502567Y809750D01*
X503067Y809500D01*
G01X506250Y808750D02*
X508917D01*
X508667Y809333D01*
X508250Y809667D01*
X507667Y809833D01*
X507083Y809750D01*
X506583Y809500D01*
X506250Y808917D01*
X506083Y808417D01*
Y807917D01*
X506250Y807417D01*
X506667Y806917D01*
X507167Y806583D01*
X507750Y806500D01*
X508333Y806667D01*
X508917Y807167D01*
G01X514600Y804833D02*
Y809833D01*
G01Y809083D02*
X514183Y809500D01*
X513683Y809750D01*
X513100Y809833D01*
X512600Y809750D01*
X512017Y809333D01*
X511683Y808750D01*
X511600Y808167D01*
X511683Y807583D01*
X512017Y807000D01*
X512600Y806583D01*
X513100Y806500D01*
X513683Y806583D01*
X514183Y806833D01*
X514600Y807250D01*
G01X517283Y809833D02*
Y807500D01*
X517617Y806917D01*
X518117Y806583D01*
X518700Y806500D01*
X519283Y806583D01*
X519783Y806917D01*
X520117Y807500D01*
G01Y806500D02*
Y809833D01*
G01X524300D02*
Y806500D01*
G01Y811167D02*
X524133Y811250D01*
Y811417D01*
X524300Y811500D01*
X524467Y811417D01*
Y811250D01*
X524300Y811167D01*
G01X528733Y806500D02*
Y809833D01*
G01Y809167D02*
X529150Y809500D01*
X529567Y809750D01*
X530150Y809833D01*
X530567Y809750D01*
X531067Y809500D01*
G01X534250Y808750D02*
X536917D01*
X536667Y809333D01*
X536250Y809667D01*
X535667Y809833D01*
X535083Y809750D01*
X534583Y809500D01*
X534250Y808917D01*
X534083Y808417D01*
Y807917D01*
X534250Y807417D01*
X534667Y806917D01*
X535167Y806583D01*
X535750Y806500D01*
X536333Y806667D01*
X536917Y807167D01*
G01X542600Y811500D02*
Y806500D01*
G01Y807250D02*
X542267Y806833D01*
X541767Y806583D01*
X541183Y806500D01*
X540517Y806667D01*
X540017Y807083D01*
X539683Y807583D01*
X539600Y808167D01*
X539683Y808750D01*
X540017Y809250D01*
X540517Y809667D01*
X541183Y809833D01*
X541767Y809750D01*
X542183Y809583D01*
X542600Y809250D01*
G01X546533Y805583D02*
X546867Y806667D01*
G01X0Y820500D02*
X694500D01*
G01X0Y850500D02*
X694500D01*
G01X112333Y-60000D02*
Y-65000D01*
X115667D01*
G01X119600D02*
X119100Y-64917D01*
X118600Y-64583D01*
X118267Y-64000D01*
X118100Y-63333D01*
X118267Y-62667D01*
X118600Y-62083D01*
X119100Y-61750D01*
X119600Y-61667D01*
X120100Y-61750D01*
X120600Y-62083D01*
X120933Y-62667D01*
X121017Y-63333D01*
X120933Y-64000D01*
X120600Y-64583D01*
X120100Y-64917D01*
X119600Y-65000D01*
G01X124033Y-66250D02*
X124617Y-66583D01*
X125283Y-66667D01*
X125867Y-66583D01*
X126367Y-66167D01*
X126700Y-65583D01*
Y-61667D01*
G01Y-62333D02*
X126367Y-62000D01*
X125867Y-61750D01*
X125283Y-61667D01*
X124617Y-61833D01*
X124200Y-62167D01*
X123867Y-62750D01*
X123700Y-63333D01*
X123783Y-63833D01*
X124117Y-64417D01*
X124617Y-64833D01*
X125283Y-65000D01*
X125783Y-64917D01*
X126367Y-64583D01*
X126700Y-64250D01*
G01X130800Y-65000D02*
X130300Y-64917D01*
X129800Y-64583D01*
X129467Y-64000D01*
X129300Y-63333D01*
X129467Y-62667D01*
X129800Y-62083D01*
X130300Y-61750D01*
X130800Y-61667D01*
X131300Y-61750D01*
X131800Y-62083D01*
X132133Y-62667D01*
X132217Y-63333D01*
X132133Y-64000D01*
X131800Y-64583D01*
X131300Y-64917D01*
X130800Y-65000D01*
G01X114000Y-36000D02*
Y-41000D01*
G01X112833Y-37667D02*
X115167D01*
G01X118183Y-41000D02*
Y-36000D01*
G01Y-38417D02*
X118600Y-38000D01*
X119017Y-37750D01*
X119683Y-37667D01*
X120183Y-37750D01*
X120767Y-38083D01*
X121017Y-38583D01*
Y-41000D01*
G01X125200Y-37667D02*
Y-41000D01*
G01Y-36333D02*
X125033Y-36250D01*
Y-36083D01*
X125200Y-36000D01*
X125367Y-36083D01*
Y-36250D01*
X125200Y-36333D01*
G01X132133Y-38083D02*
X131550Y-37750D01*
X131050Y-37667D01*
X130383Y-37833D01*
X129883Y-38167D01*
X129550Y-38750D01*
X129467Y-39333D01*
X129550Y-39917D01*
X129883Y-40417D01*
X130383Y-40833D01*
X131050Y-41000D01*
X131633Y-40833D01*
X132133Y-40500D01*
G01X134983Y-41000D02*
Y-36000D01*
G01X137650Y-37667D02*
X134983Y-39583D01*
G01X136067Y-38833D02*
X137817Y-41000D01*
G01X140583D02*
Y-37667D01*
G01Y-38500D02*
X140917Y-38083D01*
X141417Y-37750D01*
X142083Y-37667D01*
X142667Y-37750D01*
X143167Y-38083D01*
X143417Y-38667D01*
Y-41000D01*
G01X146350Y-38750D02*
X149017D01*
X148767Y-38167D01*
X148350Y-37833D01*
X147767Y-37667D01*
X147183Y-37750D01*
X146683Y-38000D01*
X146350Y-38583D01*
X146183Y-39083D01*
Y-39583D01*
X146350Y-40083D01*
X146767Y-40583D01*
X147267Y-40917D01*
X147850Y-41000D01*
X148433Y-40833D01*
X149017Y-40333D01*
G01X151950Y-40417D02*
X152367Y-40750D01*
X152950Y-41000D01*
X153450D01*
X153950Y-40833D01*
X154283Y-40583D01*
X154450Y-40250D01*
X154367Y-39750D01*
X154033Y-39500D01*
X152533Y-39000D01*
X152200Y-38417D01*
X152367Y-38000D01*
X152700Y-37750D01*
X153200Y-37667D01*
X153700Y-37750D01*
X154200Y-38000D01*
G01X157550Y-40417D02*
X157967Y-40750D01*
X158550Y-41000D01*
X159050D01*
X159550Y-40833D01*
X159883Y-40583D01*
X160050Y-40250D01*
X159967Y-39750D01*
X159633Y-39500D01*
X158133Y-39000D01*
X157800Y-38417D01*
X157967Y-38000D01*
X158300Y-37750D01*
X158800Y-37667D01*
X159300Y-37750D01*
X159800Y-38000D01*
G01X114000Y-15000D02*
Y-20000D01*
G01X112833Y-16667D02*
X115167D01*
G01X118183Y-20000D02*
Y-15000D01*
G01Y-17417D02*
X118600Y-17000D01*
X119017Y-16750D01*
X119683Y-16667D01*
X120183Y-16750D01*
X120767Y-17083D01*
X121017Y-17583D01*
Y-20000D01*
G01X125200Y-16667D02*
Y-20000D01*
G01Y-15333D02*
X125033Y-15250D01*
Y-15083D01*
X125200Y-15000D01*
X125367Y-15083D01*
Y-15250D01*
X125200Y-15333D01*
G01X132133Y-17083D02*
X131550Y-16750D01*
X131050Y-16667D01*
X130383Y-16833D01*
X129883Y-17167D01*
X129550Y-17750D01*
X129467Y-18333D01*
X129550Y-18917D01*
X129883Y-19417D01*
X130383Y-19833D01*
X131050Y-20000D01*
X131633Y-19833D01*
X132133Y-19500D01*
G01X134983Y-20000D02*
Y-15000D01*
G01X137650Y-16667D02*
X134983Y-18583D01*
G01X136067Y-17833D02*
X137817Y-20000D01*
G01X140583D02*
Y-16667D01*
G01Y-17500D02*
X140917Y-17083D01*
X141417Y-16750D01*
X142083Y-16667D01*
X142667Y-16750D01*
X143167Y-17083D01*
X143417Y-17667D01*
Y-20000D01*
G01X146350Y-17750D02*
X149017D01*
X148767Y-17167D01*
X148350Y-16833D01*
X147767Y-16667D01*
X147183Y-16750D01*
X146683Y-17000D01*
X146350Y-17583D01*
X146183Y-18083D01*
Y-18583D01*
X146350Y-19083D01*
X146767Y-19583D01*
X147267Y-19917D01*
X147850Y-20000D01*
X148433Y-19833D01*
X149017Y-19333D01*
G01X151950Y-19417D02*
X152367Y-19750D01*
X152950Y-20000D01*
X153450D01*
X153950Y-19833D01*
X154283Y-19583D01*
X154450Y-19250D01*
X154367Y-18750D01*
X154033Y-18500D01*
X152533Y-18000D01*
X152200Y-17417D01*
X152367Y-17000D01*
X152700Y-16750D01*
X153200Y-16667D01*
X153700Y-16750D01*
X154200Y-17000D01*
G01X157550Y-19417D02*
X157967Y-19750D01*
X158550Y-20000D01*
X159050D01*
X159550Y-19833D01*
X159883Y-19583D01*
X160050Y-19250D01*
X159967Y-18750D01*
X159633Y-18500D01*
X158133Y-18000D01*
X157800Y-17417D01*
X157967Y-17000D01*
X158300Y-16750D01*
X158800Y-16667D01*
X159300Y-16750D01*
X159800Y-17000D01*
G01X103500Y679000D02*
Y-69500D01*
G01Y-9500D02*
X694500D01*
G01X103500Y-54500D02*
X694500D01*
G01X112483Y24700D02*
Y29700D01*
X114650Y25533D01*
X116817Y29700D01*
Y24700D01*
G01X121750D02*
Y28033D01*
G01Y27450D02*
X121417Y27783D01*
X120917Y27950D01*
X120333Y28033D01*
X119750Y27867D01*
X119250Y27533D01*
X118917Y27033D01*
X118750Y26367D01*
X118917Y25700D01*
X119250Y25200D01*
X119750Y24867D01*
X120333Y24700D01*
X120917Y24783D01*
X121417Y25033D01*
X121750Y25367D01*
G01X124683Y24700D02*
Y28033D01*
G01Y27367D02*
X125100Y27700D01*
X125517Y27950D01*
X126100Y28033D01*
X126517Y27950D01*
X127017Y27700D01*
G01X130033Y24700D02*
Y29700D01*
G01X132700Y28033D02*
X130033Y26117D01*
G01X131117Y26867D02*
X132867Y24700D01*
G01X137467Y23033D02*
X138300Y23867D01*
X138717Y24700D01*
Y28033D01*
X138300Y28867D01*
X137467Y29700D01*
G01X113070Y36130D02*
X114737D01*
Y34630D01*
X114237Y34130D01*
X113653Y33797D01*
X112820Y33630D01*
X111987Y33797D01*
X111403Y34130D01*
X110903Y34630D01*
X110570Y35213D01*
X110403Y35880D01*
Y36463D01*
X110570Y36963D01*
X110903Y37547D01*
X111403Y38047D01*
X111903Y38380D01*
X112570Y38630D01*
X113153D01*
X113820Y38463D01*
X114320Y38130D01*
G01X118170Y33630D02*
X117670Y33713D01*
X117170Y34047D01*
X116837Y34630D01*
X116670Y35297D01*
X116837Y35963D01*
X117170Y36547D01*
X117670Y36880D01*
X118170Y36963D01*
X118670Y36880D01*
X119170Y36547D01*
X119503Y35963D01*
X119587Y35297D01*
X119503Y34630D01*
X119170Y34047D01*
X118670Y33713D01*
X118170Y33630D01*
G01X123770D02*
Y38630D01*
G01X130870D02*
Y33630D01*
G01Y34380D02*
X130537Y33963D01*
X130037Y33713D01*
X129453Y33630D01*
X128787Y33797D01*
X128287Y34213D01*
X127953Y34713D01*
X127870Y35297D01*
X127953Y35880D01*
X128287Y36380D01*
X128787Y36797D01*
X129453Y36963D01*
X130037Y36880D01*
X130453Y36713D01*
X130870Y36380D01*
G01X133720Y35880D02*
X136387D01*
X136137Y36463D01*
X135720Y36797D01*
X135137Y36963D01*
X134553Y36880D01*
X134053Y36630D01*
X133720Y36047D01*
X133553Y35547D01*
Y35047D01*
X133720Y34547D01*
X134137Y34047D01*
X134637Y33713D01*
X135220Y33630D01*
X135803Y33797D01*
X136387Y34297D01*
G01X139153Y33630D02*
Y36963D01*
G01Y36130D02*
X139487Y36547D01*
X139987Y36880D01*
X140653Y36963D01*
X141237Y36880D01*
X141737Y36547D01*
X141987Y35963D01*
Y33630D01*
G01X151270D02*
Y37880D01*
X151437Y38297D01*
X151770Y38547D01*
X152270Y38630D01*
X152770Y38463D01*
X153020Y38047D01*
G01X152020Y36630D02*
X150353D01*
G01X157370Y36963D02*
Y33630D01*
G01Y38297D02*
X157203Y38380D01*
Y38547D01*
X157370Y38630D01*
X157537Y38547D01*
Y38380D01*
X157370Y38297D01*
G01X161553Y33630D02*
Y36963D01*
G01Y36130D02*
X161887Y36547D01*
X162387Y36880D01*
X163053Y36963D01*
X163637Y36880D01*
X164137Y36547D01*
X164387Y35963D01*
Y33630D01*
G01X167403Y32380D02*
X167987Y32047D01*
X168653Y31963D01*
X169237Y32047D01*
X169737Y32463D01*
X170070Y33047D01*
Y36963D01*
G01Y36297D02*
X169737Y36630D01*
X169237Y36880D01*
X168653Y36963D01*
X167987Y36797D01*
X167570Y36463D01*
X167237Y35880D01*
X167070Y35297D01*
X167153Y34797D01*
X167487Y34213D01*
X167987Y33797D01*
X168653Y33630D01*
X169153Y33713D01*
X169737Y34047D01*
X170070Y34380D01*
G01X172920Y35880D02*
X175587D01*
X175337Y36463D01*
X174920Y36797D01*
X174337Y36963D01*
X173753Y36880D01*
X173253Y36630D01*
X172920Y36047D01*
X172753Y35547D01*
Y35047D01*
X172920Y34547D01*
X173337Y34047D01*
X173837Y33713D01*
X174420Y33630D01*
X175003Y33797D01*
X175587Y34297D01*
G01X178603Y33630D02*
Y36963D01*
G01Y36297D02*
X179020Y36630D01*
X179437Y36880D01*
X180020Y36963D01*
X180437Y36880D01*
X180937Y36630D01*
G01X189303Y33630D02*
Y38630D01*
X191303D01*
X191970Y38380D01*
X192470Y37797D01*
X192637Y37130D01*
X192470Y36463D01*
X192053Y35963D01*
X191303Y35713D01*
X189303D01*
G01X194487Y33630D02*
X196570Y38630D01*
X198653Y33630D01*
G01X197903Y35380D02*
X195237D01*
G01X200337Y33630D02*
Y38630D01*
X202003D01*
X202670Y38380D01*
X203170Y38047D01*
X203587Y37547D01*
X203920Y36963D01*
X204003Y36130D01*
X203920Y35297D01*
X203587Y34713D01*
X203170Y34213D01*
X202670Y33880D01*
X202003Y33630D01*
X200337D01*
G01X211870Y33463D02*
X214870Y38630D01*
G01X217387Y33630D02*
Y38630D01*
X220553D01*
G01X219387Y36213D02*
X217387D01*
G01X224570Y36963D02*
Y33630D01*
G01Y38297D02*
X224403Y38380D01*
Y38547D01*
X224570Y38630D01*
X224737Y38547D01*
Y38380D01*
X224570Y38297D01*
G01X231670Y38630D02*
Y33630D01*
G01Y34380D02*
X231337Y33963D01*
X230837Y33713D01*
X230253Y33630D01*
X229587Y33797D01*
X229087Y34213D01*
X228753Y34713D01*
X228670Y35297D01*
X228753Y35880D01*
X229087Y36380D01*
X229587Y36797D01*
X230253Y36963D01*
X230837Y36880D01*
X231253Y36713D01*
X231670Y36380D01*
G01X234353Y36963D02*
Y34630D01*
X234687Y34047D01*
X235187Y33713D01*
X235770Y33630D01*
X236353Y33713D01*
X236853Y34047D01*
X237187Y34630D01*
G01Y33630D02*
Y36963D01*
G01X242703Y36547D02*
X242120Y36880D01*
X241620Y36963D01*
X240953Y36797D01*
X240453Y36463D01*
X240120Y35880D01*
X240037Y35297D01*
X240120Y34713D01*
X240453Y34213D01*
X240953Y33797D01*
X241620Y33630D01*
X242203Y33797D01*
X242703Y34130D01*
G01X246970Y36963D02*
Y33630D01*
G01Y38297D02*
X246803Y38380D01*
Y38547D01*
X246970Y38630D01*
X247137Y38547D01*
Y38380D01*
X246970Y38297D01*
G01X254070Y33630D02*
Y36963D01*
G01Y36380D02*
X253737Y36713D01*
X253237Y36880D01*
X252653Y36963D01*
X252070Y36797D01*
X251570Y36463D01*
X251237Y35963D01*
X251070Y35297D01*
X251237Y34630D01*
X251570Y34130D01*
X252070Y33797D01*
X252653Y33630D01*
X253237Y33713D01*
X253737Y33963D01*
X254070Y34297D01*
G01X258170Y33630D02*
Y38630D01*
G01X112743Y42673D02*
X111910Y43507D01*
X111493Y44340D01*
Y47673D01*
X111910Y48507D01*
X112743Y49340D01*
G01X116260Y44340D02*
Y47673D01*
G01Y46757D02*
X116510Y47173D01*
X116927Y47507D01*
X117510Y47673D01*
X118093Y47507D01*
X118510Y47173D01*
X118760Y46757D01*
Y44340D01*
G01Y46757D02*
X119010Y47173D01*
X119427Y47507D01*
X120010Y47673D01*
X120593Y47507D01*
X121010Y47173D01*
X121260Y46673D01*
Y44340D01*
G01X123110Y46590D02*
X125777D01*
X125527Y47173D01*
X125110Y47507D01*
X124527Y47673D01*
X123943Y47590D01*
X123443Y47340D01*
X123110Y46757D01*
X122943Y46257D01*
Y45757D01*
X123110Y45257D01*
X123527Y44757D01*
X124027Y44423D01*
X124610Y44340D01*
X125193Y44507D01*
X125777Y45007D01*
G01X131460Y44340D02*
Y47673D01*
G01Y47090D02*
X131127Y47423D01*
X130627Y47590D01*
X130043Y47673D01*
X129460Y47507D01*
X128960Y47173D01*
X128627Y46673D01*
X128460Y46007D01*
X128627Y45340D01*
X128960Y44840D01*
X129460Y44507D01*
X130043Y44340D01*
X130627Y44423D01*
X131127Y44673D01*
X131460Y45007D01*
G01X134310Y44923D02*
X134727Y44590D01*
X135310Y44340D01*
X135810D01*
X136310Y44507D01*
X136643Y44757D01*
X136810Y45090D01*
X136727Y45590D01*
X136393Y45840D01*
X134893Y46340D01*
X134560Y46923D01*
X134727Y47340D01*
X135060Y47590D01*
X135560Y47673D01*
X136060Y47590D01*
X136560Y47340D01*
G01X139743Y47673D02*
Y45340D01*
X140077Y44757D01*
X140577Y44423D01*
X141160Y44340D01*
X141743Y44423D01*
X142243Y44757D01*
X142577Y45340D01*
G01Y44340D02*
Y47673D01*
G01X145593Y44340D02*
Y47673D01*
G01Y47007D02*
X146010Y47340D01*
X146427Y47590D01*
X147010Y47673D01*
X147427Y47590D01*
X147927Y47340D01*
G01X151110Y46590D02*
X153777D01*
X153527Y47173D01*
X153110Y47507D01*
X152527Y47673D01*
X151943Y47590D01*
X151443Y47340D01*
X151110Y46757D01*
X150943Y46257D01*
Y45757D01*
X151110Y45257D01*
X151527Y44757D01*
X152027Y44423D01*
X152610Y44340D01*
X153193Y44507D01*
X153777Y45007D01*
G01X163560Y49340D02*
Y44340D01*
G01X162393Y47673D02*
X164727D01*
G01X169160Y44340D02*
X168660Y44423D01*
X168160Y44757D01*
X167827Y45340D01*
X167660Y46007D01*
X167827Y46673D01*
X168160Y47257D01*
X168660Y47590D01*
X169160Y47673D01*
X169660Y47590D01*
X170160Y47257D01*
X170493Y46673D01*
X170577Y46007D01*
X170493Y45340D01*
X170160Y44757D01*
X169660Y44423D01*
X169160Y44340D01*
G01X173260Y42673D02*
Y47673D01*
G01Y46923D02*
X173677Y47340D01*
X174093Y47590D01*
X174760Y47673D01*
X175343Y47590D01*
X175927Y47173D01*
X176177Y46590D01*
X176260Y46007D01*
X176177Y45423D01*
X175927Y44840D01*
X175427Y44507D01*
X174760Y44340D01*
X174177Y44423D01*
X173593Y44673D01*
X173260Y45007D01*
G01X184710Y44923D02*
X185127Y44590D01*
X185710Y44340D01*
X186210D01*
X186710Y44507D01*
X187043Y44757D01*
X187210Y45090D01*
X187127Y45590D01*
X186793Y45840D01*
X185293Y46340D01*
X184960Y46923D01*
X185127Y47340D01*
X185460Y47590D01*
X185960Y47673D01*
X186460Y47590D01*
X186960Y47340D01*
G01X191560Y47673D02*
Y44340D01*
G01Y49007D02*
X191393Y49090D01*
Y49257D01*
X191560Y49340D01*
X191727Y49257D01*
Y49090D01*
X191560Y49007D01*
G01X195910Y47673D02*
X198410D01*
X195910Y44340D01*
X198410D01*
G01X201510Y46590D02*
X204177D01*
X203927Y47173D01*
X203510Y47507D01*
X202927Y47673D01*
X202343Y47590D01*
X201843Y47340D01*
X201510Y46757D01*
X201343Y46257D01*
Y45757D01*
X201510Y45257D01*
X201927Y44757D01*
X202427Y44423D01*
X203010Y44340D01*
X203593Y44507D01*
X204177Y45007D01*
G01X213960Y44340D02*
X213460Y44423D01*
X212960Y44757D01*
X212627Y45340D01*
X212460Y46007D01*
X212627Y46673D01*
X212960Y47257D01*
X213460Y47590D01*
X213960Y47673D01*
X214460Y47590D01*
X214960Y47257D01*
X215293Y46673D01*
X215377Y46007D01*
X215293Y45340D01*
X214960Y44757D01*
X214460Y44423D01*
X213960Y44340D01*
G01X219060D02*
Y48590D01*
X219227Y49007D01*
X219560Y49257D01*
X220060Y49340D01*
X220560Y49173D01*
X220810Y48757D01*
G01X219810Y47340D02*
X218143D01*
G01X229093Y44340D02*
Y49340D01*
X231093D01*
X231760Y49090D01*
X232260Y48507D01*
X232427Y47840D01*
X232260Y47173D01*
X231843Y46673D01*
X231093Y46423D01*
X229093D01*
G01X234277Y44340D02*
X236360Y49340D01*
X238443Y44340D01*
G01X237693Y46090D02*
X235027D01*
G01X240127Y44340D02*
Y49340D01*
X241793D01*
X242460Y49090D01*
X242960Y48757D01*
X243377Y48257D01*
X243710Y47673D01*
X243793Y46840D01*
X243710Y46007D01*
X243377Y45423D01*
X242960Y44923D01*
X242460Y44590D01*
X241793Y44340D01*
X240127D01*
G01X251660Y44173D02*
X254660Y49340D01*
G01X119183Y-2167D02*
X118350Y-1333D01*
X117933Y-500D01*
Y2833D01*
X118350Y3667D01*
X119183Y4500D01*
G01X123450Y167D02*
X124117Y-250D01*
X124867Y-500D01*
X125533D01*
X126200Y-250D01*
X126700Y167D01*
X126950Y750D01*
X126783Y1333D01*
X126367Y1833D01*
X125617Y2167D01*
X124617Y2333D01*
X124033Y2667D01*
X123783Y3250D01*
X123950Y3833D01*
X124367Y4250D01*
X124950Y4500D01*
X125533D01*
X126117Y4333D01*
X126617Y3917D01*
G01X128633Y-500D02*
Y4500D01*
X130800Y333D01*
X132967Y4500D01*
Y-500D01*
G01X134567D02*
Y4500D01*
X136233D01*
X136900Y4250D01*
X137400Y3917D01*
X137817Y3417D01*
X138150Y2833D01*
X138233Y2000D01*
X138150Y1167D01*
X137817Y583D01*
X137400Y83D01*
X136900Y-250D01*
X136233Y-500D01*
X134567D01*
G01X142417Y-2167D02*
X143250Y-1333D01*
X143667Y-500D01*
Y2833D01*
X143250Y3667D01*
X142417Y4500D01*
G01X112250Y12167D02*
X112917Y11750D01*
X113667Y11500D01*
X114333D01*
X115000Y11750D01*
X115500Y12167D01*
X115750Y12750D01*
X115583Y13333D01*
X115167Y13833D01*
X114417Y14167D01*
X113417Y14333D01*
X112833Y14667D01*
X112583Y15250D01*
X112750Y15833D01*
X113167Y16250D01*
X113750Y16500D01*
X114333D01*
X114917Y16333D01*
X115417Y15917D01*
G01X119600Y11500D02*
X119100Y11583D01*
X118600Y11917D01*
X118267Y12500D01*
X118100Y13167D01*
X118267Y13833D01*
X118600Y14417D01*
X119100Y14750D01*
X119600Y14833D01*
X120100Y14750D01*
X120600Y14417D01*
X120933Y13833D01*
X121017Y13167D01*
X120933Y12500D01*
X120600Y11917D01*
X120100Y11583D01*
X119600Y11500D01*
G01X125200D02*
Y16500D01*
G01X132300D02*
Y11500D01*
G01Y12250D02*
X131967Y11833D01*
X131467Y11583D01*
X130883Y11500D01*
X130217Y11667D01*
X129717Y12083D01*
X129383Y12583D01*
X129300Y13167D01*
X129383Y13750D01*
X129717Y14250D01*
X130217Y14667D01*
X130883Y14833D01*
X131467Y14750D01*
X131883Y14583D01*
X132300Y14250D01*
G01X135150Y13750D02*
X137817D01*
X137567Y14333D01*
X137150Y14667D01*
X136567Y14833D01*
X135983Y14750D01*
X135483Y14500D01*
X135150Y13917D01*
X134983Y13417D01*
Y12917D01*
X135150Y12417D01*
X135567Y11917D01*
X136067Y11583D01*
X136650Y11500D01*
X137233Y11667D01*
X137817Y12167D01*
G01X140833Y11500D02*
Y14833D01*
G01Y14167D02*
X141250Y14500D01*
X141667Y14750D01*
X142250Y14833D01*
X142667Y14750D01*
X143167Y14500D01*
G01X150700Y11500D02*
Y14833D01*
G01Y13917D02*
X150950Y14333D01*
X151367Y14667D01*
X151950Y14833D01*
X152533Y14667D01*
X152950Y14333D01*
X153200Y13917D01*
Y11500D01*
G01Y13917D02*
X153450Y14333D01*
X153867Y14667D01*
X154450Y14833D01*
X155033Y14667D01*
X155450Y14333D01*
X155700Y13833D01*
Y11500D01*
G01X160300D02*
Y14833D01*
G01Y14250D02*
X159967Y14583D01*
X159467Y14750D01*
X158883Y14833D01*
X158300Y14667D01*
X157800Y14333D01*
X157467Y13833D01*
X157300Y13167D01*
X157467Y12500D01*
X157800Y12000D01*
X158300Y11667D01*
X158883Y11500D01*
X159467Y11583D01*
X159967Y11833D01*
X160300Y12167D01*
G01X163150Y12083D02*
X163567Y11750D01*
X164150Y11500D01*
X164650D01*
X165150Y11667D01*
X165483Y11917D01*
X165650Y12250D01*
X165567Y12750D01*
X165233Y13000D01*
X163733Y13500D01*
X163400Y14083D01*
X163567Y14500D01*
X163900Y14750D01*
X164400Y14833D01*
X164900Y14750D01*
X165400Y14500D01*
G01X168583Y11500D02*
Y16500D01*
G01X171250Y14833D02*
X168583Y12917D01*
G01X169667Y13667D02*
X171417Y11500D01*
G01X182700Y16500D02*
Y11500D01*
G01Y12250D02*
X182367Y11833D01*
X181867Y11583D01*
X181283Y11500D01*
X180617Y11667D01*
X180117Y12083D01*
X179783Y12583D01*
X179700Y13167D01*
X179783Y13750D01*
X180117Y14250D01*
X180617Y14667D01*
X181283Y14833D01*
X181867Y14750D01*
X182283Y14583D01*
X182700Y14250D01*
G01X185550Y13750D02*
X188217D01*
X187967Y14333D01*
X187550Y14667D01*
X186967Y14833D01*
X186383Y14750D01*
X185883Y14500D01*
X185550Y13917D01*
X185383Y13417D01*
Y12917D01*
X185550Y12417D01*
X185967Y11917D01*
X186467Y11583D01*
X187050Y11500D01*
X187633Y11667D01*
X188217Y12167D01*
G01X191900Y11500D02*
Y15750D01*
X192067Y16167D01*
X192400Y16417D01*
X192900Y16500D01*
X193400Y16333D01*
X193650Y15917D01*
G01X192650Y14500D02*
X190983D01*
G01X198000Y14833D02*
Y11500D01*
G01Y16167D02*
X197833Y16250D01*
Y16417D01*
X198000Y16500D01*
X198167Y16417D01*
Y16250D01*
X198000Y16167D01*
G01X202183Y11500D02*
Y14833D01*
G01Y14000D02*
X202517Y14417D01*
X203017Y14750D01*
X203683Y14833D01*
X204267Y14750D01*
X204767Y14417D01*
X205017Y13833D01*
Y11500D01*
G01X207950Y13750D02*
X210617D01*
X210367Y14333D01*
X209950Y14667D01*
X209367Y14833D01*
X208783Y14750D01*
X208283Y14500D01*
X207950Y13917D01*
X207783Y13417D01*
Y12917D01*
X207950Y12417D01*
X208367Y11917D01*
X208867Y11583D01*
X209450Y11500D01*
X210033Y11667D01*
X210617Y12167D01*
G01X218900Y9833D02*
Y14833D01*
G01Y14083D02*
X219317Y14500D01*
X219733Y14750D01*
X220400Y14833D01*
X220983Y14750D01*
X221567Y14333D01*
X221817Y13750D01*
X221900Y13167D01*
X221817Y12583D01*
X221567Y12000D01*
X221067Y11667D01*
X220400Y11500D01*
X219817Y11583D01*
X219233Y11833D01*
X218900Y12167D01*
G01X227500Y11500D02*
Y14833D01*
G01Y14250D02*
X227167Y14583D01*
X226667Y14750D01*
X226083Y14833D01*
X225500Y14667D01*
X225000Y14333D01*
X224667Y13833D01*
X224500Y13167D01*
X224667Y12500D01*
X225000Y12000D01*
X225500Y11667D01*
X226083Y11500D01*
X226667Y11583D01*
X227167Y11833D01*
X227500Y12167D01*
G01X233100Y16500D02*
Y11500D01*
G01Y12250D02*
X232767Y11833D01*
X232267Y11583D01*
X231683Y11500D01*
X231017Y11667D01*
X230517Y12083D01*
X230183Y12583D01*
X230100Y13167D01*
X230183Y13750D01*
X230517Y14250D01*
X231017Y14667D01*
X231683Y14833D01*
X232267Y14750D01*
X232683Y14583D01*
X233100Y14250D01*
G01X112333Y51500D02*
Y56500D01*
X114333D01*
X115000Y56250D01*
X115500Y55667D01*
X115667Y55000D01*
X115500Y54333D01*
X115083Y53833D01*
X114333Y53583D01*
X112333D01*
G01X117517Y51500D02*
X119600Y56500D01*
X121683Y51500D01*
G01X120933Y53250D02*
X118267D01*
G01X123367Y51500D02*
Y56500D01*
X125033D01*
X125700Y56250D01*
X126200Y55917D01*
X126617Y55417D01*
X126950Y54833D01*
X127033Y54000D01*
X126950Y53167D01*
X126617Y52583D01*
X126200Y52083D01*
X125700Y51750D01*
X125033Y51500D01*
X123367D01*
G01X135150Y52083D02*
X135567Y51750D01*
X136150Y51500D01*
X136650D01*
X137150Y51667D01*
X137483Y51917D01*
X137650Y52250D01*
X137567Y52750D01*
X137233Y53000D01*
X135733Y53500D01*
X135400Y54083D01*
X135567Y54500D01*
X135900Y54750D01*
X136400Y54833D01*
X136900Y54750D01*
X137400Y54500D01*
G01X142000Y54833D02*
Y51500D01*
G01Y56167D02*
X141833Y56250D01*
Y56417D01*
X142000Y56500D01*
X142167Y56417D01*
Y56250D01*
X142000Y56167D01*
G01X146350Y54833D02*
X148850D01*
X146350Y51500D01*
X148850D01*
G01X151950Y53750D02*
X154617D01*
X154367Y54333D01*
X153950Y54667D01*
X153367Y54833D01*
X152783Y54750D01*
X152283Y54500D01*
X151950Y53917D01*
X151783Y53417D01*
Y52917D01*
X151950Y52417D01*
X152367Y51917D01*
X152867Y51583D01*
X153450Y51500D01*
X154033Y51667D01*
X154617Y52167D01*
G01X103500Y60500D02*
X694500D01*
G01X114000Y85000D02*
Y80000D01*
G01X112083Y85000D02*
X115917D01*
G01X118433Y80000D02*
Y83333D01*
G01Y82667D02*
X118850Y83000D01*
X119267Y83250D01*
X119850Y83333D01*
X120267Y83250D01*
X120767Y83000D01*
G01X126700Y80000D02*
Y83333D01*
G01Y82750D02*
X126367Y83083D01*
X125867Y83250D01*
X125283Y83333D01*
X124700Y83167D01*
X124200Y82833D01*
X123867Y82333D01*
X123700Y81667D01*
X123867Y81000D01*
X124200Y80500D01*
X124700Y80167D01*
X125283Y80000D01*
X125867Y80083D01*
X126367Y80333D01*
X126700Y80667D01*
G01X132133Y82917D02*
X131550Y83250D01*
X131050Y83333D01*
X130383Y83167D01*
X129883Y82833D01*
X129550Y82250D01*
X129467Y81667D01*
X129550Y81083D01*
X129883Y80583D01*
X130383Y80167D01*
X131050Y80000D01*
X131633Y80167D01*
X132133Y80500D01*
G01X135150Y82250D02*
X137817D01*
X137567Y82833D01*
X137150Y83167D01*
X136567Y83333D01*
X135983Y83250D01*
X135483Y83000D01*
X135150Y82417D01*
X134983Y81917D01*
Y81417D01*
X135150Y80917D01*
X135567Y80417D01*
X136067Y80083D01*
X136650Y80000D01*
X137233Y80167D01*
X137817Y80667D01*
G01X145517Y83333D02*
X146517Y80000D01*
X147600Y83333D01*
X148683Y80000D01*
X149683Y83333D01*
G01X153200D02*
Y80000D01*
G01Y84667D02*
X153033Y84750D01*
Y84917D01*
X153200Y85000D01*
X153367Y84917D01*
Y84750D01*
X153200Y84667D01*
G01X160300Y85000D02*
Y80000D01*
G01Y80750D02*
X159967Y80333D01*
X159467Y80083D01*
X158883Y80000D01*
X158217Y80167D01*
X157717Y80583D01*
X157383Y81083D01*
X157300Y81667D01*
X157383Y82250D01*
X157717Y82750D01*
X158217Y83167D01*
X158883Y83333D01*
X159467Y83250D01*
X159883Y83083D01*
X160300Y82750D01*
G01X164400Y85000D02*
Y80000D01*
G01X163233Y83333D02*
X165567D01*
G01X168583Y80000D02*
Y85000D01*
G01Y82583D02*
X169000Y83000D01*
X169417Y83250D01*
X170083Y83333D01*
X170583Y83250D01*
X171167Y82917D01*
X171417Y82417D01*
Y80000D01*
G01X112333Y111500D02*
Y116500D01*
X114417D01*
X115083Y116250D01*
X115500Y115917D01*
X115667Y115250D01*
X115500Y114583D01*
X115000Y114167D01*
X114417Y113917D01*
X112333D01*
G01X114417D02*
X115667Y111500D01*
G01X118350Y113750D02*
X121017D01*
X120767Y114333D01*
X120350Y114667D01*
X119767Y114833D01*
X119183Y114750D01*
X118683Y114500D01*
X118350Y113917D01*
X118183Y113417D01*
Y112917D01*
X118350Y112417D01*
X118767Y111917D01*
X119267Y111583D01*
X119850Y111500D01*
X120433Y111667D01*
X121017Y112167D01*
G01X125200Y111500D02*
Y116500D01*
G01X132300Y111500D02*
Y114833D01*
G01Y114250D02*
X131967Y114583D01*
X131467Y114750D01*
X130883Y114833D01*
X130300Y114667D01*
X129800Y114333D01*
X129467Y113833D01*
X129300Y113167D01*
X129467Y112500D01*
X129800Y112000D01*
X130300Y111667D01*
X130883Y111500D01*
X131467Y111583D01*
X131967Y111833D01*
X132300Y112167D01*
G01X136400Y116500D02*
Y111500D01*
G01X135233Y114833D02*
X137567D01*
G01X142000D02*
Y111500D01*
G01Y116167D02*
X141833Y116250D01*
Y116417D01*
X142000Y116500D01*
X142167Y116417D01*
Y116250D01*
X142000Y116167D01*
G01X146100Y114833D02*
X147600Y111500D01*
X149100Y114833D01*
G01X151950Y113750D02*
X154617D01*
X154367Y114333D01*
X153950Y114667D01*
X153367Y114833D01*
X152783Y114750D01*
X152283Y114500D01*
X151950Y113917D01*
X151783Y113417D01*
Y112917D01*
X151950Y112417D01*
X152367Y111917D01*
X152867Y111583D01*
X153450Y111500D01*
X154033Y111667D01*
X154617Y112167D01*
G01X162900Y109833D02*
Y114833D01*
G01Y114083D02*
X163317Y114500D01*
X163733Y114750D01*
X164400Y114833D01*
X164983Y114750D01*
X165567Y114333D01*
X165817Y113750D01*
X165900Y113167D01*
X165817Y112583D01*
X165567Y112000D01*
X165067Y111667D01*
X164400Y111500D01*
X163817Y111583D01*
X163233Y111833D01*
X162900Y112167D01*
G01X170000Y111500D02*
X169500Y111583D01*
X169000Y111917D01*
X168667Y112500D01*
X168500Y113167D01*
X168667Y113833D01*
X169000Y114417D01*
X169500Y114750D01*
X170000Y114833D01*
X170500Y114750D01*
X171000Y114417D01*
X171333Y113833D01*
X171417Y113167D01*
X171333Y112500D01*
X171000Y111917D01*
X170500Y111583D01*
X170000Y111500D01*
G01X174350Y112083D02*
X174767Y111750D01*
X175350Y111500D01*
X175850D01*
X176350Y111667D01*
X176683Y111917D01*
X176850Y112250D01*
X176767Y112750D01*
X176433Y113000D01*
X174933Y113500D01*
X174600Y114083D01*
X174767Y114500D01*
X175100Y114750D01*
X175600Y114833D01*
X176100Y114750D01*
X176600Y114500D01*
G01X181200Y114833D02*
Y111500D01*
G01Y116167D02*
X181033Y116250D01*
Y116417D01*
X181200Y116500D01*
X181367Y116417D01*
Y116250D01*
X181200Y116167D01*
G01X186800Y116500D02*
Y111500D01*
G01X185633Y114833D02*
X187967D01*
G01X192400D02*
Y111500D01*
G01Y116167D02*
X192233Y116250D01*
Y116417D01*
X192400Y116500D01*
X192567Y116417D01*
Y116250D01*
X192400Y116167D01*
G01X198000Y111500D02*
X197500Y111583D01*
X197000Y111917D01*
X196667Y112500D01*
X196500Y113167D01*
X196667Y113833D01*
X197000Y114417D01*
X197500Y114750D01*
X198000Y114833D01*
X198500Y114750D01*
X199000Y114417D01*
X199333Y113833D01*
X199417Y113167D01*
X199333Y112500D01*
X199000Y111917D01*
X198500Y111583D01*
X198000Y111500D01*
G01X202183D02*
Y114833D01*
G01Y114000D02*
X202517Y114417D01*
X203017Y114750D01*
X203683Y114833D01*
X204267Y114750D01*
X204767Y114417D01*
X205017Y113833D01*
Y111500D01*
G01X114000Y143500D02*
Y138500D01*
G01X112833Y141833D02*
X115167D01*
G01X118183Y138500D02*
Y143500D01*
G01Y141083D02*
X118600Y141500D01*
X119017Y141750D01*
X119683Y141833D01*
X120183Y141750D01*
X120767Y141417D01*
X121017Y140917D01*
Y138500D01*
G01X125200Y141833D02*
Y138500D01*
G01Y143167D02*
X125033Y143250D01*
Y143417D01*
X125200Y143500D01*
X125367Y143417D01*
Y143250D01*
X125200Y143167D01*
G01X132133Y141417D02*
X131550Y141750D01*
X131050Y141833D01*
X130383Y141667D01*
X129883Y141333D01*
X129550Y140750D01*
X129467Y140167D01*
X129550Y139583D01*
X129883Y139083D01*
X130383Y138667D01*
X131050Y138500D01*
X131633Y138667D01*
X132133Y139000D01*
G01X134983Y138500D02*
Y143500D01*
G01X137650Y141833D02*
X134983Y139917D01*
G01X136067Y140667D02*
X137817Y138500D01*
G01X140583D02*
Y141833D01*
G01Y141000D02*
X140917Y141417D01*
X141417Y141750D01*
X142083Y141833D01*
X142667Y141750D01*
X143167Y141417D01*
X143417Y140833D01*
Y138500D01*
G01X146350Y140750D02*
X149017D01*
X148767Y141333D01*
X148350Y141667D01*
X147767Y141833D01*
X147183Y141750D01*
X146683Y141500D01*
X146350Y140917D01*
X146183Y140417D01*
Y139917D01*
X146350Y139417D01*
X146767Y138917D01*
X147267Y138583D01*
X147850Y138500D01*
X148433Y138667D01*
X149017Y139167D01*
G01X151950Y139083D02*
X152367Y138750D01*
X152950Y138500D01*
X153450D01*
X153950Y138667D01*
X154283Y138917D01*
X154450Y139250D01*
X154367Y139750D01*
X154033Y140000D01*
X152533Y140500D01*
X152200Y141083D01*
X152367Y141500D01*
X152700Y141750D01*
X153200Y141833D01*
X153700Y141750D01*
X154200Y141500D01*
G01X157550Y139083D02*
X157967Y138750D01*
X158550Y138500D01*
X159050D01*
X159550Y138667D01*
X159883Y138917D01*
X160050Y139250D01*
X159967Y139750D01*
X159633Y140000D01*
X158133Y140500D01*
X157800Y141083D01*
X157967Y141500D01*
X158300Y141750D01*
X158800Y141833D01*
X159300Y141750D01*
X159800Y141500D01*
G01X171500Y138500D02*
Y141833D01*
G01Y141250D02*
X171167Y141583D01*
X170667Y141750D01*
X170083Y141833D01*
X169500Y141667D01*
X169000Y141333D01*
X168667Y140833D01*
X168500Y140167D01*
X168667Y139500D01*
X169000Y139000D01*
X169500Y138667D01*
X170083Y138500D01*
X170667Y138583D01*
X171167Y138833D01*
X171500Y139167D01*
G01X175100Y138500D02*
Y142750D01*
X175267Y143167D01*
X175600Y143417D01*
X176100Y143500D01*
X176600Y143333D01*
X176850Y142917D01*
G01X175850Y141500D02*
X174183D01*
G01X181200Y143500D02*
Y138500D01*
G01X180033Y141833D02*
X182367D01*
G01X185550Y140750D02*
X188217D01*
X187967Y141333D01*
X187550Y141667D01*
X186967Y141833D01*
X186383Y141750D01*
X185883Y141500D01*
X185550Y140917D01*
X185383Y140417D01*
Y139917D01*
X185550Y139417D01*
X185967Y138917D01*
X186467Y138583D01*
X187050Y138500D01*
X187633Y138667D01*
X188217Y139167D01*
G01X191233Y138500D02*
Y141833D01*
G01Y141167D02*
X191650Y141500D01*
X192067Y141750D01*
X192650Y141833D01*
X193067Y141750D01*
X193567Y141500D01*
G01X202100Y136833D02*
Y141833D01*
G01Y141083D02*
X202517Y141500D01*
X202933Y141750D01*
X203600Y141833D01*
X204183Y141750D01*
X204767Y141333D01*
X205017Y140750D01*
X205100Y140167D01*
X205017Y139583D01*
X204767Y139000D01*
X204267Y138667D01*
X203600Y138500D01*
X203017Y138583D01*
X202433Y138833D01*
X202100Y139167D01*
G01X209200Y138500D02*
Y143500D01*
G01X216300Y138500D02*
Y141833D01*
G01Y141250D02*
X215967Y141583D01*
X215467Y141750D01*
X214883Y141833D01*
X214300Y141667D01*
X213800Y141333D01*
X213467Y140833D01*
X213300Y140167D01*
X213467Y139500D01*
X213800Y139000D01*
X214300Y138667D01*
X214883Y138500D01*
X215467Y138583D01*
X215967Y138833D01*
X216300Y139167D01*
G01X220400Y143500D02*
Y138500D01*
G01X219233Y141833D02*
X221567D01*
G01X226000D02*
Y138500D01*
G01Y143167D02*
X225833Y143250D01*
Y143417D01*
X226000Y143500D01*
X226167Y143417D01*
Y143250D01*
X226000Y143167D01*
G01X230183Y138500D02*
Y141833D01*
G01Y141000D02*
X230517Y141417D01*
X231017Y141750D01*
X231683Y141833D01*
X232267Y141750D01*
X232767Y141417D01*
X233017Y140833D01*
Y138500D01*
G01X236033Y137250D02*
X236617Y136917D01*
X237283Y136833D01*
X237867Y136917D01*
X238367Y137333D01*
X238700Y137917D01*
Y141833D01*
G01Y141167D02*
X238367Y141500D01*
X237867Y141750D01*
X237283Y141833D01*
X236617Y141667D01*
X236200Y141333D01*
X235867Y140750D01*
X235700Y140167D01*
X235783Y139667D01*
X236117Y139083D01*
X236617Y138667D01*
X237283Y138500D01*
X237783Y138583D01*
X238367Y138917D01*
X238700Y139250D01*
G01X115667Y148500D02*
X112333D01*
Y153500D01*
X115667D01*
G01X114333Y151083D02*
X112333D01*
G01X118350Y151833D02*
X120850Y148500D01*
G01Y151833D02*
X118350Y148500D01*
G01X125200Y153500D02*
Y148500D01*
G01X124033Y151833D02*
X126367D01*
G01X129550Y150750D02*
X132217D01*
X131967Y151333D01*
X131550Y151667D01*
X130967Y151833D01*
X130383Y151750D01*
X129883Y151500D01*
X129550Y150917D01*
X129383Y150417D01*
Y149917D01*
X129550Y149417D01*
X129967Y148917D01*
X130467Y148583D01*
X131050Y148500D01*
X131633Y148667D01*
X132217Y149167D01*
G01X135233Y148500D02*
Y151833D01*
G01Y151167D02*
X135650Y151500D01*
X136067Y151750D01*
X136650Y151833D01*
X137067Y151750D01*
X137567Y151500D01*
G01X140583Y148500D02*
Y151833D01*
G01Y151000D02*
X140917Y151417D01*
X141417Y151750D01*
X142083Y151833D01*
X142667Y151750D01*
X143167Y151417D01*
X143417Y150833D01*
Y148500D01*
G01X149100D02*
Y151833D01*
G01Y151250D02*
X148767Y151583D01*
X148267Y151750D01*
X147683Y151833D01*
X147100Y151667D01*
X146600Y151333D01*
X146267Y150833D01*
X146100Y150167D01*
X146267Y149500D01*
X146600Y149000D01*
X147100Y148667D01*
X147683Y148500D01*
X148267Y148583D01*
X148767Y148833D01*
X149100Y149167D01*
G01X153200Y148500D02*
Y153500D01*
G01X165733Y151417D02*
X165150Y151750D01*
X164650Y151833D01*
X163983Y151667D01*
X163483Y151333D01*
X163150Y150750D01*
X163067Y150167D01*
X163150Y149583D01*
X163483Y149083D01*
X163983Y148667D01*
X164650Y148500D01*
X165233Y148667D01*
X165733Y149000D01*
G01X170000Y148500D02*
X169500Y148583D01*
X169000Y148917D01*
X168667Y149500D01*
X168500Y150167D01*
X168667Y150833D01*
X169000Y151417D01*
X169500Y151750D01*
X170000Y151833D01*
X170500Y151750D01*
X171000Y151417D01*
X171333Y150833D01*
X171417Y150167D01*
X171333Y149500D01*
X171000Y148917D01*
X170500Y148583D01*
X170000Y148500D01*
G01X174183D02*
Y151833D01*
G01Y151000D02*
X174517Y151417D01*
X175017Y151750D01*
X175683Y151833D01*
X176267Y151750D01*
X176767Y151417D01*
X177017Y150833D01*
Y148500D01*
G01X182700Y153500D02*
Y148500D01*
G01Y149250D02*
X182367Y148833D01*
X181867Y148583D01*
X181283Y148500D01*
X180617Y148667D01*
X180117Y149083D01*
X179783Y149583D01*
X179700Y150167D01*
X179783Y150750D01*
X180117Y151250D01*
X180617Y151667D01*
X181283Y151833D01*
X181867Y151750D01*
X182283Y151583D01*
X182700Y151250D01*
G01X185383Y151833D02*
Y149500D01*
X185717Y148917D01*
X186217Y148583D01*
X186800Y148500D01*
X187383Y148583D01*
X187883Y148917D01*
X188217Y149500D01*
G01Y148500D02*
Y151833D01*
G01X193733Y151417D02*
X193150Y151750D01*
X192650Y151833D01*
X191983Y151667D01*
X191483Y151333D01*
X191150Y150750D01*
X191067Y150167D01*
X191150Y149583D01*
X191483Y149083D01*
X191983Y148667D01*
X192650Y148500D01*
X193233Y148667D01*
X193733Y149000D01*
G01X198000Y153500D02*
Y148500D01*
G01X196833Y151833D02*
X199167D01*
G01X203600Y148500D02*
X203100Y148583D01*
X202600Y148917D01*
X202267Y149500D01*
X202100Y150167D01*
X202267Y150833D01*
X202600Y151417D01*
X203100Y151750D01*
X203600Y151833D01*
X204100Y151750D01*
X204600Y151417D01*
X204933Y150833D01*
X205017Y150167D01*
X204933Y149500D01*
X204600Y148917D01*
X204100Y148583D01*
X203600Y148500D01*
G01X208033D02*
Y151833D01*
G01Y151167D02*
X208450Y151500D01*
X208867Y151750D01*
X209450Y151833D01*
X209867Y151750D01*
X210367Y151500D01*
G01X112333Y356500D02*
Y351500D01*
X115667D01*
G01X121100D02*
Y354833D01*
G01Y354250D02*
X120767Y354583D01*
X120267Y354750D01*
X119683Y354833D01*
X119100Y354667D01*
X118600Y354333D01*
X118267Y353833D01*
X118100Y353167D01*
X118267Y352500D01*
X118600Y352000D01*
X119100Y351667D01*
X119683Y351500D01*
X120267Y351583D01*
X120767Y351833D01*
X121100Y352167D01*
G01X123950Y352083D02*
X124367Y351750D01*
X124950Y351500D01*
X125450D01*
X125950Y351667D01*
X126283Y351917D01*
X126450Y352250D01*
X126367Y352750D01*
X126033Y353000D01*
X124533Y353500D01*
X124200Y354083D01*
X124367Y354500D01*
X124700Y354750D01*
X125200Y354833D01*
X125700Y354750D01*
X126200Y354500D01*
G01X129550Y353750D02*
X132217D01*
X131967Y354333D01*
X131550Y354667D01*
X130967Y354833D01*
X130383Y354750D01*
X129883Y354500D01*
X129550Y353917D01*
X129383Y353417D01*
Y352917D01*
X129550Y352417D01*
X129967Y351917D01*
X130467Y351583D01*
X131050Y351500D01*
X131633Y351667D01*
X132217Y352167D01*
G01X135233Y351500D02*
Y354833D01*
G01Y354167D02*
X135650Y354500D01*
X136067Y354750D01*
X136650Y354833D01*
X137067Y354750D01*
X137567Y354500D01*
G01X146100Y354833D02*
X147600Y351500D01*
X149100Y354833D01*
G01X153200D02*
Y351500D01*
G01Y356167D02*
X153033Y356250D01*
Y356417D01*
X153200Y356500D01*
X153367Y356417D01*
Y356250D01*
X153200Y356167D01*
G01X160300Y351500D02*
Y354833D01*
G01Y354250D02*
X159967Y354583D01*
X159467Y354750D01*
X158883Y354833D01*
X158300Y354667D01*
X157800Y354333D01*
X157467Y353833D01*
X157300Y353167D01*
X157467Y352500D01*
X157800Y352000D01*
X158300Y351667D01*
X158883Y351500D01*
X159467Y351583D01*
X159967Y351833D01*
X160300Y352167D01*
G01X168167Y351333D02*
X171833Y355000D01*
G01X170000Y355667D02*
Y350667D01*
G01X171833Y351333D02*
X168167Y355000D01*
G01X167500Y353167D02*
X172500D01*
G01X175183Y349833D02*
X174350Y350667D01*
X173933Y351500D01*
Y354833D01*
X174350Y355667D01*
X175183Y356500D01*
G01X179367Y352250D02*
X179867Y351833D01*
X180450Y351583D01*
X181200Y351500D01*
X181950Y351667D01*
X182533Y352000D01*
X182950Y352583D01*
X183033Y353250D01*
X182867Y353917D01*
X182450Y354333D01*
X181867Y354667D01*
X181283Y354750D01*
X180700Y354667D01*
X179950Y354333D01*
X180200Y356500D01*
X182450D01*
G01X186800Y351333D02*
X186633Y351417D01*
Y351583D01*
X186800Y351667D01*
X186967Y351583D01*
Y351417D01*
X186800Y351333D01*
G01X192400Y351500D02*
Y356500D01*
X191400Y355500D01*
G01Y351500D02*
X193400D01*
G01X198417Y349833D02*
X199250Y350667D01*
X199667Y351500D01*
Y354833D01*
X199250Y355667D01*
X198417Y356500D01*
G01X112333Y406500D02*
Y411500D01*
X114333D01*
X115000Y411250D01*
X115500Y410667D01*
X115667Y410000D01*
X115500Y409333D01*
X115083Y408833D01*
X114333Y408583D01*
X112333D01*
G01X119600Y411500D02*
Y406500D01*
G01X117683Y411500D02*
X121517D01*
G01X123450Y406500D02*
Y411500D01*
G01X126950D02*
Y406500D01*
G01Y409000D02*
X123450D01*
G01X135233Y406500D02*
Y409833D01*
G01Y409167D02*
X135650Y409500D01*
X136067Y409750D01*
X136650Y409833D01*
X137067Y409750D01*
X137567Y409500D01*
G01X140750Y408750D02*
X143417D01*
X143167Y409333D01*
X142750Y409667D01*
X142167Y409833D01*
X141583Y409750D01*
X141083Y409500D01*
X140750Y408917D01*
X140583Y408417D01*
Y407917D01*
X140750Y407417D01*
X141167Y406917D01*
X141667Y406583D01*
X142250Y406500D01*
X142833Y406667D01*
X143417Y407167D01*
G01X146433Y405250D02*
X147017Y404917D01*
X147683Y404833D01*
X148267Y404917D01*
X148767Y405333D01*
X149100Y405917D01*
Y409833D01*
G01Y409167D02*
X148767Y409500D01*
X148267Y409750D01*
X147683Y409833D01*
X147017Y409667D01*
X146600Y409333D01*
X146267Y408750D01*
X146100Y408167D01*
X146183Y407667D01*
X146517Y407083D01*
X147017Y406667D01*
X147683Y406500D01*
X148183Y406583D01*
X148767Y406917D01*
X149100Y407250D01*
G01X153200Y409833D02*
Y406500D01*
G01Y411167D02*
X153033Y411250D01*
Y411417D01*
X153200Y411500D01*
X153367Y411417D01*
Y411250D01*
X153200Y411167D01*
G01X157550Y407083D02*
X157967Y406750D01*
X158550Y406500D01*
X159050D01*
X159550Y406667D01*
X159883Y406917D01*
X160050Y407250D01*
X159967Y407750D01*
X159633Y408000D01*
X158133Y408500D01*
X157800Y409083D01*
X157967Y409500D01*
X158300Y409750D01*
X158800Y409833D01*
X159300Y409750D01*
X159800Y409500D01*
G01X164400Y411500D02*
Y406500D01*
G01X163233Y409833D02*
X165567D01*
G01X168833Y406500D02*
Y409833D01*
G01Y409167D02*
X169250Y409500D01*
X169667Y409750D01*
X170250Y409833D01*
X170667Y409750D01*
X171167Y409500D01*
G01X177100Y406500D02*
Y409833D01*
G01Y409250D02*
X176767Y409583D01*
X176267Y409750D01*
X175683Y409833D01*
X175100Y409667D01*
X174600Y409333D01*
X174267Y408833D01*
X174100Y408167D01*
X174267Y407500D01*
X174600Y407000D01*
X175100Y406667D01*
X175683Y406500D01*
X176267Y406583D01*
X176767Y406833D01*
X177100Y407167D01*
G01X181200Y411500D02*
Y406500D01*
G01X180033Y409833D02*
X182367D01*
G01X186800D02*
Y406500D01*
G01Y411167D02*
X186633Y411250D01*
Y411417D01*
X186800Y411500D01*
X186967Y411417D01*
Y411250D01*
X186800Y411167D01*
G01X192400Y406500D02*
X191900Y406583D01*
X191400Y406917D01*
X191067Y407500D01*
X190900Y408167D01*
X191067Y408833D01*
X191400Y409417D01*
X191900Y409750D01*
X192400Y409833D01*
X192900Y409750D01*
X193400Y409417D01*
X193733Y408833D01*
X193817Y408167D01*
X193733Y407500D01*
X193400Y406917D01*
X192900Y406583D01*
X192400Y406500D01*
G01X196583D02*
Y409833D01*
G01Y409000D02*
X196917Y409417D01*
X197417Y409750D01*
X198083Y409833D01*
X198667Y409750D01*
X199167Y409417D01*
X199417Y408833D01*
Y406500D01*
G01X105000Y364500D02*
X694500D01*
G01X112167Y433000D02*
Y438000D01*
X113833D01*
X114500Y437750D01*
X115000Y437417D01*
X115417Y436917D01*
X115750Y436333D01*
X115833Y435500D01*
X115750Y434667D01*
X115417Y434083D01*
X115000Y433583D01*
X114500Y433250D01*
X113833Y433000D01*
X112167D01*
G01X118350Y435250D02*
X121017D01*
X120767Y435833D01*
X120350Y436167D01*
X119767Y436333D01*
X119183Y436250D01*
X118683Y436000D01*
X118350Y435417D01*
X118183Y434917D01*
Y434417D01*
X118350Y433917D01*
X118767Y433417D01*
X119267Y433083D01*
X119850Y433000D01*
X120433Y433167D01*
X121017Y433667D01*
G01X123700Y431333D02*
Y436333D01*
G01Y435583D02*
X124117Y436000D01*
X124533Y436250D01*
X125200Y436333D01*
X125783Y436250D01*
X126367Y435833D01*
X126617Y435250D01*
X126700Y434667D01*
X126617Y434083D01*
X126367Y433500D01*
X125867Y433167D01*
X125200Y433000D01*
X124617Y433083D01*
X124033Y433333D01*
X123700Y433667D01*
G01X130800Y438000D02*
Y433000D01*
G01X129633Y436333D02*
X131967D01*
G01X134983Y433000D02*
Y438000D01*
G01Y435583D02*
X135400Y436000D01*
X135817Y436250D01*
X136483Y436333D01*
X136983Y436250D01*
X137567Y435917D01*
X137817Y435417D01*
Y433000D01*
G01X148933Y435917D02*
X148350Y436250D01*
X147850Y436333D01*
X147183Y436167D01*
X146683Y435833D01*
X146350Y435250D01*
X146267Y434667D01*
X146350Y434083D01*
X146683Y433583D01*
X147183Y433167D01*
X147850Y433000D01*
X148433Y433167D01*
X148933Y433500D01*
G01X153200Y433000D02*
X152700Y433083D01*
X152200Y433417D01*
X151867Y434000D01*
X151700Y434667D01*
X151867Y435333D01*
X152200Y435917D01*
X152700Y436250D01*
X153200Y436333D01*
X153700Y436250D01*
X154200Y435917D01*
X154533Y435333D01*
X154617Y434667D01*
X154533Y434000D01*
X154200Y433417D01*
X153700Y433083D01*
X153200Y433000D01*
G01X157383D02*
Y436333D01*
G01Y435500D02*
X157717Y435917D01*
X158217Y436250D01*
X158883Y436333D01*
X159467Y436250D01*
X159967Y435917D01*
X160217Y435333D01*
Y433000D01*
G01X164400Y438000D02*
Y433000D01*
G01X163233Y436333D02*
X165567D01*
G01X168833Y433000D02*
Y436333D01*
G01Y435667D02*
X169250Y436000D01*
X169667Y436250D01*
X170250Y436333D01*
X170667Y436250D01*
X171167Y436000D01*
G01X175600Y433000D02*
X175100Y433083D01*
X174600Y433417D01*
X174267Y434000D01*
X174100Y434667D01*
X174267Y435333D01*
X174600Y435917D01*
X175100Y436250D01*
X175600Y436333D01*
X176100Y436250D01*
X176600Y435917D01*
X176933Y435333D01*
X177017Y434667D01*
X176933Y434000D01*
X176600Y433417D01*
X176100Y433083D01*
X175600Y433000D01*
G01X181200D02*
Y438000D01*
G01X190983Y433000D02*
Y438000D01*
G01Y435583D02*
X191400Y436000D01*
X191817Y436250D01*
X192483Y436333D01*
X192983Y436250D01*
X193567Y435917D01*
X193817Y435417D01*
Y433000D01*
G01X198000D02*
X197500Y433083D01*
X197000Y433417D01*
X196667Y434000D01*
X196500Y434667D01*
X196667Y435333D01*
X197000Y435917D01*
X197500Y436250D01*
X198000Y436333D01*
X198500Y436250D01*
X199000Y435917D01*
X199333Y435333D01*
X199417Y434667D01*
X199333Y434000D01*
X199000Y433417D01*
X198500Y433083D01*
X198000Y433000D01*
G01X203600D02*
Y438000D01*
G01X207950Y435250D02*
X210617D01*
X210367Y435833D01*
X209950Y436167D01*
X209367Y436333D01*
X208783Y436250D01*
X208283Y436000D01*
X207950Y435417D01*
X207783Y434917D01*
Y434417D01*
X207950Y433917D01*
X208367Y433417D01*
X208867Y433083D01*
X209450Y433000D01*
X210033Y433167D01*
X210617Y433667D01*
G01X112333Y455000D02*
Y460000D01*
X114417D01*
X115083Y459750D01*
X115500Y459417D01*
X115667Y458750D01*
X115500Y458083D01*
X115000Y457667D01*
X114417Y457417D01*
X112333D01*
G01X114417D02*
X115667Y455000D01*
G01X119600D02*
X119100Y455083D01*
X118600Y455417D01*
X118267Y456000D01*
X118100Y456667D01*
X118267Y457333D01*
X118600Y457917D01*
X119100Y458250D01*
X119600Y458333D01*
X120100Y458250D01*
X120600Y457917D01*
X120933Y457333D01*
X121017Y456667D01*
X120933Y456000D01*
X120600Y455417D01*
X120100Y455083D01*
X119600Y455000D01*
G01X123783Y458333D02*
Y456000D01*
X124117Y455417D01*
X124617Y455083D01*
X125200Y455000D01*
X125783Y455083D01*
X126283Y455417D01*
X126617Y456000D01*
G01Y455000D02*
Y458333D01*
G01X129633Y453750D02*
X130217Y453417D01*
X130883Y453333D01*
X131467Y453417D01*
X131967Y453833D01*
X132300Y454417D01*
Y458333D01*
G01Y457667D02*
X131967Y458000D01*
X131467Y458250D01*
X130883Y458333D01*
X130217Y458167D01*
X129800Y457833D01*
X129467Y457250D01*
X129300Y456667D01*
X129383Y456167D01*
X129717Y455583D01*
X130217Y455167D01*
X130883Y455000D01*
X131383Y455083D01*
X131967Y455417D01*
X132300Y455750D01*
G01X134983Y455000D02*
Y460000D01*
G01Y457583D02*
X135400Y458000D01*
X135817Y458250D01*
X136483Y458333D01*
X136983Y458250D01*
X137567Y457917D01*
X137817Y457417D01*
Y455000D01*
G01X140583D02*
Y458333D01*
G01Y457500D02*
X140917Y457917D01*
X141417Y458250D01*
X142083Y458333D01*
X142667Y458250D01*
X143167Y457917D01*
X143417Y457333D01*
Y455000D01*
G01X146350Y457250D02*
X149017D01*
X148767Y457833D01*
X148350Y458167D01*
X147767Y458333D01*
X147183Y458250D01*
X146683Y458000D01*
X146350Y457417D01*
X146183Y456917D01*
Y456417D01*
X146350Y455917D01*
X146767Y455417D01*
X147267Y455083D01*
X147850Y455000D01*
X148433Y455167D01*
X149017Y455667D01*
G01X151950Y455583D02*
X152367Y455250D01*
X152950Y455000D01*
X153450D01*
X153950Y455167D01*
X154283Y455417D01*
X154450Y455750D01*
X154367Y456250D01*
X154033Y456500D01*
X152533Y457000D01*
X152200Y457583D01*
X152367Y458000D01*
X152700Y458250D01*
X153200Y458333D01*
X153700Y458250D01*
X154200Y458000D01*
G01X157550Y455583D02*
X157967Y455250D01*
X158550Y455000D01*
X159050D01*
X159550Y455167D01*
X159883Y455417D01*
X160050Y455750D01*
X159967Y456250D01*
X159633Y456500D01*
X158133Y457000D01*
X157800Y457583D01*
X157967Y458000D01*
X158300Y458250D01*
X158800Y458333D01*
X159300Y458250D01*
X159800Y458000D01*
G01X103500Y449000D02*
X694500D01*
G01X104000Y464000D02*
X694500D01*
G01X103500Y424000D02*
X694500D01*
G01X112250Y513500D02*
Y518500D01*
G01X115750D02*
Y513500D01*
G01Y516000D02*
X112250D01*
G01X119600Y513500D02*
X119100Y513583D01*
X118600Y513917D01*
X118267Y514500D01*
X118100Y515167D01*
X118267Y515833D01*
X118600Y516417D01*
X119100Y516750D01*
X119600Y516833D01*
X120100Y516750D01*
X120600Y516417D01*
X120933Y515833D01*
X121017Y515167D01*
X120933Y514500D01*
X120600Y513917D01*
X120100Y513583D01*
X119600Y513500D01*
G01X125200D02*
Y518500D01*
G01X129550Y515750D02*
X132217D01*
X131967Y516333D01*
X131550Y516667D01*
X130967Y516833D01*
X130383Y516750D01*
X129883Y516500D01*
X129550Y515917D01*
X129383Y515417D01*
Y514917D01*
X129550Y514417D01*
X129967Y513917D01*
X130467Y513583D01*
X131050Y513500D01*
X131633Y513667D01*
X132217Y514167D01*
G01X140750Y514083D02*
X141167Y513750D01*
X141750Y513500D01*
X142250D01*
X142750Y513667D01*
X143083Y513917D01*
X143250Y514250D01*
X143167Y514750D01*
X142833Y515000D01*
X141333Y515500D01*
X141000Y516083D01*
X141167Y516500D01*
X141500Y516750D01*
X142000Y516833D01*
X142500Y516750D01*
X143000Y516500D01*
G01X147600Y516833D02*
Y513500D01*
G01Y518167D02*
X147433Y518250D01*
Y518417D01*
X147600Y518500D01*
X147767Y518417D01*
Y518250D01*
X147600Y518167D01*
G01X151950Y516833D02*
X154450D01*
X151950Y513500D01*
X154450D01*
G01X157550Y515750D02*
X160217D01*
X159967Y516333D01*
X159550Y516667D01*
X158967Y516833D01*
X158383Y516750D01*
X157883Y516500D01*
X157550Y515917D01*
X157383Y515417D01*
Y514917D01*
X157550Y514417D01*
X157967Y513917D01*
X158467Y513583D01*
X159050Y513500D01*
X159633Y513667D01*
X160217Y514167D01*
G01X111917Y610000D02*
X114000Y605000D01*
X116083Y610000D01*
G01X119600Y608333D02*
Y605000D01*
G01Y609667D02*
X119433Y609750D01*
Y609917D01*
X119600Y610000D01*
X119767Y609917D01*
Y609750D01*
X119600Y609667D01*
G01X126700Y605000D02*
Y608333D01*
G01Y607750D02*
X126367Y608083D01*
X125867Y608250D01*
X125283Y608333D01*
X124700Y608167D01*
X124200Y607833D01*
X123867Y607333D01*
X123700Y606667D01*
X123867Y606000D01*
X124200Y605500D01*
X124700Y605167D01*
X125283Y605000D01*
X125867Y605083D01*
X126367Y605333D01*
X126700Y605667D01*
G01X134983Y605000D02*
Y610000D01*
G01Y607583D02*
X135400Y608000D01*
X135817Y608250D01*
X136483Y608333D01*
X136983Y608250D01*
X137567Y607917D01*
X137817Y607417D01*
Y605000D01*
G01X142000D02*
X141500Y605083D01*
X141000Y605417D01*
X140667Y606000D01*
X140500Y606667D01*
X140667Y607333D01*
X141000Y607917D01*
X141500Y608250D01*
X142000Y608333D01*
X142500Y608250D01*
X143000Y607917D01*
X143333Y607333D01*
X143417Y606667D01*
X143333Y606000D01*
X143000Y605417D01*
X142500Y605083D01*
X142000Y605000D01*
G01X147600D02*
Y610000D01*
G01X151950Y607250D02*
X154617D01*
X154367Y607833D01*
X153950Y608167D01*
X153367Y608333D01*
X152783Y608250D01*
X152283Y608000D01*
X151950Y607417D01*
X151783Y606917D01*
Y606417D01*
X151950Y605917D01*
X152367Y605417D01*
X152867Y605083D01*
X153450Y605000D01*
X154033Y605167D01*
X154617Y605667D01*
G01X164400Y610000D02*
Y605000D01*
G01X163233Y608333D02*
X165567D01*
G01X168583Y605000D02*
Y610000D01*
G01Y607583D02*
X169000Y608000D01*
X169417Y608250D01*
X170083Y608333D01*
X170583Y608250D01*
X171167Y607917D01*
X171417Y607417D01*
Y605000D01*
G01X174350Y607250D02*
X177017D01*
X176767Y607833D01*
X176350Y608167D01*
X175767Y608333D01*
X175183Y608250D01*
X174683Y608000D01*
X174350Y607417D01*
X174183Y606917D01*
Y606417D01*
X174350Y605917D01*
X174767Y605417D01*
X175267Y605083D01*
X175850Y605000D01*
X176433Y605167D01*
X177017Y605667D01*
G01X180033Y605000D02*
Y608333D01*
G01Y607667D02*
X180450Y608000D01*
X180867Y608250D01*
X181450Y608333D01*
X181867Y608250D01*
X182367Y608000D01*
G01X184300Y605000D02*
Y608333D01*
G01Y607417D02*
X184550Y607833D01*
X184967Y608167D01*
X185550Y608333D01*
X186133Y608167D01*
X186550Y607833D01*
X186800Y607417D01*
Y605000D01*
G01Y607417D02*
X187050Y607833D01*
X187467Y608167D01*
X188050Y608333D01*
X188633Y608167D01*
X189050Y607833D01*
X189300Y607333D01*
Y605000D01*
G01X193900D02*
Y608333D01*
G01Y607750D02*
X193567Y608083D01*
X193067Y608250D01*
X192483Y608333D01*
X191900Y608167D01*
X191400Y607833D01*
X191067Y607333D01*
X190900Y606667D01*
X191067Y606000D01*
X191400Y605500D01*
X191900Y605167D01*
X192483Y605000D01*
X193067Y605083D01*
X193567Y605333D01*
X193900Y605667D01*
G01X198000Y605000D02*
Y610000D01*
G01X207700Y603333D02*
Y608333D01*
G01Y607583D02*
X208117Y608000D01*
X208533Y608250D01*
X209200Y608333D01*
X209783Y608250D01*
X210367Y607833D01*
X210617Y607250D01*
X210700Y606667D01*
X210617Y606083D01*
X210367Y605500D01*
X209867Y605167D01*
X209200Y605000D01*
X208617Y605083D01*
X208033Y605333D01*
X207700Y605667D01*
G01X216300Y605000D02*
Y608333D01*
G01Y607750D02*
X215967Y608083D01*
X215467Y608250D01*
X214883Y608333D01*
X214300Y608167D01*
X213800Y607833D01*
X213467Y607333D01*
X213300Y606667D01*
X213467Y606000D01*
X213800Y605500D01*
X214300Y605167D01*
X214883Y605000D01*
X215467Y605083D01*
X215967Y605333D01*
X216300Y605667D01*
G01X221900Y610000D02*
Y605000D01*
G01Y605750D02*
X221567Y605333D01*
X221067Y605083D01*
X220483Y605000D01*
X219817Y605167D01*
X219317Y605583D01*
X218983Y606083D01*
X218900Y606667D01*
X218983Y607250D01*
X219317Y607750D01*
X219817Y608167D01*
X220483Y608333D01*
X221067Y608250D01*
X221483Y608083D01*
X221900Y607750D01*
G01X112250Y588500D02*
Y593500D01*
G01X115750D02*
Y588500D01*
G01Y591000D02*
X112250D01*
G01X119600Y588500D02*
X119100Y588583D01*
X118600Y588917D01*
X118267Y589500D01*
X118100Y590167D01*
X118267Y590833D01*
X118600Y591417D01*
X119100Y591750D01*
X119600Y591833D01*
X120100Y591750D01*
X120600Y591417D01*
X120933Y590833D01*
X121017Y590167D01*
X120933Y589500D01*
X120600Y588917D01*
X120100Y588583D01*
X119600Y588500D01*
G01X125200D02*
Y593500D01*
G01X129550Y590750D02*
X132217D01*
X131967Y591333D01*
X131550Y591667D01*
X130967Y591833D01*
X130383Y591750D01*
X129883Y591500D01*
X129550Y590917D01*
X129383Y590417D01*
Y589917D01*
X129550Y589417D01*
X129967Y588917D01*
X130467Y588583D01*
X131050Y588500D01*
X131633Y588667D01*
X132217Y589167D01*
G01X140500Y586833D02*
Y591833D01*
G01Y591083D02*
X140917Y591500D01*
X141333Y591750D01*
X142000Y591833D01*
X142583Y591750D01*
X143167Y591333D01*
X143417Y590750D01*
X143500Y590167D01*
X143417Y589583D01*
X143167Y589000D01*
X142667Y588667D01*
X142000Y588500D01*
X141417Y588583D01*
X140833Y588833D01*
X140500Y589167D01*
G01X147600Y588500D02*
X147100Y588583D01*
X146600Y588917D01*
X146267Y589500D01*
X146100Y590167D01*
X146267Y590833D01*
X146600Y591417D01*
X147100Y591750D01*
X147600Y591833D01*
X148100Y591750D01*
X148600Y591417D01*
X148933Y590833D01*
X149017Y590167D01*
X148933Y589500D01*
X148600Y588917D01*
X148100Y588583D01*
X147600Y588500D01*
G01X151950Y589083D02*
X152367Y588750D01*
X152950Y588500D01*
X153450D01*
X153950Y588667D01*
X154283Y588917D01*
X154450Y589250D01*
X154367Y589750D01*
X154033Y590000D01*
X152533Y590500D01*
X152200Y591083D01*
X152367Y591500D01*
X152700Y591750D01*
X153200Y591833D01*
X153700Y591750D01*
X154200Y591500D01*
G01X158800Y591833D02*
Y588500D01*
G01Y593167D02*
X158633Y593250D01*
Y593417D01*
X158800Y593500D01*
X158967Y593417D01*
Y593250D01*
X158800Y593167D01*
G01X164400Y593500D02*
Y588500D01*
G01X163233Y591833D02*
X165567D01*
G01X170000D02*
Y588500D01*
G01Y593167D02*
X169833Y593250D01*
Y593417D01*
X170000Y593500D01*
X170167Y593417D01*
Y593250D01*
X170000Y593167D01*
G01X175600Y588500D02*
X175100Y588583D01*
X174600Y588917D01*
X174267Y589500D01*
X174100Y590167D01*
X174267Y590833D01*
X174600Y591417D01*
X175100Y591750D01*
X175600Y591833D01*
X176100Y591750D01*
X176600Y591417D01*
X176933Y590833D01*
X177017Y590167D01*
X176933Y589500D01*
X176600Y588917D01*
X176100Y588583D01*
X175600Y588500D01*
G01X179783D02*
Y591833D01*
G01Y591000D02*
X180117Y591417D01*
X180617Y591750D01*
X181283Y591833D01*
X181867Y591750D01*
X182367Y591417D01*
X182617Y590833D01*
Y588500D01*
G01X192400Y593500D02*
Y588500D01*
G01X191233Y591833D02*
X193567D01*
G01X198000Y588500D02*
X197500Y588583D01*
X197000Y588917D01*
X196667Y589500D01*
X196500Y590167D01*
X196667Y590833D01*
X197000Y591417D01*
X197500Y591750D01*
X198000Y591833D01*
X198500Y591750D01*
X199000Y591417D01*
X199333Y590833D01*
X199417Y590167D01*
X199333Y589500D01*
X199000Y588917D01*
X198500Y588583D01*
X198000Y588500D01*
G01X203600D02*
Y593500D01*
G01X207950Y590750D02*
X210617D01*
X210367Y591333D01*
X209950Y591667D01*
X209367Y591833D01*
X208783Y591750D01*
X208283Y591500D01*
X207950Y590917D01*
X207783Y590417D01*
Y589917D01*
X207950Y589417D01*
X208367Y588917D01*
X208867Y588583D01*
X209450Y588500D01*
X210033Y588667D01*
X210617Y589167D01*
G01X213633Y588500D02*
Y591833D01*
G01Y591167D02*
X214050Y591500D01*
X214467Y591750D01*
X215050Y591833D01*
X215467Y591750D01*
X215967Y591500D01*
G01X221900Y588500D02*
Y591833D01*
G01Y591250D02*
X221567Y591583D01*
X221067Y591750D01*
X220483Y591833D01*
X219900Y591667D01*
X219400Y591333D01*
X219067Y590833D01*
X218900Y590167D01*
X219067Y589500D01*
X219400Y589000D01*
X219900Y588667D01*
X220483Y588500D01*
X221067Y588583D01*
X221567Y588833D01*
X221900Y589167D01*
G01X224583Y588500D02*
Y591833D01*
G01Y591000D02*
X224917Y591417D01*
X225417Y591750D01*
X226083Y591833D01*
X226667Y591750D01*
X227167Y591417D01*
X227417Y590833D01*
Y588500D01*
G01X232933Y591417D02*
X232350Y591750D01*
X231850Y591833D01*
X231183Y591667D01*
X230683Y591333D01*
X230350Y590750D01*
X230267Y590167D01*
X230350Y589583D01*
X230683Y589083D01*
X231183Y588667D01*
X231850Y588500D01*
X232433Y588667D01*
X232933Y589000D01*
G01X235950Y590750D02*
X238617D01*
X238367Y591333D01*
X237950Y591667D01*
X237367Y591833D01*
X236783Y591750D01*
X236283Y591500D01*
X235950Y590917D01*
X235783Y590417D01*
Y589917D01*
X235950Y589417D01*
X236367Y588917D01*
X236867Y588583D01*
X237450Y588500D01*
X238033Y588667D01*
X238617Y589167D01*
G01X111917Y620000D02*
X114000Y625000D01*
X116083Y620000D01*
G01X115333Y621750D02*
X112667D01*
G01X118183Y620000D02*
Y623333D01*
G01Y622500D02*
X118517Y622917D01*
X119017Y623250D01*
X119683Y623333D01*
X120267Y623250D01*
X120767Y622917D01*
X121017Y622333D01*
Y620000D01*
G01X125200Y625000D02*
Y620000D01*
G01X124033Y623333D02*
X126367D01*
G01X130800D02*
Y620000D01*
G01Y624667D02*
X130633Y624750D01*
Y624917D01*
X130800Y625000D01*
X130967Y624917D01*
Y624750D01*
X130800Y624667D01*
G01X135317Y621667D02*
X137483D01*
G01X146100Y618333D02*
Y623333D01*
G01Y622583D02*
X146517Y623000D01*
X146933Y623250D01*
X147600Y623333D01*
X148183Y623250D01*
X148767Y622833D01*
X149017Y622250D01*
X149100Y621667D01*
X149017Y621083D01*
X148767Y620500D01*
X148267Y620167D01*
X147600Y620000D01*
X147017Y620083D01*
X146433Y620333D01*
X146100Y620667D01*
G01X154700Y620000D02*
Y623333D01*
G01Y622750D02*
X154367Y623083D01*
X153867Y623250D01*
X153283Y623333D01*
X152700Y623167D01*
X152200Y622833D01*
X151867Y622333D01*
X151700Y621667D01*
X151867Y621000D01*
X152200Y620500D01*
X152700Y620167D01*
X153283Y620000D01*
X153867Y620083D01*
X154367Y620333D01*
X154700Y620667D01*
G01X160300Y625000D02*
Y620000D01*
G01Y620750D02*
X159967Y620333D01*
X159467Y620083D01*
X158883Y620000D01*
X158217Y620167D01*
X157717Y620583D01*
X157383Y621083D01*
X157300Y621667D01*
X157383Y622250D01*
X157717Y622750D01*
X158217Y623167D01*
X158883Y623333D01*
X159467Y623250D01*
X159883Y623083D01*
X160300Y622750D01*
G01X103500Y614000D02*
X694500D01*
G01X103500Y584000D02*
X694500D01*
G01X103500Y629000D02*
X694500D01*
G01X111843Y639590D02*
Y644590D01*
X115677Y639590D01*
Y644590D01*
G01X119360Y639590D02*
X118860Y639673D01*
X118360Y640007D01*
X118027Y640590D01*
X117860Y641257D01*
X118027Y641923D01*
X118360Y642507D01*
X118860Y642840D01*
X119360Y642923D01*
X119860Y642840D01*
X120360Y642507D01*
X120693Y641923D01*
X120777Y641257D01*
X120693Y640590D01*
X120360Y640007D01*
X119860Y639673D01*
X119360Y639590D01*
G01X123543D02*
Y642923D01*
G01Y642090D02*
X123877Y642507D01*
X124377Y642840D01*
X125043Y642923D01*
X125627Y642840D01*
X126127Y642507D01*
X126377Y641923D01*
Y639590D01*
G01X129477Y641257D02*
X131643D01*
G01X135660Y639590D02*
Y643840D01*
X135827Y644257D01*
X136160Y644507D01*
X136660Y644590D01*
X137160Y644423D01*
X137410Y644007D01*
G01X136410Y642590D02*
X134743D01*
G01X140343Y642923D02*
Y640590D01*
X140677Y640007D01*
X141177Y639673D01*
X141760Y639590D01*
X142343Y639673D01*
X142843Y640007D01*
X143177Y640590D01*
G01Y639590D02*
Y642923D01*
G01X145943Y639590D02*
Y642923D01*
G01Y642090D02*
X146277Y642507D01*
X146777Y642840D01*
X147443Y642923D01*
X148027Y642840D01*
X148527Y642507D01*
X148777Y641923D01*
Y639590D01*
G01X154293Y642507D02*
X153710Y642840D01*
X153210Y642923D01*
X152543Y642757D01*
X152043Y642423D01*
X151710Y641840D01*
X151627Y641257D01*
X151710Y640673D01*
X152043Y640173D01*
X152543Y639757D01*
X153210Y639590D01*
X153793Y639757D01*
X154293Y640090D01*
G01X158560Y644590D02*
Y639590D01*
G01X157393Y642923D02*
X159727D01*
G01X164160D02*
Y639590D01*
G01Y644257D02*
X163993Y644340D01*
Y644507D01*
X164160Y644590D01*
X164327Y644507D01*
Y644340D01*
X164160Y644257D01*
G01X169760Y639590D02*
X169260Y639673D01*
X168760Y640007D01*
X168427Y640590D01*
X168260Y641257D01*
X168427Y641923D01*
X168760Y642507D01*
X169260Y642840D01*
X169760Y642923D01*
X170260Y642840D01*
X170760Y642507D01*
X171093Y641923D01*
X171177Y641257D01*
X171093Y640590D01*
X170760Y640007D01*
X170260Y639673D01*
X169760Y639590D01*
G01X173943D02*
Y642923D01*
G01Y642090D02*
X174277Y642507D01*
X174777Y642840D01*
X175443Y642923D01*
X176027Y642840D01*
X176527Y642507D01*
X176777Y641923D01*
Y639590D01*
G01X182460D02*
Y642923D01*
G01Y642340D02*
X182127Y642673D01*
X181627Y642840D01*
X181043Y642923D01*
X180460Y642757D01*
X179960Y642423D01*
X179627Y641923D01*
X179460Y641257D01*
X179627Y640590D01*
X179960Y640090D01*
X180460Y639757D01*
X181043Y639590D01*
X181627Y639673D01*
X182127Y639923D01*
X182460Y640257D01*
G01X186560Y639590D02*
Y644590D01*
G01X196260Y637923D02*
Y642923D01*
G01Y642173D02*
X196677Y642590D01*
X197093Y642840D01*
X197760Y642923D01*
X198343Y642840D01*
X198927Y642423D01*
X199177Y641840D01*
X199260Y641257D01*
X199177Y640673D01*
X198927Y640090D01*
X198427Y639757D01*
X197760Y639590D01*
X197177Y639673D01*
X196593Y639923D01*
X196260Y640257D01*
G01X204860Y639590D02*
Y642923D01*
G01Y642340D02*
X204527Y642673D01*
X204027Y642840D01*
X203443Y642923D01*
X202860Y642757D01*
X202360Y642423D01*
X202027Y641923D01*
X201860Y641257D01*
X202027Y640590D01*
X202360Y640090D01*
X202860Y639757D01*
X203443Y639590D01*
X204027Y639673D01*
X204527Y639923D01*
X204860Y640257D01*
G01X210460Y644590D02*
Y639590D01*
G01Y640340D02*
X210127Y639923D01*
X209627Y639673D01*
X209043Y639590D01*
X208377Y639757D01*
X207877Y640173D01*
X207543Y640673D01*
X207460Y641257D01*
X207543Y641840D01*
X207877Y642340D01*
X208377Y642757D01*
X209043Y642923D01*
X209627Y642840D01*
X210043Y642673D01*
X210460Y642340D01*
G01X71000Y729600D02*
X73000D01*
G01X72000D02*
Y724600D01*
G01X71000D02*
X73000D01*
G01X75933D02*
Y729600D01*
X77933D01*
X78600Y729350D01*
X79100Y728767D01*
X79267Y728100D01*
X79100Y727433D01*
X78683Y726933D01*
X77933Y726683D01*
X75933D01*
G01X85033Y729183D02*
X84533Y729433D01*
X83950Y729600D01*
X83283D01*
X82533Y729350D01*
X81950Y728933D01*
X81533Y728433D01*
X81200Y727600D01*
X81117Y726850D01*
X81283Y726100D01*
X81533Y725600D01*
X82033Y725100D01*
X82617Y724767D01*
X83200Y724600D01*
X83783D01*
X84367Y724767D01*
X84867Y725017D01*
X85283Y725350D01*
G01X87717Y726267D02*
X89883D01*
G01X92733Y729600D02*
Y724600D01*
X96067D01*
G01X98917Y726267D02*
X101083D01*
G01X105600Y724600D02*
Y729600D01*
X104600Y728600D01*
G01Y724600D02*
X106600D01*
G01X111200Y729600D02*
X110533Y729433D01*
X110033Y729017D01*
X109700Y728517D01*
X109450Y727850D01*
X109367Y727100D01*
X109450Y726350D01*
X109700Y725683D01*
X110033Y725183D01*
X110533Y724767D01*
X111200Y724600D01*
X111867Y724767D01*
X112367Y725183D01*
X112700Y725683D01*
X112950Y726350D01*
X113033Y727100D01*
X112950Y727850D01*
X112700Y728517D01*
X112367Y729017D01*
X111867Y729433D01*
X111200Y729600D01*
G01X115383Y725183D02*
X115967Y724767D01*
X116633Y724600D01*
X117300Y724767D01*
X117883Y725267D01*
X118300Y726017D01*
X118467Y726767D01*
Y727683D01*
X118300Y728433D01*
X117883Y729100D01*
X117383Y729433D01*
X116800Y729600D01*
X116133Y729433D01*
X115633Y729100D01*
X115300Y728600D01*
X115133Y727933D01*
X115300Y727350D01*
X115717Y726767D01*
X116217Y726433D01*
X116800Y726350D01*
X117467Y726517D01*
X117967Y726933D01*
X118467Y727683D01*
G01X126250Y725267D02*
X126917Y724850D01*
X127667Y724600D01*
X128333D01*
X129000Y724850D01*
X129500Y725267D01*
X129750Y725850D01*
X129583Y726433D01*
X129167Y726933D01*
X128417Y727267D01*
X127417Y727433D01*
X126833Y727767D01*
X126583Y728350D01*
X126750Y728933D01*
X127167Y729350D01*
X127750Y729600D01*
X128333D01*
X128917Y729433D01*
X129417Y729017D01*
G01X132100Y722933D02*
Y727933D01*
G01Y727183D02*
X132517Y727600D01*
X132933Y727850D01*
X133600Y727933D01*
X134183Y727850D01*
X134767Y727433D01*
X135017Y726850D01*
X135100Y726267D01*
X135017Y725683D01*
X134767Y725100D01*
X134267Y724767D01*
X133600Y724600D01*
X133017Y724683D01*
X132433Y724933D01*
X132100Y725267D01*
G01X137950Y726850D02*
X140617D01*
X140367Y727433D01*
X139950Y727767D01*
X139367Y727933D01*
X138783Y727850D01*
X138283Y727600D01*
X137950Y727017D01*
X137783Y726517D01*
Y726017D01*
X137950Y725517D01*
X138367Y725017D01*
X138867Y724683D01*
X139450Y724600D01*
X140033Y724767D01*
X140617Y725267D01*
G01X146133Y727517D02*
X145550Y727850D01*
X145050Y727933D01*
X144383Y727767D01*
X143883Y727433D01*
X143550Y726850D01*
X143467Y726267D01*
X143550Y725683D01*
X143883Y725183D01*
X144383Y724767D01*
X145050Y724600D01*
X145633Y724767D01*
X146133Y725100D01*
G01X150400Y727933D02*
Y724600D01*
G01Y729267D02*
X150233Y729350D01*
Y729517D01*
X150400Y729600D01*
X150567Y729517D01*
Y729350D01*
X150400Y729267D01*
G01X155500Y724600D02*
Y728850D01*
X155667Y729267D01*
X156000Y729517D01*
X156500Y729600D01*
X157000Y729433D01*
X157250Y729017D01*
G01X156250Y727600D02*
X154583D01*
G01X161600Y727933D02*
Y724600D01*
G01Y729267D02*
X161433Y729350D01*
Y729517D01*
X161600Y729600D01*
X161767Y729517D01*
Y729350D01*
X161600Y729267D01*
G01X168533Y727517D02*
X167950Y727850D01*
X167450Y727933D01*
X166783Y727767D01*
X166283Y727433D01*
X165950Y726850D01*
X165867Y726267D01*
X165950Y725683D01*
X166283Y725183D01*
X166783Y724767D01*
X167450Y724600D01*
X168033Y724767D01*
X168533Y725100D01*
G01X174300Y724600D02*
Y727933D01*
G01Y727350D02*
X173967Y727683D01*
X173467Y727850D01*
X172883Y727933D01*
X172300Y727767D01*
X171800Y727433D01*
X171467Y726933D01*
X171300Y726267D01*
X171467Y725600D01*
X171800Y725100D01*
X172300Y724767D01*
X172883Y724600D01*
X173467Y724683D01*
X173967Y724933D01*
X174300Y725267D01*
G01X178400Y729600D02*
Y724600D01*
G01X177233Y727933D02*
X179567D01*
G01X184000D02*
Y724600D01*
G01Y729267D02*
X183833Y729350D01*
Y729517D01*
X184000Y729600D01*
X184167Y729517D01*
Y729350D01*
X184000Y729267D01*
G01X189600Y724600D02*
X189100Y724683D01*
X188600Y725017D01*
X188267Y725600D01*
X188100Y726267D01*
X188267Y726933D01*
X188600Y727517D01*
X189100Y727850D01*
X189600Y727933D01*
X190100Y727850D01*
X190600Y727517D01*
X190933Y726933D01*
X191017Y726267D01*
X190933Y725600D01*
X190600Y725017D01*
X190100Y724683D01*
X189600Y724600D01*
G01X193783D02*
Y727933D01*
G01Y727100D02*
X194117Y727517D01*
X194617Y727850D01*
X195283Y727933D01*
X195867Y727850D01*
X196367Y727517D01*
X196617Y726933D01*
Y724600D01*
G01X205900D02*
Y728850D01*
X206067Y729267D01*
X206400Y729517D01*
X206900Y729600D01*
X207400Y729433D01*
X207650Y729017D01*
G01X206650Y727600D02*
X204983D01*
G01X212000Y724600D02*
X211500Y724683D01*
X211000Y725017D01*
X210667Y725600D01*
X210500Y726267D01*
X210667Y726933D01*
X211000Y727517D01*
X211500Y727850D01*
X212000Y727933D01*
X212500Y727850D01*
X213000Y727517D01*
X213333Y726933D01*
X213417Y726267D01*
X213333Y725600D01*
X213000Y725017D01*
X212500Y724683D01*
X212000Y724600D01*
G01X216433D02*
Y727933D01*
G01Y727267D02*
X216850Y727600D01*
X217267Y727850D01*
X217850Y727933D01*
X218267Y727850D01*
X218767Y727600D01*
G01X227133Y724600D02*
Y729600D01*
X229217D01*
X229883Y729350D01*
X230300Y729017D01*
X230467Y728350D01*
X230300Y727683D01*
X229800Y727267D01*
X229217Y727017D01*
X227133D01*
G01X229217D02*
X230467Y724600D01*
G01X233150Y726850D02*
X235817D01*
X235567Y727433D01*
X235150Y727767D01*
X234567Y727933D01*
X233983Y727850D01*
X233483Y727600D01*
X233150Y727017D01*
X232983Y726517D01*
Y726017D01*
X233150Y725517D01*
X233567Y725017D01*
X234067Y724683D01*
X234650Y724600D01*
X235233Y724767D01*
X235817Y725267D01*
G01X238750Y725183D02*
X239167Y724850D01*
X239750Y724600D01*
X240250D01*
X240750Y724767D01*
X241083Y725017D01*
X241250Y725350D01*
X241167Y725850D01*
X240833Y726100D01*
X239333Y726600D01*
X239000Y727183D01*
X239167Y727600D01*
X239500Y727850D01*
X240000Y727933D01*
X240500Y727850D01*
X241000Y727600D01*
G01X245600Y727933D02*
Y724600D01*
G01Y729267D02*
X245433Y729350D01*
Y729517D01*
X245600Y729600D01*
X245767Y729517D01*
Y729350D01*
X245600Y729267D01*
G01X249783Y724600D02*
Y727933D01*
G01Y727100D02*
X250117Y727517D01*
X250617Y727850D01*
X251283Y727933D01*
X251867Y727850D01*
X252367Y727517D01*
X252617Y726933D01*
Y724600D01*
G01X261400Y729600D02*
X263400D01*
G01X262400D02*
Y724600D01*
G01X261400D02*
X263400D01*
G01X265500D02*
Y727933D01*
G01Y727017D02*
X265750Y727433D01*
X266167Y727767D01*
X266750Y727933D01*
X267333Y727767D01*
X267750Y727433D01*
X268000Y727017D01*
Y724600D01*
G01Y727017D02*
X268250Y727433D01*
X268667Y727767D01*
X269250Y727933D01*
X269833Y727767D01*
X270250Y727433D01*
X270500Y726933D01*
Y724600D01*
G01X272100Y722933D02*
Y727933D01*
G01Y727183D02*
X272517Y727600D01*
X272933Y727850D01*
X273600Y727933D01*
X274183Y727850D01*
X274767Y727433D01*
X275017Y726850D01*
X275100Y726267D01*
X275017Y725683D01*
X274767Y725100D01*
X274267Y724767D01*
X273600Y724600D01*
X273017Y724683D01*
X272433Y724933D01*
X272100Y725267D01*
G01X278033Y724600D02*
Y727933D01*
G01Y727267D02*
X278450Y727600D01*
X278867Y727850D01*
X279450Y727933D01*
X279867Y727850D01*
X280367Y727600D01*
G01X283550Y726850D02*
X286217D01*
X285967Y727433D01*
X285550Y727767D01*
X284967Y727933D01*
X284383Y727850D01*
X283883Y727600D01*
X283550Y727017D01*
X283383Y726517D01*
Y726017D01*
X283550Y725517D01*
X283967Y725017D01*
X284467Y724683D01*
X285050Y724600D01*
X285633Y724767D01*
X286217Y725267D01*
G01X289233Y723350D02*
X289817Y723017D01*
X290483Y722933D01*
X291067Y723017D01*
X291567Y723433D01*
X291900Y724017D01*
Y727933D01*
G01Y727267D02*
X291567Y727600D01*
X291067Y727850D01*
X290483Y727933D01*
X289817Y727767D01*
X289400Y727433D01*
X289067Y726850D01*
X288900Y726267D01*
X288983Y725767D01*
X289317Y725183D01*
X289817Y724767D01*
X290483Y724600D01*
X290983Y724683D01*
X291567Y725017D01*
X291900Y725350D01*
G01X294583Y724600D02*
Y727933D01*
G01Y727100D02*
X294917Y727517D01*
X295417Y727850D01*
X296083Y727933D01*
X296667Y727850D01*
X297167Y727517D01*
X297417Y726933D01*
Y724600D01*
G01X303100D02*
Y727933D01*
G01Y727350D02*
X302767Y727683D01*
X302267Y727850D01*
X301683Y727933D01*
X301100Y727767D01*
X300600Y727433D01*
X300267Y726933D01*
X300100Y726267D01*
X300267Y725600D01*
X300600Y725100D01*
X301100Y724767D01*
X301683Y724600D01*
X302267Y724683D01*
X302767Y724933D01*
X303100Y725267D01*
G01X307200Y729600D02*
Y724600D01*
G01X306033Y727933D02*
X308367D01*
G01X311550Y726850D02*
X314217D01*
X313967Y727433D01*
X313550Y727767D01*
X312967Y727933D01*
X312383Y727850D01*
X311883Y727600D01*
X311550Y727017D01*
X311383Y726517D01*
Y726017D01*
X311550Y725517D01*
X311967Y725017D01*
X312467Y724683D01*
X313050Y724600D01*
X313633Y724767D01*
X314217Y725267D01*
G01X319900Y729600D02*
Y724600D01*
G01Y725350D02*
X319567Y724933D01*
X319067Y724683D01*
X318483Y724600D01*
X317817Y724767D01*
X317317Y725183D01*
X316983Y725683D01*
X316900Y726267D01*
X316983Y726850D01*
X317317Y727350D01*
X317817Y727767D01*
X318483Y727933D01*
X319067Y727850D01*
X319483Y727683D01*
X319900Y727350D01*
G01X328017Y724600D02*
Y729600D01*
X331183D01*
G01X330017Y727183D02*
X328017D01*
G01X336700Y724600D02*
Y727933D01*
G01Y727350D02*
X336367Y727683D01*
X335867Y727850D01*
X335283Y727933D01*
X334700Y727767D01*
X334200Y727433D01*
X333867Y726933D01*
X333700Y726267D01*
X333867Y725600D01*
X334200Y725100D01*
X334700Y724767D01*
X335283Y724600D01*
X335867Y724683D01*
X336367Y724933D01*
X336700Y725267D01*
G01X339300Y724600D02*
Y729600D01*
G01Y727100D02*
X339717Y727600D01*
X340217Y727850D01*
X340717Y727933D01*
X341467Y727767D01*
X341967Y727433D01*
X342300Y726850D01*
Y726183D01*
X342133Y725517D01*
X341800Y725017D01*
X341217Y724683D01*
X340717Y724600D01*
X340217Y724683D01*
X339717Y724933D01*
X339300Y725350D01*
G01X345233Y724600D02*
Y727933D01*
G01Y727267D02*
X345650Y727600D01*
X346067Y727850D01*
X346650Y727933D01*
X347067Y727850D01*
X347567Y727600D01*
G01X352000Y727933D02*
Y724600D01*
G01Y729267D02*
X351833Y729350D01*
Y729517D01*
X352000Y729600D01*
X352167Y729517D01*
Y729350D01*
X352000Y729267D01*
G01X358933Y727517D02*
X358350Y727850D01*
X357850Y727933D01*
X357183Y727767D01*
X356683Y727433D01*
X356350Y726850D01*
X356267Y726267D01*
X356350Y725683D01*
X356683Y725183D01*
X357183Y724767D01*
X357850Y724600D01*
X358433Y724767D01*
X358933Y725100D01*
G01X362783Y722933D02*
X361950Y723767D01*
X361533Y724600D01*
Y727933D01*
X361950Y728767D01*
X362783Y729600D01*
G01X367133Y724600D02*
Y729600D01*
X369133D01*
X369800Y729350D01*
X370300Y728767D01*
X370467Y728100D01*
X370300Y727433D01*
X369883Y726933D01*
X369133Y726683D01*
X367133D01*
G01X373233Y724600D02*
Y727933D01*
G01Y727267D02*
X373650Y727600D01*
X374067Y727850D01*
X374650Y727933D01*
X375067Y727850D01*
X375567Y727600D01*
G01X378750Y726850D02*
X381417D01*
X381167Y727433D01*
X380750Y727767D01*
X380167Y727933D01*
X379583Y727850D01*
X379083Y727600D01*
X378750Y727017D01*
X378583Y726517D01*
Y726017D01*
X378750Y725517D01*
X379167Y725017D01*
X379667Y724683D01*
X380250Y724600D01*
X380833Y724767D01*
X381417Y725267D01*
G01X384100Y722933D02*
Y727933D01*
G01Y727183D02*
X384517Y727600D01*
X384933Y727850D01*
X385600Y727933D01*
X386183Y727850D01*
X386767Y727433D01*
X387017Y726850D01*
X387100Y726267D01*
X387017Y725683D01*
X386767Y725100D01*
X386267Y724767D01*
X385600Y724600D01*
X385017Y724683D01*
X384433Y724933D01*
X384100Y725267D01*
G01X390033Y724600D02*
Y727933D01*
G01Y727267D02*
X390450Y727600D01*
X390867Y727850D01*
X391450Y727933D01*
X391867Y727850D01*
X392367Y727600D01*
G01X395550Y726850D02*
X398217D01*
X397967Y727433D01*
X397550Y727767D01*
X396967Y727933D01*
X396383Y727850D01*
X395883Y727600D01*
X395550Y727017D01*
X395383Y726517D01*
Y726017D01*
X395550Y725517D01*
X395967Y725017D01*
X396467Y724683D01*
X397050Y724600D01*
X397633Y724767D01*
X398217Y725267D01*
G01X401233Y723350D02*
X401817Y723017D01*
X402483Y722933D01*
X403067Y723017D01*
X403567Y723433D01*
X403900Y724017D01*
Y727933D01*
G01Y727267D02*
X403567Y727600D01*
X403067Y727850D01*
X402483Y727933D01*
X401817Y727767D01*
X401400Y727433D01*
X401067Y726850D01*
X400900Y726267D01*
X400983Y725767D01*
X401317Y725183D01*
X401817Y724767D01*
X402483Y724600D01*
X402983Y724683D01*
X403567Y725017D01*
X403900Y725350D01*
G01X408417Y722933D02*
X409250Y723767D01*
X409667Y724600D01*
Y727933D01*
X409250Y728767D01*
X408417Y729600D01*
G01X418700Y724600D02*
Y728850D01*
X418867Y729267D01*
X419200Y729517D01*
X419700Y729600D01*
X420200Y729433D01*
X420450Y729017D01*
G01X419450Y727600D02*
X417783D01*
G01X424800Y724600D02*
X424300Y724683D01*
X423800Y725017D01*
X423467Y725600D01*
X423300Y726267D01*
X423467Y726933D01*
X423800Y727517D01*
X424300Y727850D01*
X424800Y727933D01*
X425300Y727850D01*
X425800Y727517D01*
X426133Y726933D01*
X426217Y726267D01*
X426133Y725600D01*
X425800Y725017D01*
X425300Y724683D01*
X424800Y724600D01*
G01X429233D02*
Y727933D01*
G01Y727267D02*
X429650Y727600D01*
X430067Y727850D01*
X430650Y727933D01*
X431067Y727850D01*
X431567Y727600D01*
G01X439433Y724600D02*
Y729600D01*
X441600Y725433D01*
X443767Y729600D01*
Y724600D01*
G01X445783Y727933D02*
Y725600D01*
X446117Y725017D01*
X446617Y724683D01*
X447200Y724600D01*
X447783Y724683D01*
X448283Y725017D01*
X448617Y725600D01*
G01Y724600D02*
Y727933D01*
G01X452800Y724600D02*
Y729600D01*
G01X458400D02*
Y724600D01*
G01X457233Y727933D02*
X459567D01*
G01X464000D02*
Y724600D01*
G01Y729267D02*
X463833Y729350D01*
Y729517D01*
X464000Y729600D01*
X464167Y729517D01*
Y729350D01*
X464000Y729267D01*
G01X469600Y724600D02*
Y729600D01*
G01X476700Y724600D02*
Y727933D01*
G01Y727350D02*
X476367Y727683D01*
X475867Y727850D01*
X475283Y727933D01*
X474700Y727767D01*
X474200Y727433D01*
X473867Y726933D01*
X473700Y726267D01*
X473867Y725600D01*
X474200Y725100D01*
X474700Y724767D01*
X475283Y724600D01*
X475867Y724683D01*
X476367Y724933D01*
X476700Y725267D01*
G01X479050Y723100D02*
X479550Y722933D01*
X480217Y723100D01*
X480633Y723433D01*
X480967Y723850D01*
X481467Y725183D01*
X482550Y727933D01*
G01X479883D02*
X481467Y725183D01*
G01X485150Y726850D02*
X487817D01*
X487567Y727433D01*
X487150Y727767D01*
X486567Y727933D01*
X485983Y727850D01*
X485483Y727600D01*
X485150Y727017D01*
X484983Y726517D01*
Y726017D01*
X485150Y725517D01*
X485567Y725017D01*
X486067Y724683D01*
X486650Y724600D01*
X487233Y724767D01*
X487817Y725267D01*
G01X490833Y724600D02*
Y727933D01*
G01Y727267D02*
X491250Y727600D01*
X491667Y727850D01*
X492250Y727933D01*
X492667Y727850D01*
X493167Y727600D01*
G01X501533Y724600D02*
Y729600D01*
X503533D01*
X504200Y729350D01*
X504700Y728767D01*
X504867Y728100D01*
X504700Y727433D01*
X504283Y726933D01*
X503533Y726683D01*
X501533D01*
G01X507633Y724600D02*
Y727933D01*
G01Y727267D02*
X508050Y727600D01*
X508467Y727850D01*
X509050Y727933D01*
X509467Y727850D01*
X509967Y727600D01*
G01X514400Y727933D02*
Y724600D01*
G01Y729267D02*
X514233Y729350D01*
Y729517D01*
X514400Y729600D01*
X514567Y729517D01*
Y729350D01*
X514400Y729267D01*
G01X518583Y724600D02*
Y727933D01*
G01Y727100D02*
X518917Y727517D01*
X519417Y727850D01*
X520083Y727933D01*
X520667Y727850D01*
X521167Y727517D01*
X521417Y726933D01*
Y724600D01*
G01X525600Y729600D02*
Y724600D01*
G01X524433Y727933D02*
X526767D01*
G01X529950Y726850D02*
X532617D01*
X532367Y727433D01*
X531950Y727767D01*
X531367Y727933D01*
X530783Y727850D01*
X530283Y727600D01*
X529950Y727017D01*
X529783Y726517D01*
Y726017D01*
X529950Y725517D01*
X530367Y725017D01*
X530867Y724683D01*
X531450Y724600D01*
X532033Y724767D01*
X532617Y725267D01*
G01X538300Y729600D02*
Y724600D01*
G01Y725350D02*
X537967Y724933D01*
X537467Y724683D01*
X536883Y724600D01*
X536217Y724767D01*
X535717Y725183D01*
X535383Y725683D01*
X535300Y726267D01*
X535383Y726850D01*
X535717Y727350D01*
X536217Y727767D01*
X536883Y727933D01*
X537467Y727850D01*
X537883Y727683D01*
X538300Y727350D01*
G01X548667Y727267D02*
X549000Y727517D01*
X549250Y727933D01*
X549417Y728517D01*
X549250Y729017D01*
X548917Y729350D01*
X548333Y729600D01*
X546083D01*
Y724600D01*
X548833D01*
X549417Y724933D01*
X549750Y725433D01*
X549917Y726017D01*
X549750Y726600D01*
X549250Y727100D01*
X548667Y727267D01*
X546083D01*
G01X553600Y724600D02*
X553100Y724683D01*
X552600Y725017D01*
X552267Y725600D01*
X552100Y726267D01*
X552267Y726933D01*
X552600Y727517D01*
X553100Y727850D01*
X553600Y727933D01*
X554100Y727850D01*
X554600Y727517D01*
X554933Y726933D01*
X555017Y726267D01*
X554933Y725600D01*
X554600Y725017D01*
X554100Y724683D01*
X553600Y724600D01*
G01X560700D02*
Y727933D01*
G01Y727350D02*
X560367Y727683D01*
X559867Y727850D01*
X559283Y727933D01*
X558700Y727767D01*
X558200Y727433D01*
X557867Y726933D01*
X557700Y726267D01*
X557867Y725600D01*
X558200Y725100D01*
X558700Y724767D01*
X559283Y724600D01*
X559867Y724683D01*
X560367Y724933D01*
X560700Y725267D01*
G01X563633Y724600D02*
Y727933D01*
G01Y727267D02*
X564050Y727600D01*
X564467Y727850D01*
X565050Y727933D01*
X565467Y727850D01*
X565967Y727600D01*
G01X571900Y729600D02*
Y724600D01*
G01Y725350D02*
X571567Y724933D01*
X571067Y724683D01*
X570483Y724600D01*
X569817Y724767D01*
X569317Y725183D01*
X568983Y725683D01*
X568900Y726267D01*
X568983Y726850D01*
X569317Y727350D01*
X569817Y727767D01*
X570483Y727933D01*
X571067Y727850D01*
X571483Y727683D01*
X571900Y727350D01*
G01X574750Y725183D02*
X575167Y724850D01*
X575750Y724600D01*
X576250D01*
X576750Y724767D01*
X577083Y725017D01*
X577250Y725350D01*
X577167Y725850D01*
X576833Y726100D01*
X575333Y726600D01*
X575000Y727183D01*
X575167Y727600D01*
X575500Y727850D01*
X576000Y727933D01*
X576500Y727850D01*
X577000Y727600D01*
G01X71000Y738600D02*
X73000D01*
G01X72000D02*
Y733600D01*
G01X71000D02*
X73000D01*
G01X75933D02*
Y738600D01*
X77933D01*
X78600Y738350D01*
X79100Y737767D01*
X79267Y737100D01*
X79100Y736433D01*
X78683Y735933D01*
X77933Y735683D01*
X75933D01*
G01X85033Y738183D02*
X84533Y738433D01*
X83950Y738600D01*
X83283D01*
X82533Y738350D01*
X81950Y737933D01*
X81533Y737433D01*
X81200Y736600D01*
X81117Y735850D01*
X81283Y735100D01*
X81533Y734600D01*
X82033Y734100D01*
X82617Y733767D01*
X83200Y733600D01*
X83783D01*
X84367Y733767D01*
X84867Y734017D01*
X85283Y734350D01*
G01X87717Y735267D02*
X89883D01*
G01X92233Y733600D02*
Y738600D01*
X94400Y734433D01*
X96567Y738600D01*
Y733600D01*
G01X98417D02*
Y738600D01*
X101583D01*
G01X100417Y736183D02*
X98417D01*
G01X104517Y735267D02*
X106683D01*
G01X111200Y733600D02*
Y738600D01*
X110200Y737600D01*
G01Y733600D02*
X112200D01*
G01X114967Y734350D02*
X115467Y733933D01*
X116050Y733683D01*
X116800Y733600D01*
X117550Y733767D01*
X118133Y734100D01*
X118550Y734683D01*
X118633Y735350D01*
X118467Y736017D01*
X118050Y736433D01*
X117467Y736767D01*
X116883Y736850D01*
X116300Y736767D01*
X115550Y736433D01*
X115800Y738600D01*
X118050D01*
G01X122400D02*
X121733Y738433D01*
X121233Y738017D01*
X120900Y737517D01*
X120650Y736850D01*
X120567Y736100D01*
X120650Y735350D01*
X120900Y734683D01*
X121233Y734183D01*
X121733Y733767D01*
X122400Y733600D01*
X123067Y733767D01*
X123567Y734183D01*
X123900Y734683D01*
X124150Y735350D01*
X124233Y736100D01*
X124150Y736850D01*
X123900Y737517D01*
X123567Y738017D01*
X123067Y738433D01*
X122400Y738600D01*
G01X131433Y733600D02*
Y738600D01*
X133600Y734433D01*
X135767Y738600D01*
Y733600D01*
G01X137950Y735850D02*
X140617D01*
X140367Y736433D01*
X139950Y736767D01*
X139367Y736933D01*
X138783Y736850D01*
X138283Y736600D01*
X137950Y736017D01*
X137783Y735517D01*
Y735017D01*
X137950Y734517D01*
X138367Y734017D01*
X138867Y733683D01*
X139450Y733600D01*
X140033Y733767D01*
X140617Y734267D01*
G01X144800Y738600D02*
Y733600D01*
G01X143633Y736933D02*
X145967D01*
G01X151900Y733600D02*
Y736933D01*
G01Y736350D02*
X151567Y736683D01*
X151067Y736850D01*
X150483Y736933D01*
X149900Y736767D01*
X149400Y736433D01*
X149067Y735933D01*
X148900Y735267D01*
X149067Y734600D01*
X149400Y734100D01*
X149900Y733767D01*
X150483Y733600D01*
X151067Y733683D01*
X151567Y733933D01*
X151900Y734267D01*
G01X156000Y733600D02*
Y738600D01*
G01X165617Y733600D02*
Y738600D01*
X168783D01*
G01X167617Y736183D02*
X165617D01*
G01X172800Y733600D02*
X172300Y733683D01*
X171800Y734017D01*
X171467Y734600D01*
X171300Y735267D01*
X171467Y735933D01*
X171800Y736517D01*
X172300Y736850D01*
X172800Y736933D01*
X173300Y736850D01*
X173800Y736517D01*
X174133Y735933D01*
X174217Y735267D01*
X174133Y734600D01*
X173800Y734017D01*
X173300Y733683D01*
X172800Y733600D01*
G01X178400Y736933D02*
Y733600D01*
G01Y738267D02*
X178233Y738350D01*
Y738517D01*
X178400Y738600D01*
X178567Y738517D01*
Y738350D01*
X178400Y738267D01*
G01X184000Y733600D02*
Y738600D01*
G01X194700Y733600D02*
Y737850D01*
X194867Y738267D01*
X195200Y738517D01*
X195700Y738600D01*
X196200Y738433D01*
X196450Y738017D01*
G01X195450Y736600D02*
X193783D01*
G01X200800Y733600D02*
X200300Y733683D01*
X199800Y734017D01*
X199467Y734600D01*
X199300Y735267D01*
X199467Y735933D01*
X199800Y736517D01*
X200300Y736850D01*
X200800Y736933D01*
X201300Y736850D01*
X201800Y736517D01*
X202133Y735933D01*
X202217Y735267D01*
X202133Y734600D01*
X201800Y734017D01*
X201300Y733683D01*
X200800Y733600D01*
G01X205233D02*
Y736933D01*
G01Y736267D02*
X205650Y736600D01*
X206067Y736850D01*
X206650Y736933D01*
X207067Y736850D01*
X207567Y736600D01*
G01X215933Y733600D02*
Y738600D01*
X217933D01*
X218600Y738350D01*
X219100Y737767D01*
X219267Y737100D01*
X219100Y736433D01*
X218683Y735933D01*
X217933Y735683D01*
X215933D01*
G01X222033Y733600D02*
Y736933D01*
G01Y736267D02*
X222450Y736600D01*
X222867Y736850D01*
X223450Y736933D01*
X223867Y736850D01*
X224367Y736600D01*
G01X228800Y736933D02*
Y733600D01*
G01Y738267D02*
X228633Y738350D01*
Y738517D01*
X228800Y738600D01*
X228967Y738517D01*
Y738350D01*
X228800Y738267D01*
G01X232983Y733600D02*
Y736933D01*
G01Y736100D02*
X233317Y736517D01*
X233817Y736850D01*
X234483Y736933D01*
X235067Y736850D01*
X235567Y736517D01*
X235817Y735933D01*
Y733600D01*
G01X240000Y738600D02*
Y733600D01*
G01X238833Y736933D02*
X241167D01*
G01X244350Y735850D02*
X247017D01*
X246767Y736433D01*
X246350Y736767D01*
X245767Y736933D01*
X245183Y736850D01*
X244683Y736600D01*
X244350Y736017D01*
X244183Y735517D01*
Y735017D01*
X244350Y734517D01*
X244767Y734017D01*
X245267Y733683D01*
X245850Y733600D01*
X246433Y733767D01*
X247017Y734267D01*
G01X252700Y738600D02*
Y733600D01*
G01Y734350D02*
X252367Y733933D01*
X251867Y733683D01*
X251283Y733600D01*
X250617Y733767D01*
X250117Y734183D01*
X249783Y734683D01*
X249700Y735267D01*
X249783Y735850D01*
X250117Y736350D01*
X250617Y736767D01*
X251283Y736933D01*
X251867Y736850D01*
X252283Y736683D01*
X252700Y736350D01*
G01X259900Y738600D02*
X261067Y733600D01*
X262400Y738600D01*
X263733Y733600D01*
X264900Y738600D01*
G01X268000Y736933D02*
Y733600D01*
G01Y738267D02*
X267833Y738350D01*
Y738517D01*
X268000Y738600D01*
X268167Y738517D01*
Y738350D01*
X268000Y738267D01*
G01X272433Y733600D02*
Y736933D01*
G01Y736267D02*
X272850Y736600D01*
X273267Y736850D01*
X273850Y736933D01*
X274267Y736850D01*
X274767Y736600D01*
G01X279200Y736933D02*
Y733600D01*
G01Y738267D02*
X279033Y738350D01*
Y738517D01*
X279200Y738600D01*
X279367Y738517D01*
Y738350D01*
X279200Y738267D01*
G01X283383Y733600D02*
Y736933D01*
G01Y736100D02*
X283717Y736517D01*
X284217Y736850D01*
X284883Y736933D01*
X285467Y736850D01*
X285967Y736517D01*
X286217Y735933D01*
Y733600D01*
G01X289233Y732350D02*
X289817Y732017D01*
X290483Y731933D01*
X291067Y732017D01*
X291567Y732433D01*
X291900Y733017D01*
Y736933D01*
G01Y736267D02*
X291567Y736600D01*
X291067Y736850D01*
X290483Y736933D01*
X289817Y736767D01*
X289400Y736433D01*
X289067Y735850D01*
X288900Y735267D01*
X288983Y734767D01*
X289317Y734183D01*
X289817Y733767D01*
X290483Y733600D01*
X290983Y733683D01*
X291567Y734017D01*
X291900Y734350D01*
G01X299517Y733600D02*
X301600Y738600D01*
X303683Y733600D01*
G01X302933Y735350D02*
X300267D01*
G01X305700Y731933D02*
Y736933D01*
G01Y736183D02*
X306117Y736600D01*
X306533Y736850D01*
X307200Y736933D01*
X307783Y736850D01*
X308367Y736433D01*
X308617Y735850D01*
X308700Y735267D01*
X308617Y734683D01*
X308367Y734100D01*
X307867Y733767D01*
X307200Y733600D01*
X306617Y733683D01*
X306033Y733933D01*
X305700Y734267D01*
G01X311300Y731933D02*
Y736933D01*
G01Y736183D02*
X311717Y736600D01*
X312133Y736850D01*
X312800Y736933D01*
X313383Y736850D01*
X313967Y736433D01*
X314217Y735850D01*
X314300Y735267D01*
X314217Y734683D01*
X313967Y734100D01*
X313467Y733767D01*
X312800Y733600D01*
X312217Y733683D01*
X311633Y733933D01*
X311300Y734267D01*
G01X318400Y733600D02*
Y738600D01*
G01X324000Y736933D02*
Y733600D01*
G01Y738267D02*
X323833Y738350D01*
Y738517D01*
X324000Y738600D01*
X324167Y738517D01*
Y738350D01*
X324000Y738267D01*
G01X330933Y736517D02*
X330350Y736850D01*
X329850Y736933D01*
X329183Y736767D01*
X328683Y736433D01*
X328350Y735850D01*
X328267Y735267D01*
X328350Y734683D01*
X328683Y734183D01*
X329183Y733767D01*
X329850Y733600D01*
X330433Y733767D01*
X330933Y734100D01*
G01X336700Y733600D02*
Y736933D01*
G01Y736350D02*
X336367Y736683D01*
X335867Y736850D01*
X335283Y736933D01*
X334700Y736767D01*
X334200Y736433D01*
X333867Y735933D01*
X333700Y735267D01*
X333867Y734600D01*
X334200Y734100D01*
X334700Y733767D01*
X335283Y733600D01*
X335867Y733683D01*
X336367Y733933D01*
X336700Y734267D01*
G01X340800Y738600D02*
Y733600D01*
G01X339633Y736933D02*
X341967D01*
G01X346400D02*
Y733600D01*
G01Y738267D02*
X346233Y738350D01*
Y738517D01*
X346400Y738600D01*
X346567Y738517D01*
Y738350D01*
X346400Y738267D01*
G01X352000Y733600D02*
X351500Y733683D01*
X351000Y734017D01*
X350667Y734600D01*
X350500Y735267D01*
X350667Y735933D01*
X351000Y736517D01*
X351500Y736850D01*
X352000Y736933D01*
X352500Y736850D01*
X353000Y736517D01*
X353333Y735933D01*
X353417Y735267D01*
X353333Y734600D01*
X353000Y734017D01*
X352500Y733683D01*
X352000Y733600D01*
G01X356183D02*
Y736933D01*
G01Y736100D02*
X356517Y736517D01*
X357017Y736850D01*
X357683Y736933D01*
X358267Y736850D01*
X358767Y736517D01*
X359017Y735933D01*
Y733600D01*
G01X361950Y734183D02*
X362367Y733850D01*
X362950Y733600D01*
X363450D01*
X363950Y733767D01*
X364283Y734017D01*
X364450Y734350D01*
X364367Y734850D01*
X364033Y735100D01*
X362533Y735600D01*
X362200Y736183D01*
X362367Y736600D01*
X362700Y736850D01*
X363200Y736933D01*
X363700Y736850D01*
X364200Y736600D01*
G01X71000Y747600D02*
X73000D01*
G01X72000D02*
Y742600D01*
G01X71000D02*
X73000D01*
G01X75933D02*
Y747600D01*
X77933D01*
X78600Y747350D01*
X79100Y746767D01*
X79267Y746100D01*
X79100Y745433D01*
X78683Y744933D01*
X77933Y744683D01*
X75933D01*
G01X85033Y747183D02*
X84533Y747433D01*
X83950Y747600D01*
X83283D01*
X82533Y747350D01*
X81950Y746933D01*
X81533Y746433D01*
X81200Y745600D01*
X81117Y744850D01*
X81283Y744100D01*
X81533Y743600D01*
X82033Y743100D01*
X82617Y742767D01*
X83200Y742600D01*
X83783D01*
X84367Y742767D01*
X84867Y743017D01*
X85283Y743350D01*
G01X87717Y744267D02*
X89883D01*
G01X95400Y742600D02*
Y747600D01*
X92317Y744017D01*
X96483D01*
G01X100000Y742600D02*
Y747600D01*
X99000Y746600D01*
G01Y742600D02*
X101000D01*
G01X105600Y747600D02*
X104933Y747433D01*
X104433Y747017D01*
X104100Y746517D01*
X103850Y745850D01*
X103767Y745100D01*
X103850Y744350D01*
X104100Y743683D01*
X104433Y743183D01*
X104933Y742767D01*
X105600Y742600D01*
X106267Y742767D01*
X106767Y743183D01*
X107100Y743683D01*
X107350Y744350D01*
X107433Y745100D01*
X107350Y745850D01*
X107100Y746517D01*
X106767Y747017D01*
X106267Y747433D01*
X105600Y747600D01*
G01X111200Y742600D02*
Y747600D01*
X110200Y746600D01*
G01Y742600D02*
X112200D01*
G01X120650Y743267D02*
X121317Y742850D01*
X122067Y742600D01*
X122733D01*
X123400Y742850D01*
X123900Y743267D01*
X124150Y743850D01*
X123983Y744433D01*
X123567Y744933D01*
X122817Y745267D01*
X121817Y745433D01*
X121233Y745767D01*
X120983Y746350D01*
X121150Y746933D01*
X121567Y747350D01*
X122150Y747600D01*
X122733D01*
X123317Y747433D01*
X123817Y747017D01*
G01X126500Y740933D02*
Y745933D01*
G01Y745183D02*
X126917Y745600D01*
X127333Y745850D01*
X128000Y745933D01*
X128583Y745850D01*
X129167Y745433D01*
X129417Y744850D01*
X129500Y744267D01*
X129417Y743683D01*
X129167Y743100D01*
X128667Y742767D01*
X128000Y742600D01*
X127417Y742683D01*
X126833Y742933D01*
X126500Y743267D01*
G01X132350Y744850D02*
X135017D01*
X134767Y745433D01*
X134350Y745767D01*
X133767Y745933D01*
X133183Y745850D01*
X132683Y745600D01*
X132350Y745017D01*
X132183Y744517D01*
Y744017D01*
X132350Y743517D01*
X132767Y743017D01*
X133267Y742683D01*
X133850Y742600D01*
X134433Y742767D01*
X135017Y743267D01*
G01X140533Y745517D02*
X139950Y745850D01*
X139450Y745933D01*
X138783Y745767D01*
X138283Y745433D01*
X137950Y744850D01*
X137867Y744267D01*
X137950Y743683D01*
X138283Y743183D01*
X138783Y742767D01*
X139450Y742600D01*
X140033Y742767D01*
X140533Y743100D01*
G01X144800Y745933D02*
Y742600D01*
G01Y747267D02*
X144633Y747350D01*
Y747517D01*
X144800Y747600D01*
X144967Y747517D01*
Y747350D01*
X144800Y747267D01*
G01X149900Y742600D02*
Y746850D01*
X150067Y747267D01*
X150400Y747517D01*
X150900Y747600D01*
X151400Y747433D01*
X151650Y747017D01*
G01X150650Y745600D02*
X148983D01*
G01X156000Y745933D02*
Y742600D01*
G01Y747267D02*
X155833Y747350D01*
Y747517D01*
X156000Y747600D01*
X156167Y747517D01*
Y747350D01*
X156000Y747267D01*
G01X162933Y745517D02*
X162350Y745850D01*
X161850Y745933D01*
X161183Y745767D01*
X160683Y745433D01*
X160350Y744850D01*
X160267Y744267D01*
X160350Y743683D01*
X160683Y743183D01*
X161183Y742767D01*
X161850Y742600D01*
X162433Y742767D01*
X162933Y743100D01*
G01X168700Y742600D02*
Y745933D01*
G01Y745350D02*
X168367Y745683D01*
X167867Y745850D01*
X167283Y745933D01*
X166700Y745767D01*
X166200Y745433D01*
X165867Y744933D01*
X165700Y744267D01*
X165867Y743600D01*
X166200Y743100D01*
X166700Y742767D01*
X167283Y742600D01*
X167867Y742683D01*
X168367Y742933D01*
X168700Y743267D01*
G01X172800Y747600D02*
Y742600D01*
G01X171633Y745933D02*
X173967D01*
G01X178400D02*
Y742600D01*
G01Y747267D02*
X178233Y747350D01*
Y747517D01*
X178400Y747600D01*
X178567Y747517D01*
Y747350D01*
X178400Y747267D01*
G01X184000Y742600D02*
X183500Y742683D01*
X183000Y743017D01*
X182667Y743600D01*
X182500Y744267D01*
X182667Y744933D01*
X183000Y745517D01*
X183500Y745850D01*
X184000Y745933D01*
X184500Y745850D01*
X185000Y745517D01*
X185333Y744933D01*
X185417Y744267D01*
X185333Y743600D01*
X185000Y743017D01*
X184500Y742683D01*
X184000Y742600D01*
G01X188183D02*
Y745933D01*
G01Y745100D02*
X188517Y745517D01*
X189017Y745850D01*
X189683Y745933D01*
X190267Y745850D01*
X190767Y745517D01*
X191017Y744933D01*
Y742600D01*
G01X200300D02*
Y746850D01*
X200467Y747267D01*
X200800Y747517D01*
X201300Y747600D01*
X201800Y747433D01*
X202050Y747017D01*
G01X201050Y745600D02*
X199383D01*
G01X206400Y742600D02*
X205900Y742683D01*
X205400Y743017D01*
X205067Y743600D01*
X204900Y744267D01*
X205067Y744933D01*
X205400Y745517D01*
X205900Y745850D01*
X206400Y745933D01*
X206900Y745850D01*
X207400Y745517D01*
X207733Y744933D01*
X207817Y744267D01*
X207733Y743600D01*
X207400Y743017D01*
X206900Y742683D01*
X206400Y742600D01*
G01X210833D02*
Y745933D01*
G01Y745267D02*
X211250Y745600D01*
X211667Y745850D01*
X212250Y745933D01*
X212667Y745850D01*
X213167Y745600D01*
G01X223867Y745267D02*
X224200Y745517D01*
X224450Y745933D01*
X224617Y746517D01*
X224450Y747017D01*
X224117Y747350D01*
X223533Y747600D01*
X221283D01*
Y742600D01*
X224033D01*
X224617Y742933D01*
X224950Y743433D01*
X225117Y744017D01*
X224950Y744600D01*
X224450Y745100D01*
X223867Y745267D01*
X221283D01*
G01X230300Y742600D02*
Y745933D01*
G01Y745350D02*
X229967Y745683D01*
X229467Y745850D01*
X228883Y745933D01*
X228300Y745767D01*
X227800Y745433D01*
X227467Y744933D01*
X227300Y744267D01*
X227467Y743600D01*
X227800Y743100D01*
X228300Y742767D01*
X228883Y742600D01*
X229467Y742683D01*
X229967Y742933D01*
X230300Y743267D01*
G01X233150Y743183D02*
X233567Y742850D01*
X234150Y742600D01*
X234650D01*
X235150Y742767D01*
X235483Y743017D01*
X235650Y743350D01*
X235567Y743850D01*
X235233Y744100D01*
X233733Y744600D01*
X233400Y745183D01*
X233567Y745600D01*
X233900Y745850D01*
X234400Y745933D01*
X234900Y745850D01*
X235400Y745600D01*
G01X238750Y744850D02*
X241417D01*
X241167Y745433D01*
X240750Y745767D01*
X240167Y745933D01*
X239583Y745850D01*
X239083Y745600D01*
X238750Y745017D01*
X238583Y744517D01*
Y744017D01*
X238750Y743517D01*
X239167Y743017D01*
X239667Y742683D01*
X240250Y742600D01*
X240833Y742767D01*
X241417Y743267D01*
G01X249033Y742600D02*
Y747600D01*
X251200Y743433D01*
X253367Y747600D01*
Y742600D01*
G01X258300D02*
Y745933D01*
G01Y745350D02*
X257967Y745683D01*
X257467Y745850D01*
X256883Y745933D01*
X256300Y745767D01*
X255800Y745433D01*
X255467Y744933D01*
X255300Y744267D01*
X255467Y743600D01*
X255800Y743100D01*
X256300Y742767D01*
X256883Y742600D01*
X257467Y742683D01*
X257967Y742933D01*
X258300Y743267D01*
G01X262400Y747600D02*
Y742600D01*
G01X261233Y745933D02*
X263567D01*
G01X266750Y744850D02*
X269417D01*
X269167Y745433D01*
X268750Y745767D01*
X268167Y745933D01*
X267583Y745850D01*
X267083Y745600D01*
X266750Y745017D01*
X266583Y744517D01*
Y744017D01*
X266750Y743517D01*
X267167Y743017D01*
X267667Y742683D01*
X268250Y742600D01*
X268833Y742767D01*
X269417Y743267D01*
G01X272433Y742600D02*
Y745933D01*
G01Y745267D02*
X272850Y745600D01*
X273267Y745850D01*
X273850Y745933D01*
X274267Y745850D01*
X274767Y745600D01*
G01X279200Y745933D02*
Y742600D01*
G01Y747267D02*
X279033Y747350D01*
Y747517D01*
X279200Y747600D01*
X279367Y747517D01*
Y747350D01*
X279200Y747267D01*
G01X286300Y742600D02*
Y745933D01*
G01Y745350D02*
X285967Y745683D01*
X285467Y745850D01*
X284883Y745933D01*
X284300Y745767D01*
X283800Y745433D01*
X283467Y744933D01*
X283300Y744267D01*
X283467Y743600D01*
X283800Y743100D01*
X284300Y742767D01*
X284883Y742600D01*
X285467Y742683D01*
X285967Y742933D01*
X286300Y743267D01*
G01X290400Y742600D02*
Y747600D01*
G01X294750Y743183D02*
X295167Y742850D01*
X295750Y742600D01*
X296250D01*
X296750Y742767D01*
X297083Y743017D01*
X297250Y743350D01*
X297167Y743850D01*
X296833Y744100D01*
X295333Y744600D01*
X295000Y745183D01*
X295167Y745600D01*
X295500Y745850D01*
X296000Y745933D01*
X296500Y745850D01*
X297000Y745600D01*
G01X306700Y742600D02*
Y746850D01*
X306867Y747267D01*
X307200Y747517D01*
X307700Y747600D01*
X308200Y747433D01*
X308450Y747017D01*
G01X307450Y745600D02*
X305783D01*
G01X312800Y742600D02*
X312300Y742683D01*
X311800Y743017D01*
X311467Y743600D01*
X311300Y744267D01*
X311467Y744933D01*
X311800Y745517D01*
X312300Y745850D01*
X312800Y745933D01*
X313300Y745850D01*
X313800Y745517D01*
X314133Y744933D01*
X314217Y744267D01*
X314133Y743600D01*
X313800Y743017D01*
X313300Y742683D01*
X312800Y742600D01*
G01X317233D02*
Y745933D01*
G01Y745267D02*
X317650Y745600D01*
X318067Y745850D01*
X318650Y745933D01*
X319067Y745850D01*
X319567Y745600D01*
G01X327933Y742600D02*
Y747600D01*
X330017D01*
X330683Y747350D01*
X331100Y747017D01*
X331267Y746350D01*
X331100Y745683D01*
X330600Y745267D01*
X330017Y745017D01*
X327933D01*
G01X330017D02*
X331267Y742600D01*
G01X335200Y745933D02*
Y742600D01*
G01Y747267D02*
X335033Y747350D01*
Y747517D01*
X335200Y747600D01*
X335367Y747517D01*
Y747350D01*
X335200Y747267D01*
G01X339633Y741350D02*
X340217Y741017D01*
X340883Y740933D01*
X341467Y741017D01*
X341967Y741433D01*
X342300Y742017D01*
Y745933D01*
G01Y745267D02*
X341967Y745600D01*
X341467Y745850D01*
X340883Y745933D01*
X340217Y745767D01*
X339800Y745433D01*
X339467Y744850D01*
X339300Y744267D01*
X339383Y743767D01*
X339717Y743183D01*
X340217Y742767D01*
X340883Y742600D01*
X341383Y742683D01*
X341967Y743017D01*
X342300Y743350D01*
G01X346400Y745933D02*
Y742600D01*
G01Y747267D02*
X346233Y747350D01*
Y747517D01*
X346400Y747600D01*
X346567Y747517D01*
Y747350D01*
X346400Y747267D01*
G01X353500Y747600D02*
Y742600D01*
G01Y743350D02*
X353167Y742933D01*
X352667Y742683D01*
X352083Y742600D01*
X351417Y742767D01*
X350917Y743183D01*
X350583Y743683D01*
X350500Y744267D01*
X350583Y744850D01*
X350917Y745350D01*
X351417Y745767D01*
X352083Y745933D01*
X352667Y745850D01*
X353083Y745683D01*
X353500Y745350D01*
G01X364700Y742600D02*
Y745933D01*
G01Y745350D02*
X364367Y745683D01*
X363867Y745850D01*
X363283Y745933D01*
X362700Y745767D01*
X362200Y745433D01*
X361867Y744933D01*
X361700Y744267D01*
X361867Y743600D01*
X362200Y743100D01*
X362700Y742767D01*
X363283Y742600D01*
X363867Y742683D01*
X364367Y742933D01*
X364700Y743267D01*
G01X367383Y742600D02*
Y745933D01*
G01Y745100D02*
X367717Y745517D01*
X368217Y745850D01*
X368883Y745933D01*
X369467Y745850D01*
X369967Y745517D01*
X370217Y744933D01*
Y742600D01*
G01X375900Y747600D02*
Y742600D01*
G01Y743350D02*
X375567Y742933D01*
X375067Y742683D01*
X374483Y742600D01*
X373817Y742767D01*
X373317Y743183D01*
X372983Y743683D01*
X372900Y744267D01*
X372983Y744850D01*
X373317Y745350D01*
X373817Y745767D01*
X374483Y745933D01*
X375067Y745850D01*
X375483Y745683D01*
X375900Y745350D01*
G01X383433Y742600D02*
Y747600D01*
X385600Y743433D01*
X387767Y747600D01*
Y742600D01*
G01X389783Y745933D02*
Y743600D01*
X390117Y743017D01*
X390617Y742683D01*
X391200Y742600D01*
X391783Y742683D01*
X392283Y743017D01*
X392617Y743600D01*
G01Y742600D02*
Y745933D01*
G01X396800Y742600D02*
Y747600D01*
G01X402400D02*
Y742600D01*
G01X401233Y745933D02*
X403567D01*
G01X408000D02*
Y742600D01*
G01Y747267D02*
X407833Y747350D01*
Y747517D01*
X408000Y747600D01*
X408167Y747517D01*
Y747350D01*
X408000Y747267D01*
G01X413600Y742600D02*
Y747600D01*
G01X420700Y742600D02*
Y745933D01*
G01Y745350D02*
X420367Y745683D01*
X419867Y745850D01*
X419283Y745933D01*
X418700Y745767D01*
X418200Y745433D01*
X417867Y744933D01*
X417700Y744267D01*
X417867Y743600D01*
X418200Y743100D01*
X418700Y742767D01*
X419283Y742600D01*
X419867Y742683D01*
X420367Y742933D01*
X420700Y743267D01*
G01X423050Y741100D02*
X423550Y740933D01*
X424217Y741100D01*
X424633Y741433D01*
X424967Y741850D01*
X425467Y743183D01*
X426550Y745933D01*
G01X423883D02*
X425467Y743183D01*
G01X429150Y744850D02*
X431817D01*
X431567Y745433D01*
X431150Y745767D01*
X430567Y745933D01*
X429983Y745850D01*
X429483Y745600D01*
X429150Y745017D01*
X428983Y744517D01*
Y744017D01*
X429150Y743517D01*
X429567Y743017D01*
X430067Y742683D01*
X430650Y742600D01*
X431233Y742767D01*
X431817Y743267D01*
G01X434833Y742600D02*
Y745933D01*
G01Y745267D02*
X435250Y745600D01*
X435667Y745850D01*
X436250Y745933D01*
X436667Y745850D01*
X437167Y745600D01*
G01X445533Y742600D02*
Y747600D01*
X447533D01*
X448200Y747350D01*
X448700Y746767D01*
X448867Y746100D01*
X448700Y745433D01*
X448283Y744933D01*
X447533Y744683D01*
X445533D01*
G01X451633Y742600D02*
Y745933D01*
G01Y745267D02*
X452050Y745600D01*
X452467Y745850D01*
X453050Y745933D01*
X453467Y745850D01*
X453967Y745600D01*
G01X458400Y745933D02*
Y742600D01*
G01Y747267D02*
X458233Y747350D01*
Y747517D01*
X458400Y747600D01*
X458567Y747517D01*
Y747350D01*
X458400Y747267D01*
G01X462583Y742600D02*
Y745933D01*
G01Y745100D02*
X462917Y745517D01*
X463417Y745850D01*
X464083Y745933D01*
X464667Y745850D01*
X465167Y745517D01*
X465417Y744933D01*
Y742600D01*
G01X469600Y747600D02*
Y742600D01*
G01X468433Y745933D02*
X470767D01*
G01X473950Y744850D02*
X476617D01*
X476367Y745433D01*
X475950Y745767D01*
X475367Y745933D01*
X474783Y745850D01*
X474283Y745600D01*
X473950Y745017D01*
X473783Y744517D01*
Y744017D01*
X473950Y743517D01*
X474367Y743017D01*
X474867Y742683D01*
X475450Y742600D01*
X476033Y742767D01*
X476617Y743267D01*
G01X482300Y747600D02*
Y742600D01*
G01Y743350D02*
X481967Y742933D01*
X481467Y742683D01*
X480883Y742600D01*
X480217Y742767D01*
X479717Y743183D01*
X479383Y743683D01*
X479300Y744267D01*
X479383Y744850D01*
X479717Y745350D01*
X480217Y745767D01*
X480883Y745933D01*
X481467Y745850D01*
X481883Y745683D01*
X482300Y745350D01*
G01X492667Y745267D02*
X493000Y745517D01*
X493250Y745933D01*
X493417Y746517D01*
X493250Y747017D01*
X492917Y747350D01*
X492333Y747600D01*
X490083D01*
Y742600D01*
X492833D01*
X493417Y742933D01*
X493750Y743433D01*
X493917Y744017D01*
X493750Y744600D01*
X493250Y745100D01*
X492667Y745267D01*
X490083D01*
G01X497600Y742600D02*
X497100Y742683D01*
X496600Y743017D01*
X496267Y743600D01*
X496100Y744267D01*
X496267Y744933D01*
X496600Y745517D01*
X497100Y745850D01*
X497600Y745933D01*
X498100Y745850D01*
X498600Y745517D01*
X498933Y744933D01*
X499017Y744267D01*
X498933Y743600D01*
X498600Y743017D01*
X498100Y742683D01*
X497600Y742600D01*
G01X504700D02*
Y745933D01*
G01Y745350D02*
X504367Y745683D01*
X503867Y745850D01*
X503283Y745933D01*
X502700Y745767D01*
X502200Y745433D01*
X501867Y744933D01*
X501700Y744267D01*
X501867Y743600D01*
X502200Y743100D01*
X502700Y742767D01*
X503283Y742600D01*
X503867Y742683D01*
X504367Y742933D01*
X504700Y743267D01*
G01X507633Y742600D02*
Y745933D01*
G01Y745267D02*
X508050Y745600D01*
X508467Y745850D01*
X509050Y745933D01*
X509467Y745850D01*
X509967Y745600D01*
G01X515900Y747600D02*
Y742600D01*
G01Y743350D02*
X515567Y742933D01*
X515067Y742683D01*
X514483Y742600D01*
X513817Y742767D01*
X513317Y743183D01*
X512983Y743683D01*
X512900Y744267D01*
X512983Y744850D01*
X513317Y745350D01*
X513817Y745767D01*
X514483Y745933D01*
X515067Y745850D01*
X515483Y745683D01*
X515900Y745350D01*
G01X518750Y743183D02*
X519167Y742850D01*
X519750Y742600D01*
X520250D01*
X520750Y742767D01*
X521083Y743017D01*
X521250Y743350D01*
X521167Y743850D01*
X520833Y744100D01*
X519333Y744600D01*
X519000Y745183D01*
X519167Y745600D01*
X519500Y745850D01*
X520000Y745933D01*
X520500Y745850D01*
X521000Y745600D01*
G01X71000Y756600D02*
X73000D01*
G01X72000D02*
Y751600D01*
G01X71000D02*
X73000D01*
G01X75933D02*
Y756600D01*
X77933D01*
X78600Y756350D01*
X79100Y755767D01*
X79267Y755100D01*
X79100Y754433D01*
X78683Y753933D01*
X77933Y753683D01*
X75933D01*
G01X85033Y756183D02*
X84533Y756433D01*
X83950Y756600D01*
X83283D01*
X82533Y756350D01*
X81950Y755933D01*
X81533Y755433D01*
X81200Y754600D01*
X81117Y753850D01*
X81283Y753100D01*
X81533Y752600D01*
X82033Y752100D01*
X82617Y751767D01*
X83200Y751600D01*
X83783D01*
X84367Y751767D01*
X84867Y752017D01*
X85283Y752350D01*
G01X87717Y753267D02*
X89883D01*
G01X94400Y756600D02*
Y751600D01*
G01X92483Y756600D02*
X96317D01*
G01X97833Y751600D02*
Y756600D01*
X100000Y752433D01*
X102167Y756600D01*
Y751600D01*
G01X104517Y753267D02*
X106683D01*
G01X109617Y753683D02*
X110200Y754267D01*
X110700Y754600D01*
X111367Y754767D01*
X111950Y754600D01*
X112367Y754267D01*
X112700Y753767D01*
X112783Y753183D01*
X112700Y752683D01*
X112367Y752183D01*
X111867Y751767D01*
X111283Y751600D01*
X110617Y751767D01*
X110033Y752267D01*
X109700Y753017D01*
X109617Y753850D01*
X109783Y754933D01*
X110033Y755517D01*
X110450Y756100D01*
X111033Y756517D01*
X111617Y756600D01*
X112200Y756433D01*
X112617Y756017D01*
G01X114967Y752350D02*
X115467Y751933D01*
X116050Y751683D01*
X116800Y751600D01*
X117550Y751767D01*
X118133Y752100D01*
X118550Y752683D01*
X118633Y753350D01*
X118467Y754017D01*
X118050Y754433D01*
X117467Y754767D01*
X116883Y754850D01*
X116300Y754767D01*
X115550Y754433D01*
X115800Y756600D01*
X118050D01*
G01X122400D02*
X121733Y756433D01*
X121233Y756017D01*
X120900Y755517D01*
X120650Y754850D01*
X120567Y754100D01*
X120650Y753350D01*
X120900Y752683D01*
X121233Y752183D01*
X121733Y751767D01*
X122400Y751600D01*
X123067Y751767D01*
X123567Y752183D01*
X123900Y752683D01*
X124150Y753350D01*
X124233Y754100D01*
X124150Y754850D01*
X123900Y755517D01*
X123567Y756017D01*
X123067Y756433D01*
X122400Y756600D01*
G01X133600D02*
Y751600D01*
G01X131683Y756600D02*
X135517D01*
G01X137950Y753850D02*
X140617D01*
X140367Y754433D01*
X139950Y754767D01*
X139367Y754933D01*
X138783Y754850D01*
X138283Y754600D01*
X137950Y754017D01*
X137783Y753517D01*
Y753017D01*
X137950Y752517D01*
X138367Y752017D01*
X138867Y751683D01*
X139450Y751600D01*
X140033Y751767D01*
X140617Y752267D01*
G01X143550Y752183D02*
X143967Y751850D01*
X144550Y751600D01*
X145050D01*
X145550Y751767D01*
X145883Y752017D01*
X146050Y752350D01*
X145967Y752850D01*
X145633Y753100D01*
X144133Y753600D01*
X143800Y754183D01*
X143967Y754600D01*
X144300Y754850D01*
X144800Y754933D01*
X145300Y754850D01*
X145800Y754600D01*
G01X150400Y756600D02*
Y751600D01*
G01X149233Y754933D02*
X151567D01*
G01X159433Y751600D02*
Y756600D01*
X161600Y752433D01*
X163767Y756600D01*
Y751600D01*
G01X165950Y753850D02*
X168617D01*
X168367Y754433D01*
X167950Y754767D01*
X167367Y754933D01*
X166783Y754850D01*
X166283Y754600D01*
X165950Y754017D01*
X165783Y753517D01*
Y753017D01*
X165950Y752517D01*
X166367Y752017D01*
X166867Y751683D01*
X167450Y751600D01*
X168033Y751767D01*
X168617Y752267D01*
G01X172800Y756600D02*
Y751600D01*
G01X171633Y754933D02*
X173967D01*
G01X176983Y751600D02*
Y756600D01*
G01Y754183D02*
X177400Y754600D01*
X177817Y754850D01*
X178483Y754933D01*
X178983Y754850D01*
X179567Y754517D01*
X179817Y754017D01*
Y751600D01*
G01X184000D02*
X183500Y751683D01*
X183000Y752017D01*
X182667Y752600D01*
X182500Y753267D01*
X182667Y753933D01*
X183000Y754517D01*
X183500Y754850D01*
X184000Y754933D01*
X184500Y754850D01*
X185000Y754517D01*
X185333Y753933D01*
X185417Y753267D01*
X185333Y752600D01*
X185000Y752017D01*
X184500Y751683D01*
X184000Y751600D01*
G01X191100Y756600D02*
Y751600D01*
G01Y752350D02*
X190767Y751933D01*
X190267Y751683D01*
X189683Y751600D01*
X189017Y751767D01*
X188517Y752183D01*
X188183Y752683D01*
X188100Y753267D01*
X188183Y753850D01*
X188517Y754350D01*
X189017Y754767D01*
X189683Y754933D01*
X190267Y754850D01*
X190683Y754683D01*
X191100Y754350D01*
G01X193950Y752183D02*
X194367Y751850D01*
X194950Y751600D01*
X195450D01*
X195950Y751767D01*
X196283Y752017D01*
X196450Y752350D01*
X196367Y752850D01*
X196033Y753100D01*
X194533Y753600D01*
X194200Y754183D01*
X194367Y754600D01*
X194700Y754850D01*
X195200Y754933D01*
X195700Y754850D01*
X196200Y754600D01*
G01X204233Y751600D02*
Y756600D01*
X206400Y752433D01*
X208567Y756600D01*
Y751600D01*
G01X213500D02*
Y754933D01*
G01Y754350D02*
X213167Y754683D01*
X212667Y754850D01*
X212083Y754933D01*
X211500Y754767D01*
X211000Y754433D01*
X210667Y753933D01*
X210500Y753267D01*
X210667Y752600D01*
X211000Y752100D01*
X211500Y751767D01*
X212083Y751600D01*
X212667Y751683D01*
X213167Y751933D01*
X213500Y752267D01*
G01X216183Y751600D02*
Y754933D01*
G01Y754100D02*
X216517Y754517D01*
X217017Y754850D01*
X217683Y754933D01*
X218267Y754850D01*
X218767Y754517D01*
X219017Y753933D01*
Y751600D01*
G01X221783Y754933D02*
Y752600D01*
X222117Y752017D01*
X222617Y751683D01*
X223200Y751600D01*
X223783Y751683D01*
X224283Y752017D01*
X224617Y752600D01*
G01Y751600D02*
Y754933D01*
G01X230300Y751600D02*
Y754933D01*
G01Y754350D02*
X229967Y754683D01*
X229467Y754850D01*
X228883Y754933D01*
X228300Y754767D01*
X227800Y754433D01*
X227467Y753933D01*
X227300Y753267D01*
X227467Y752600D01*
X227800Y752100D01*
X228300Y751767D01*
X228883Y751600D01*
X229467Y751683D01*
X229967Y751933D01*
X230300Y752267D01*
G01X234400Y751600D02*
Y756600D01*
G01X71000Y765600D02*
X73000D01*
G01X72000D02*
Y760600D01*
G01X71000D02*
X73000D01*
G01X75933D02*
Y765600D01*
X77933D01*
X78600Y765350D01*
X79100Y764767D01*
X79267Y764100D01*
X79100Y763433D01*
X78683Y762933D01*
X77933Y762683D01*
X75933D01*
G01X85033Y765183D02*
X84533Y765433D01*
X83950Y765600D01*
X83283D01*
X82533Y765350D01*
X81950Y764933D01*
X81533Y764433D01*
X81200Y763600D01*
X81117Y762850D01*
X81283Y762100D01*
X81533Y761600D01*
X82033Y761100D01*
X82617Y760767D01*
X83200Y760600D01*
X83783D01*
X84367Y760767D01*
X84867Y761017D01*
X85283Y761350D01*
G01X87717Y762267D02*
X89883D01*
G01X92817Y762683D02*
X93400Y763267D01*
X93900Y763600D01*
X94567Y763767D01*
X95150Y763600D01*
X95567Y763267D01*
X95900Y762767D01*
X95983Y762183D01*
X95900Y761683D01*
X95567Y761183D01*
X95067Y760767D01*
X94483Y760600D01*
X93817Y760767D01*
X93233Y761267D01*
X92900Y762017D01*
X92817Y762850D01*
X92983Y763933D01*
X93233Y764517D01*
X93650Y765100D01*
X94233Y765517D01*
X94817Y765600D01*
X95400Y765433D01*
X95817Y765017D01*
G01X100000Y765600D02*
X99333Y765433D01*
X98833Y765017D01*
X98500Y764517D01*
X98250Y763850D01*
X98167Y763100D01*
X98250Y762350D01*
X98500Y761683D01*
X98833Y761183D01*
X99333Y760767D01*
X100000Y760600D01*
X100667Y760767D01*
X101167Y761183D01*
X101500Y761683D01*
X101750Y762350D01*
X101833Y763100D01*
X101750Y763850D01*
X101500Y764517D01*
X101167Y765017D01*
X100667Y765433D01*
X100000Y765600D01*
G01X105600Y760600D02*
Y765600D01*
X104600Y764600D01*
G01Y760600D02*
X106600D01*
G01X109617Y762683D02*
X110200Y763267D01*
X110700Y763600D01*
X111367Y763767D01*
X111950Y763600D01*
X112367Y763267D01*
X112700Y762767D01*
X112783Y762183D01*
X112700Y761683D01*
X112367Y761183D01*
X111867Y760767D01*
X111283Y760600D01*
X110617Y760767D01*
X110033Y761267D01*
X109700Y762017D01*
X109617Y762850D01*
X109783Y763933D01*
X110033Y764517D01*
X110450Y765100D01*
X111033Y765517D01*
X111617Y765600D01*
X112200Y765433D01*
X112617Y765017D01*
G01X122400Y760600D02*
X121733Y760683D01*
X121150Y761017D01*
X120650Y761517D01*
X120317Y762100D01*
X120150Y762767D01*
Y763433D01*
X120317Y764100D01*
X120650Y764683D01*
X121150Y765183D01*
X121733Y765517D01*
X122400Y765600D01*
X123067Y765517D01*
X123650Y765183D01*
X124150Y764683D01*
X124483Y764100D01*
X124650Y763433D01*
Y762767D01*
X124483Y762100D01*
X124150Y761517D01*
X123650Y761017D01*
X123067Y760683D01*
X122400Y760600D01*
G01X123067Y761933D02*
X124067Y760600D01*
G01X126583Y763933D02*
Y761600D01*
X126917Y761017D01*
X127417Y760683D01*
X128000Y760600D01*
X128583Y760683D01*
X129083Y761017D01*
X129417Y761600D01*
G01Y760600D02*
Y763933D01*
G01X135100Y760600D02*
Y763933D01*
G01Y763350D02*
X134767Y763683D01*
X134267Y763850D01*
X133683Y763933D01*
X133100Y763767D01*
X132600Y763433D01*
X132267Y762933D01*
X132100Y762267D01*
X132267Y761600D01*
X132600Y761100D01*
X133100Y760767D01*
X133683Y760600D01*
X134267Y760683D01*
X134767Y760933D01*
X135100Y761267D01*
G01X139200Y760600D02*
Y765600D01*
G01X144800Y763933D02*
Y760600D01*
G01Y765267D02*
X144633Y765350D01*
Y765517D01*
X144800Y765600D01*
X144967Y765517D01*
Y765350D01*
X144800Y765267D01*
G01X149900Y760600D02*
Y764850D01*
X150067Y765267D01*
X150400Y765517D01*
X150900Y765600D01*
X151400Y765433D01*
X151650Y765017D01*
G01X150650Y763600D02*
X148983D01*
G01X156000Y763933D02*
Y760600D01*
G01Y765267D02*
X155833Y765350D01*
Y765517D01*
X156000Y765600D01*
X156167Y765517D01*
Y765350D01*
X156000Y765267D01*
G01X162933Y763517D02*
X162350Y763850D01*
X161850Y763933D01*
X161183Y763767D01*
X160683Y763433D01*
X160350Y762850D01*
X160267Y762267D01*
X160350Y761683D01*
X160683Y761183D01*
X161183Y760767D01*
X161850Y760600D01*
X162433Y760767D01*
X162933Y761100D01*
G01X168700Y760600D02*
Y763933D01*
G01Y763350D02*
X168367Y763683D01*
X167867Y763850D01*
X167283Y763933D01*
X166700Y763767D01*
X166200Y763433D01*
X165867Y762933D01*
X165700Y762267D01*
X165867Y761600D01*
X166200Y761100D01*
X166700Y760767D01*
X167283Y760600D01*
X167867Y760683D01*
X168367Y760933D01*
X168700Y761267D01*
G01X172800Y765600D02*
Y760600D01*
G01X171633Y763933D02*
X173967D01*
G01X178400D02*
Y760600D01*
G01Y765267D02*
X178233Y765350D01*
Y765517D01*
X178400Y765600D01*
X178567Y765517D01*
Y765350D01*
X178400Y765267D01*
G01X184000Y760600D02*
X183500Y760683D01*
X183000Y761017D01*
X182667Y761600D01*
X182500Y762267D01*
X182667Y762933D01*
X183000Y763517D01*
X183500Y763850D01*
X184000Y763933D01*
X184500Y763850D01*
X185000Y763517D01*
X185333Y762933D01*
X185417Y762267D01*
X185333Y761600D01*
X185000Y761017D01*
X184500Y760683D01*
X184000Y760600D01*
G01X188183D02*
Y763933D01*
G01Y763100D02*
X188517Y763517D01*
X189017Y763850D01*
X189683Y763933D01*
X190267Y763850D01*
X190767Y763517D01*
X191017Y762933D01*
Y760600D01*
G01X203300Y758933D02*
X199133Y763933D01*
Y764767D01*
X199967Y765600D01*
X200800D01*
X201633Y764767D01*
Y763933D01*
X200800Y763100D01*
X199133Y762267D01*
X198300Y761433D01*
Y759767D01*
X199133Y758933D01*
X201633D01*
X203300Y760600D01*
G01X210333D02*
Y765600D01*
X212333D01*
X213000Y765350D01*
X213500Y764767D01*
X213667Y764100D01*
X213500Y763433D01*
X213083Y762933D01*
X212333Y762683D01*
X210333D01*
G01X216350Y762850D02*
X219017D01*
X218767Y763433D01*
X218350Y763767D01*
X217767Y763933D01*
X217183Y763850D01*
X216683Y763600D01*
X216350Y763017D01*
X216183Y762517D01*
Y762017D01*
X216350Y761517D01*
X216767Y761017D01*
X217267Y760683D01*
X217850Y760600D01*
X218433Y760767D01*
X219017Y761267D01*
G01X222033Y760600D02*
Y763933D01*
G01Y763267D02*
X222450Y763600D01*
X222867Y763850D01*
X223450Y763933D01*
X223867Y763850D01*
X224367Y763600D01*
G01X228300Y760600D02*
Y764850D01*
X228467Y765267D01*
X228800Y765517D01*
X229300Y765600D01*
X229800Y765433D01*
X230050Y765017D01*
G01X229050Y763600D02*
X227383D01*
G01X234400Y760600D02*
X233900Y760683D01*
X233400Y761017D01*
X233067Y761600D01*
X232900Y762267D01*
X233067Y762933D01*
X233400Y763517D01*
X233900Y763850D01*
X234400Y763933D01*
X234900Y763850D01*
X235400Y763517D01*
X235733Y762933D01*
X235817Y762267D01*
X235733Y761600D01*
X235400Y761017D01*
X234900Y760683D01*
X234400Y760600D01*
G01X238833D02*
Y763933D01*
G01Y763267D02*
X239250Y763600D01*
X239667Y763850D01*
X240250Y763933D01*
X240667Y763850D01*
X241167Y763600D01*
G01X243100Y760600D02*
Y763933D01*
G01Y763017D02*
X243350Y763433D01*
X243767Y763767D01*
X244350Y763933D01*
X244933Y763767D01*
X245350Y763433D01*
X245600Y763017D01*
Y760600D01*
G01Y763017D02*
X245850Y763433D01*
X246267Y763767D01*
X246850Y763933D01*
X247433Y763767D01*
X247850Y763433D01*
X248100Y762933D01*
Y760600D01*
G01X252700D02*
Y763933D01*
G01Y763350D02*
X252367Y763683D01*
X251867Y763850D01*
X251283Y763933D01*
X250700Y763767D01*
X250200Y763433D01*
X249867Y762933D01*
X249700Y762267D01*
X249867Y761600D01*
X250200Y761100D01*
X250700Y760767D01*
X251283Y760600D01*
X251867Y760683D01*
X252367Y760933D01*
X252700Y761267D01*
G01X255383Y760600D02*
Y763933D01*
G01Y763100D02*
X255717Y763517D01*
X256217Y763850D01*
X256883Y763933D01*
X257467Y763850D01*
X257967Y763517D01*
X258217Y762933D01*
Y760600D01*
G01X263733Y763517D02*
X263150Y763850D01*
X262650Y763933D01*
X261983Y763767D01*
X261483Y763433D01*
X261150Y762850D01*
X261067Y762267D01*
X261150Y761683D01*
X261483Y761183D01*
X261983Y760767D01*
X262650Y760600D01*
X263233Y760767D01*
X263733Y761100D01*
G01X266750Y762850D02*
X269417D01*
X269167Y763433D01*
X268750Y763767D01*
X268167Y763933D01*
X267583Y763850D01*
X267083Y763600D01*
X266750Y763017D01*
X266583Y762517D01*
Y762017D01*
X266750Y761517D01*
X267167Y761017D01*
X267667Y760683D01*
X268250Y760600D01*
X268833Y760767D01*
X269417Y761267D01*
G01X277450D02*
X278117Y760850D01*
X278867Y760600D01*
X279533D01*
X280200Y760850D01*
X280700Y761267D01*
X280950Y761850D01*
X280783Y762433D01*
X280367Y762933D01*
X279617Y763267D01*
X278617Y763433D01*
X278033Y763767D01*
X277783Y764350D01*
X277950Y764933D01*
X278367Y765350D01*
X278950Y765600D01*
X279533D01*
X280117Y765433D01*
X280617Y765017D01*
G01X283300Y758933D02*
Y763933D01*
G01Y763183D02*
X283717Y763600D01*
X284133Y763850D01*
X284800Y763933D01*
X285383Y763850D01*
X285967Y763433D01*
X286217Y762850D01*
X286300Y762267D01*
X286217Y761683D01*
X285967Y761100D01*
X285467Y760767D01*
X284800Y760600D01*
X284217Y760683D01*
X283633Y760933D01*
X283300Y761267D01*
G01X289150Y762850D02*
X291817D01*
X291567Y763433D01*
X291150Y763767D01*
X290567Y763933D01*
X289983Y763850D01*
X289483Y763600D01*
X289150Y763017D01*
X288983Y762517D01*
Y762017D01*
X289150Y761517D01*
X289567Y761017D01*
X290067Y760683D01*
X290650Y760600D01*
X291233Y760767D01*
X291817Y761267D01*
G01X297333Y763517D02*
X296750Y763850D01*
X296250Y763933D01*
X295583Y763767D01*
X295083Y763433D01*
X294750Y762850D01*
X294667Y762267D01*
X294750Y761683D01*
X295083Y761183D01*
X295583Y760767D01*
X296250Y760600D01*
X296833Y760767D01*
X297333Y761100D01*
G01X301600Y763933D02*
Y760600D01*
G01Y765267D02*
X301433Y765350D01*
Y765517D01*
X301600Y765600D01*
X301767Y765517D01*
Y765350D01*
X301600Y765267D01*
G01X306700Y760600D02*
Y764850D01*
X306867Y765267D01*
X307200Y765517D01*
X307700Y765600D01*
X308200Y765433D01*
X308450Y765017D01*
G01X307450Y763600D02*
X305783D01*
G01X312800Y763933D02*
Y760600D01*
G01Y765267D02*
X312633Y765350D01*
Y765517D01*
X312800Y765600D01*
X312967Y765517D01*
Y765350D01*
X312800Y765267D01*
G01X319733Y763517D02*
X319150Y763850D01*
X318650Y763933D01*
X317983Y763767D01*
X317483Y763433D01*
X317150Y762850D01*
X317067Y762267D01*
X317150Y761683D01*
X317483Y761183D01*
X317983Y760767D01*
X318650Y760600D01*
X319233Y760767D01*
X319733Y761100D01*
G01X325500Y760600D02*
Y763933D01*
G01Y763350D02*
X325167Y763683D01*
X324667Y763850D01*
X324083Y763933D01*
X323500Y763767D01*
X323000Y763433D01*
X322667Y762933D01*
X322500Y762267D01*
X322667Y761600D01*
X323000Y761100D01*
X323500Y760767D01*
X324083Y760600D01*
X324667Y760683D01*
X325167Y760933D01*
X325500Y761267D01*
G01X329600Y765600D02*
Y760600D01*
G01X328433Y763933D02*
X330767D01*
G01X335200D02*
Y760600D01*
G01Y765267D02*
X335033Y765350D01*
Y765517D01*
X335200Y765600D01*
X335367Y765517D01*
Y765350D01*
X335200Y765267D01*
G01X340800Y760600D02*
X340300Y760683D01*
X339800Y761017D01*
X339467Y761600D01*
X339300Y762267D01*
X339467Y762933D01*
X339800Y763517D01*
X340300Y763850D01*
X340800Y763933D01*
X341300Y763850D01*
X341800Y763517D01*
X342133Y762933D01*
X342217Y762267D01*
X342133Y761600D01*
X341800Y761017D01*
X341300Y760683D01*
X340800Y760600D01*
G01X344983D02*
Y763933D01*
G01Y763100D02*
X345317Y763517D01*
X345817Y763850D01*
X346483Y763933D01*
X347067Y763850D01*
X347567Y763517D01*
X347817Y762933D01*
Y760600D01*
G01X357100D02*
Y764850D01*
X357267Y765267D01*
X357600Y765517D01*
X358100Y765600D01*
X358600Y765433D01*
X358850Y765017D01*
G01X357850Y763600D02*
X356183D01*
G01X363200Y760600D02*
X362700Y760683D01*
X362200Y761017D01*
X361867Y761600D01*
X361700Y762267D01*
X361867Y762933D01*
X362200Y763517D01*
X362700Y763850D01*
X363200Y763933D01*
X363700Y763850D01*
X364200Y763517D01*
X364533Y762933D01*
X364617Y762267D01*
X364533Y761600D01*
X364200Y761017D01*
X363700Y760683D01*
X363200Y760600D01*
G01X367633D02*
Y763933D01*
G01Y763267D02*
X368050Y763600D01*
X368467Y763850D01*
X369050Y763933D01*
X369467Y763850D01*
X369967Y763600D01*
G01X378250Y760600D02*
Y765600D01*
G01X381750D02*
Y760600D01*
G01Y763100D02*
X378250D01*
G01X385600Y763933D02*
Y760600D01*
G01Y765267D02*
X385433Y765350D01*
Y765517D01*
X385600Y765600D01*
X385767Y765517D01*
Y765350D01*
X385600Y765267D01*
G01X390033Y759350D02*
X390617Y759017D01*
X391283Y758933D01*
X391867Y759017D01*
X392367Y759433D01*
X392700Y760017D01*
Y763933D01*
G01Y763267D02*
X392367Y763600D01*
X391867Y763850D01*
X391283Y763933D01*
X390617Y763767D01*
X390200Y763433D01*
X389867Y762850D01*
X389700Y762267D01*
X389783Y761767D01*
X390117Y761183D01*
X390617Y760767D01*
X391283Y760600D01*
X391783Y760683D01*
X392367Y761017D01*
X392700Y761350D01*
G01X395383Y760600D02*
Y765600D01*
G01Y763183D02*
X395800Y763600D01*
X396217Y763850D01*
X396883Y763933D01*
X397383Y763850D01*
X397967Y763517D01*
X398217Y763017D01*
Y760600D01*
G01X406167D02*
Y765600D01*
X407833D01*
X408500Y765350D01*
X409000Y765017D01*
X409417Y764517D01*
X409750Y763933D01*
X409833Y763100D01*
X409750Y762267D01*
X409417Y761683D01*
X409000Y761183D01*
X408500Y760850D01*
X407833Y760600D01*
X406167D01*
G01X412350Y762850D02*
X415017D01*
X414767Y763433D01*
X414350Y763767D01*
X413767Y763933D01*
X413183Y763850D01*
X412683Y763600D01*
X412350Y763017D01*
X412183Y762517D01*
Y762017D01*
X412350Y761517D01*
X412767Y761017D01*
X413267Y760683D01*
X413850Y760600D01*
X414433Y760767D01*
X415017Y761267D01*
G01X417783Y760600D02*
Y763933D01*
G01Y763100D02*
X418117Y763517D01*
X418617Y763850D01*
X419283Y763933D01*
X419867Y763850D01*
X420367Y763517D01*
X420617Y762933D01*
Y760600D01*
G01X423550Y761183D02*
X423967Y760850D01*
X424550Y760600D01*
X425050D01*
X425550Y760767D01*
X425883Y761017D01*
X426050Y761350D01*
X425967Y761850D01*
X425633Y762100D01*
X424133Y762600D01*
X423800Y763183D01*
X423967Y763600D01*
X424300Y763850D01*
X424800Y763933D01*
X425300Y763850D01*
X425800Y763600D01*
G01X430400Y763933D02*
Y760600D01*
G01Y765267D02*
X430233Y765350D01*
Y765517D01*
X430400Y765600D01*
X430567Y765517D01*
Y765350D01*
X430400Y765267D01*
G01X436000Y765600D02*
Y760600D01*
G01X434833Y763933D02*
X437167D01*
G01X439850Y759100D02*
X440350Y758933D01*
X441017Y759100D01*
X441433Y759433D01*
X441767Y759850D01*
X442267Y761183D01*
X443350Y763933D01*
G01X440683D02*
X442267Y761183D01*
G01X451800Y765600D02*
X453800D01*
G01X452800D02*
Y760600D01*
G01X451800D02*
X453800D01*
G01X456983D02*
Y763933D01*
G01Y763100D02*
X457317Y763517D01*
X457817Y763850D01*
X458483Y763933D01*
X459067Y763850D01*
X459567Y763517D01*
X459817Y762933D01*
Y760600D01*
G01X464000Y765600D02*
Y760600D01*
G01X462833Y763933D02*
X465167D01*
G01X468350Y762850D02*
X471017D01*
X470767Y763433D01*
X470350Y763767D01*
X469767Y763933D01*
X469183Y763850D01*
X468683Y763600D01*
X468350Y763017D01*
X468183Y762517D01*
Y762017D01*
X468350Y761517D01*
X468767Y761017D01*
X469267Y760683D01*
X469850Y760600D01*
X470433Y760767D01*
X471017Y761267D01*
G01X474033Y760600D02*
Y763933D01*
G01Y763267D02*
X474450Y763600D01*
X474867Y763850D01*
X475450Y763933D01*
X475867Y763850D01*
X476367Y763600D01*
G01X482133Y763517D02*
X481550Y763850D01*
X481050Y763933D01*
X480383Y763767D01*
X479883Y763433D01*
X479550Y762850D01*
X479467Y762267D01*
X479550Y761683D01*
X479883Y761183D01*
X480383Y760767D01*
X481050Y760600D01*
X481633Y760767D01*
X482133Y761100D01*
G01X486400Y760600D02*
X485900Y760683D01*
X485400Y761017D01*
X485067Y761600D01*
X484900Y762267D01*
X485067Y762933D01*
X485400Y763517D01*
X485900Y763850D01*
X486400Y763933D01*
X486900Y763850D01*
X487400Y763517D01*
X487733Y762933D01*
X487817Y762267D01*
X487733Y761600D01*
X487400Y761017D01*
X486900Y760683D01*
X486400Y760600D01*
G01X490583D02*
Y763933D01*
G01Y763100D02*
X490917Y763517D01*
X491417Y763850D01*
X492083Y763933D01*
X492667Y763850D01*
X493167Y763517D01*
X493417Y762933D01*
Y760600D01*
G01X496183D02*
Y763933D01*
G01Y763100D02*
X496517Y763517D01*
X497017Y763850D01*
X497683Y763933D01*
X498267Y763850D01*
X498767Y763517D01*
X499017Y762933D01*
Y760600D01*
G01X501950Y762850D02*
X504617D01*
X504367Y763433D01*
X503950Y763767D01*
X503367Y763933D01*
X502783Y763850D01*
X502283Y763600D01*
X501950Y763017D01*
X501783Y762517D01*
Y762017D01*
X501950Y761517D01*
X502367Y761017D01*
X502867Y760683D01*
X503450Y760600D01*
X504033Y760767D01*
X504617Y761267D01*
G01X510133Y763517D02*
X509550Y763850D01*
X509050Y763933D01*
X508383Y763767D01*
X507883Y763433D01*
X507550Y762850D01*
X507467Y762267D01*
X507550Y761683D01*
X507883Y761183D01*
X508383Y760767D01*
X509050Y760600D01*
X509633Y760767D01*
X510133Y761100D01*
G01X514400Y765600D02*
Y760600D01*
G01X513233Y763933D02*
X515567D01*
G01X519583Y758933D02*
X518750Y759767D01*
X518333Y760600D01*
Y763933D01*
X518750Y764767D01*
X519583Y765600D01*
G01X523850Y760600D02*
Y765600D01*
G01X527350D02*
Y760600D01*
G01Y763100D02*
X523850D01*
G01X529367Y760600D02*
Y765600D01*
X531033D01*
X531700Y765350D01*
X532200Y765017D01*
X532617Y764517D01*
X532950Y763933D01*
X533033Y763100D01*
X532950Y762267D01*
X532617Y761683D01*
X532200Y761183D01*
X531700Y760850D01*
X531033Y760600D01*
X529367D01*
G01X535800Y765600D02*
X537800D01*
G01X536800D02*
Y760600D01*
G01X535800D02*
X537800D01*
G01X542817Y758933D02*
X543650Y759767D01*
X544067Y760600D01*
Y763933D01*
X543650Y764767D01*
X542817Y765600D01*
G01X551933D02*
Y760600D01*
X555267D01*
G01X560700D02*
Y763933D01*
G01Y763350D02*
X560367Y763683D01*
X559867Y763850D01*
X559283Y763933D01*
X558700Y763767D01*
X558200Y763433D01*
X557867Y762933D01*
X557700Y762267D01*
X557867Y761600D01*
X558200Y761100D01*
X558700Y760767D01*
X559283Y760600D01*
X559867Y760683D01*
X560367Y760933D01*
X560700Y761267D01*
G01X563050Y759100D02*
X563550Y758933D01*
X564217Y759100D01*
X564633Y759433D01*
X564967Y759850D01*
X565467Y761183D01*
X566550Y763933D01*
G01X563883D02*
X565467Y761183D01*
G01X569150Y762850D02*
X571817D01*
X571567Y763433D01*
X571150Y763767D01*
X570567Y763933D01*
X569983Y763850D01*
X569483Y763600D01*
X569150Y763017D01*
X568983Y762517D01*
Y762017D01*
X569150Y761517D01*
X569567Y761017D01*
X570067Y760683D01*
X570650Y760600D01*
X571233Y760767D01*
X571817Y761267D01*
G01X574833Y760600D02*
Y763933D01*
G01Y763267D02*
X575250Y763600D01*
X575667Y763850D01*
X576250Y763933D01*
X576667Y763850D01*
X577167Y763600D01*
G01X580350Y761183D02*
X580767Y760850D01*
X581350Y760600D01*
X581850D01*
X582350Y760767D01*
X582683Y761017D01*
X582850Y761350D01*
X582767Y761850D01*
X582433Y762100D01*
X580933Y762600D01*
X580600Y763183D01*
X580767Y763600D01*
X581100Y763850D01*
X581600Y763933D01*
X582100Y763850D01*
X582600Y763600D01*
G01X592800Y760600D02*
X592300Y760683D01*
X591800Y761017D01*
X591467Y761600D01*
X591300Y762267D01*
X591467Y762933D01*
X591800Y763517D01*
X592300Y763850D01*
X592800Y763933D01*
X593300Y763850D01*
X593800Y763517D01*
X594133Y762933D01*
X594217Y762267D01*
X594133Y761600D01*
X593800Y761017D01*
X593300Y760683D01*
X592800Y760600D01*
G01X597233D02*
Y763933D01*
G01Y763267D02*
X597650Y763600D01*
X598067Y763850D01*
X598650Y763933D01*
X599067Y763850D01*
X599567Y763600D01*
G01X610267Y763267D02*
X610600Y763517D01*
X610850Y763933D01*
X611017Y764517D01*
X610850Y765017D01*
X610517Y765350D01*
X609933Y765600D01*
X607683D01*
Y760600D01*
X610433D01*
X611017Y760933D01*
X611350Y761433D01*
X611517Y762017D01*
X611350Y762600D01*
X610850Y763100D01*
X610267Y763267D01*
X607683D01*
G01X615200Y760600D02*
X614700Y760683D01*
X614200Y761017D01*
X613867Y761600D01*
X613700Y762267D01*
X613867Y762933D01*
X614200Y763517D01*
X614700Y763850D01*
X615200Y763933D01*
X615700Y763850D01*
X616200Y763517D01*
X616533Y762933D01*
X616617Y762267D01*
X616533Y761600D01*
X616200Y761017D01*
X615700Y760683D01*
X615200Y760600D01*
G01X622300D02*
Y763933D01*
G01Y763350D02*
X621967Y763683D01*
X621467Y763850D01*
X620883Y763933D01*
X620300Y763767D01*
X619800Y763433D01*
X619467Y762933D01*
X619300Y762267D01*
X619467Y761600D01*
X619800Y761100D01*
X620300Y760767D01*
X620883Y760600D01*
X621467Y760683D01*
X621967Y760933D01*
X622300Y761267D01*
G01X625233Y760600D02*
Y763933D01*
G01Y763267D02*
X625650Y763600D01*
X626067Y763850D01*
X626650Y763933D01*
X627067Y763850D01*
X627567Y763600D01*
G01X633500Y765600D02*
Y760600D01*
G01Y761350D02*
X633167Y760933D01*
X632667Y760683D01*
X632083Y760600D01*
X631417Y760767D01*
X630917Y761183D01*
X630583Y761683D01*
X630500Y762267D01*
X630583Y762850D01*
X630917Y763350D01*
X631417Y763767D01*
X632083Y763933D01*
X632667Y763850D01*
X633083Y763683D01*
X633500Y763350D01*
G01X636350Y761183D02*
X636767Y760850D01*
X637350Y760600D01*
X637850D01*
X638350Y760767D01*
X638683Y761017D01*
X638850Y761350D01*
X638767Y761850D01*
X638433Y762100D01*
X636933Y762600D01*
X636600Y763183D01*
X636767Y763600D01*
X637100Y763850D01*
X637600Y763933D01*
X638100Y763850D01*
X638600Y763600D01*
G01X643617Y758933D02*
X644450Y759767D01*
X644867Y760600D01*
Y763933D01*
X644450Y764767D01*
X643617Y765600D01*
G01X71000Y774600D02*
X73000D01*
G01X72000D02*
Y769600D01*
G01X71000D02*
X73000D01*
G01X75933D02*
Y774600D01*
X77933D01*
X78600Y774350D01*
X79100Y773767D01*
X79267Y773100D01*
X79100Y772433D01*
X78683Y771933D01*
X77933Y771683D01*
X75933D01*
G01X85033Y774183D02*
X84533Y774433D01*
X83950Y774600D01*
X83283D01*
X82533Y774350D01*
X81950Y773933D01*
X81533Y773433D01*
X81200Y772600D01*
X81117Y771850D01*
X81283Y771100D01*
X81533Y770600D01*
X82033Y770100D01*
X82617Y769767D01*
X83200Y769600D01*
X83783D01*
X84367Y769767D01*
X84867Y770017D01*
X85283Y770350D01*
G01X87717Y771267D02*
X89883D01*
G01X92817Y771683D02*
X93400Y772267D01*
X93900Y772600D01*
X94567Y772767D01*
X95150Y772600D01*
X95567Y772267D01*
X95900Y771767D01*
X95983Y771183D01*
X95900Y770683D01*
X95567Y770183D01*
X95067Y769767D01*
X94483Y769600D01*
X93817Y769767D01*
X93233Y770267D01*
X92900Y771017D01*
X92817Y771850D01*
X92983Y772933D01*
X93233Y773517D01*
X93650Y774100D01*
X94233Y774517D01*
X94817Y774600D01*
X95400Y774433D01*
X95817Y774017D01*
G01X100000Y774600D02*
X99333Y774433D01*
X98833Y774017D01*
X98500Y773517D01*
X98250Y772850D01*
X98167Y772100D01*
X98250Y771350D01*
X98500Y770683D01*
X98833Y770183D01*
X99333Y769767D01*
X100000Y769600D01*
X100667Y769767D01*
X101167Y770183D01*
X101500Y770683D01*
X101750Y771350D01*
X101833Y772100D01*
X101750Y772850D01*
X101500Y773517D01*
X101167Y774017D01*
X100667Y774433D01*
X100000Y774600D01*
G01X105600Y769600D02*
Y774600D01*
X104600Y773600D01*
G01Y769600D02*
X106600D01*
G01X109617Y773767D02*
X110117Y774267D01*
X110700Y774517D01*
X111367Y774600D01*
X112200Y774433D01*
X112783Y774017D01*
X112950Y773517D01*
X112867Y773017D01*
X112533Y772600D01*
X110867Y771767D01*
X110117Y771183D01*
X109617Y770350D01*
X109450Y769600D01*
X112950D01*
G01X122400D02*
X121733Y769683D01*
X121150Y770017D01*
X120650Y770517D01*
X120317Y771100D01*
X120150Y771767D01*
Y772433D01*
X120317Y773100D01*
X120650Y773683D01*
X121150Y774183D01*
X121733Y774517D01*
X122400Y774600D01*
X123067Y774517D01*
X123650Y774183D01*
X124150Y773683D01*
X124483Y773100D01*
X124650Y772433D01*
Y771767D01*
X124483Y771100D01*
X124150Y770517D01*
X123650Y770017D01*
X123067Y769683D01*
X122400Y769600D01*
G01X123067Y770933D02*
X124067Y769600D01*
G01X126583Y772933D02*
Y770600D01*
X126917Y770017D01*
X127417Y769683D01*
X128000Y769600D01*
X128583Y769683D01*
X129083Y770017D01*
X129417Y770600D01*
G01Y769600D02*
Y772933D01*
G01X135100Y769600D02*
Y772933D01*
G01Y772350D02*
X134767Y772683D01*
X134267Y772850D01*
X133683Y772933D01*
X133100Y772767D01*
X132600Y772433D01*
X132267Y771933D01*
X132100Y771267D01*
X132267Y770600D01*
X132600Y770100D01*
X133100Y769767D01*
X133683Y769600D01*
X134267Y769683D01*
X134767Y769933D01*
X135100Y770267D01*
G01X139200Y769600D02*
Y774600D01*
G01X144800Y772933D02*
Y769600D01*
G01Y774267D02*
X144633Y774350D01*
Y774517D01*
X144800Y774600D01*
X144967Y774517D01*
Y774350D01*
X144800Y774267D01*
G01X149900Y769600D02*
Y773850D01*
X150067Y774267D01*
X150400Y774517D01*
X150900Y774600D01*
X151400Y774433D01*
X151650Y774017D01*
G01X150650Y772600D02*
X148983D01*
G01X156000Y772933D02*
Y769600D01*
G01Y774267D02*
X155833Y774350D01*
Y774517D01*
X156000Y774600D01*
X156167Y774517D01*
Y774350D01*
X156000Y774267D01*
G01X162933Y772517D02*
X162350Y772850D01*
X161850Y772933D01*
X161183Y772767D01*
X160683Y772433D01*
X160350Y771850D01*
X160267Y771267D01*
X160350Y770683D01*
X160683Y770183D01*
X161183Y769767D01*
X161850Y769600D01*
X162433Y769767D01*
X162933Y770100D01*
G01X168700Y769600D02*
Y772933D01*
G01Y772350D02*
X168367Y772683D01*
X167867Y772850D01*
X167283Y772933D01*
X166700Y772767D01*
X166200Y772433D01*
X165867Y771933D01*
X165700Y771267D01*
X165867Y770600D01*
X166200Y770100D01*
X166700Y769767D01*
X167283Y769600D01*
X167867Y769683D01*
X168367Y769933D01*
X168700Y770267D01*
G01X172800Y774600D02*
Y769600D01*
G01X171633Y772933D02*
X173967D01*
G01X178400D02*
Y769600D01*
G01Y774267D02*
X178233Y774350D01*
Y774517D01*
X178400Y774600D01*
X178567Y774517D01*
Y774350D01*
X178400Y774267D01*
G01X184000Y769600D02*
X183500Y769683D01*
X183000Y770017D01*
X182667Y770600D01*
X182500Y771267D01*
X182667Y771933D01*
X183000Y772517D01*
X183500Y772850D01*
X184000Y772933D01*
X184500Y772850D01*
X185000Y772517D01*
X185333Y771933D01*
X185417Y771267D01*
X185333Y770600D01*
X185000Y770017D01*
X184500Y769683D01*
X184000Y769600D01*
G01X188183D02*
Y772933D01*
G01Y772100D02*
X188517Y772517D01*
X189017Y772850D01*
X189683Y772933D01*
X190267Y772850D01*
X190767Y772517D01*
X191017Y771933D01*
Y769600D01*
G01X202300D02*
Y772933D01*
G01Y772350D02*
X201967Y772683D01*
X201467Y772850D01*
X200883Y772933D01*
X200300Y772767D01*
X199800Y772433D01*
X199467Y771933D01*
X199300Y771267D01*
X199467Y770600D01*
X199800Y770100D01*
X200300Y769767D01*
X200883Y769600D01*
X201467Y769683D01*
X201967Y769933D01*
X202300Y770267D01*
G01X204983Y769600D02*
Y772933D01*
G01Y772100D02*
X205317Y772517D01*
X205817Y772850D01*
X206483Y772933D01*
X207067Y772850D01*
X207567Y772517D01*
X207817Y771933D01*
Y769600D01*
G01X213500Y774600D02*
Y769600D01*
G01Y770350D02*
X213167Y769933D01*
X212667Y769683D01*
X212083Y769600D01*
X211417Y769767D01*
X210917Y770183D01*
X210583Y770683D01*
X210500Y771267D01*
X210583Y771850D01*
X210917Y772350D01*
X211417Y772767D01*
X212083Y772933D01*
X212667Y772850D01*
X213083Y772683D01*
X213500Y772350D01*
G01X221533Y769600D02*
Y774600D01*
X223533D01*
X224200Y774350D01*
X224700Y773767D01*
X224867Y773100D01*
X224700Y772433D01*
X224283Y771933D01*
X223533Y771683D01*
X221533D01*
G01X227550Y771850D02*
X230217D01*
X229967Y772433D01*
X229550Y772767D01*
X228967Y772933D01*
X228383Y772850D01*
X227883Y772600D01*
X227550Y772017D01*
X227383Y771517D01*
Y771017D01*
X227550Y770517D01*
X227967Y770017D01*
X228467Y769683D01*
X229050Y769600D01*
X229633Y769767D01*
X230217Y770267D01*
G01X233233Y769600D02*
Y772933D01*
G01Y772267D02*
X233650Y772600D01*
X234067Y772850D01*
X234650Y772933D01*
X235067Y772850D01*
X235567Y772600D01*
G01X239500Y769600D02*
Y773850D01*
X239667Y774267D01*
X240000Y774517D01*
X240500Y774600D01*
X241000Y774433D01*
X241250Y774017D01*
G01X240250Y772600D02*
X238583D01*
G01X245600Y769600D02*
X245100Y769683D01*
X244600Y770017D01*
X244267Y770600D01*
X244100Y771267D01*
X244267Y771933D01*
X244600Y772517D01*
X245100Y772850D01*
X245600Y772933D01*
X246100Y772850D01*
X246600Y772517D01*
X246933Y771933D01*
X247017Y771267D01*
X246933Y770600D01*
X246600Y770017D01*
X246100Y769683D01*
X245600Y769600D01*
G01X250033D02*
Y772933D01*
G01Y772267D02*
X250450Y772600D01*
X250867Y772850D01*
X251450Y772933D01*
X251867Y772850D01*
X252367Y772600D01*
G01X254300Y769600D02*
Y772933D01*
G01Y772017D02*
X254550Y772433D01*
X254967Y772767D01*
X255550Y772933D01*
X256133Y772767D01*
X256550Y772433D01*
X256800Y772017D01*
Y769600D01*
G01Y772017D02*
X257050Y772433D01*
X257467Y772767D01*
X258050Y772933D01*
X258633Y772767D01*
X259050Y772433D01*
X259300Y771933D01*
Y769600D01*
G01X263900D02*
Y772933D01*
G01Y772350D02*
X263567Y772683D01*
X263067Y772850D01*
X262483Y772933D01*
X261900Y772767D01*
X261400Y772433D01*
X261067Y771933D01*
X260900Y771267D01*
X261067Y770600D01*
X261400Y770100D01*
X261900Y769767D01*
X262483Y769600D01*
X263067Y769683D01*
X263567Y769933D01*
X263900Y770267D01*
G01X266583Y769600D02*
Y772933D01*
G01Y772100D02*
X266917Y772517D01*
X267417Y772850D01*
X268083Y772933D01*
X268667Y772850D01*
X269167Y772517D01*
X269417Y771933D01*
Y769600D01*
G01X274933Y772517D02*
X274350Y772850D01*
X273850Y772933D01*
X273183Y772767D01*
X272683Y772433D01*
X272350Y771850D01*
X272267Y771267D01*
X272350Y770683D01*
X272683Y770183D01*
X273183Y769767D01*
X273850Y769600D01*
X274433Y769767D01*
X274933Y770100D01*
G01X277950Y771850D02*
X280617D01*
X280367Y772433D01*
X279950Y772767D01*
X279367Y772933D01*
X278783Y772850D01*
X278283Y772600D01*
X277950Y772017D01*
X277783Y771517D01*
Y771017D01*
X277950Y770517D01*
X278367Y770017D01*
X278867Y769683D01*
X279450Y769600D01*
X280033Y769767D01*
X280617Y770267D01*
G01X288650D02*
X289317Y769850D01*
X290067Y769600D01*
X290733D01*
X291400Y769850D01*
X291900Y770267D01*
X292150Y770850D01*
X291983Y771433D01*
X291567Y771933D01*
X290817Y772267D01*
X289817Y772433D01*
X289233Y772767D01*
X288983Y773350D01*
X289150Y773933D01*
X289567Y774350D01*
X290150Y774600D01*
X290733D01*
X291317Y774433D01*
X291817Y774017D01*
G01X294500Y767933D02*
Y772933D01*
G01Y772183D02*
X294917Y772600D01*
X295333Y772850D01*
X296000Y772933D01*
X296583Y772850D01*
X297167Y772433D01*
X297417Y771850D01*
X297500Y771267D01*
X297417Y770683D01*
X297167Y770100D01*
X296667Y769767D01*
X296000Y769600D01*
X295417Y769683D01*
X294833Y769933D01*
X294500Y770267D01*
G01X300350Y771850D02*
X303017D01*
X302767Y772433D01*
X302350Y772767D01*
X301767Y772933D01*
X301183Y772850D01*
X300683Y772600D01*
X300350Y772017D01*
X300183Y771517D01*
Y771017D01*
X300350Y770517D01*
X300767Y770017D01*
X301267Y769683D01*
X301850Y769600D01*
X302433Y769767D01*
X303017Y770267D01*
G01X308533Y772517D02*
X307950Y772850D01*
X307450Y772933D01*
X306783Y772767D01*
X306283Y772433D01*
X305950Y771850D01*
X305867Y771267D01*
X305950Y770683D01*
X306283Y770183D01*
X306783Y769767D01*
X307450Y769600D01*
X308033Y769767D01*
X308533Y770100D01*
G01X312800Y772933D02*
Y769600D01*
G01Y774267D02*
X312633Y774350D01*
Y774517D01*
X312800Y774600D01*
X312967Y774517D01*
Y774350D01*
X312800Y774267D01*
G01X317900Y769600D02*
Y773850D01*
X318067Y774267D01*
X318400Y774517D01*
X318900Y774600D01*
X319400Y774433D01*
X319650Y774017D01*
G01X318650Y772600D02*
X316983D01*
G01X324000Y772933D02*
Y769600D01*
G01Y774267D02*
X323833Y774350D01*
Y774517D01*
X324000Y774600D01*
X324167Y774517D01*
Y774350D01*
X324000Y774267D01*
G01X330933Y772517D02*
X330350Y772850D01*
X329850Y772933D01*
X329183Y772767D01*
X328683Y772433D01*
X328350Y771850D01*
X328267Y771267D01*
X328350Y770683D01*
X328683Y770183D01*
X329183Y769767D01*
X329850Y769600D01*
X330433Y769767D01*
X330933Y770100D01*
G01X336700Y769600D02*
Y772933D01*
G01Y772350D02*
X336367Y772683D01*
X335867Y772850D01*
X335283Y772933D01*
X334700Y772767D01*
X334200Y772433D01*
X333867Y771933D01*
X333700Y771267D01*
X333867Y770600D01*
X334200Y770100D01*
X334700Y769767D01*
X335283Y769600D01*
X335867Y769683D01*
X336367Y769933D01*
X336700Y770267D01*
G01X340800Y774600D02*
Y769600D01*
G01X339633Y772933D02*
X341967D01*
G01X346400D02*
Y769600D01*
G01Y774267D02*
X346233Y774350D01*
Y774517D01*
X346400Y774600D01*
X346567Y774517D01*
Y774350D01*
X346400Y774267D01*
G01X352000Y769600D02*
X351500Y769683D01*
X351000Y770017D01*
X350667Y770600D01*
X350500Y771267D01*
X350667Y771933D01*
X351000Y772517D01*
X351500Y772850D01*
X352000Y772933D01*
X352500Y772850D01*
X353000Y772517D01*
X353333Y771933D01*
X353417Y771267D01*
X353333Y770600D01*
X353000Y770017D01*
X352500Y769683D01*
X352000Y769600D01*
G01X356183D02*
Y772933D01*
G01Y772100D02*
X356517Y772517D01*
X357017Y772850D01*
X357683Y772933D01*
X358267Y772850D01*
X358767Y772517D01*
X359017Y771933D01*
Y769600D01*
G01X368300D02*
Y773850D01*
X368467Y774267D01*
X368800Y774517D01*
X369300Y774600D01*
X369800Y774433D01*
X370050Y774017D01*
G01X369050Y772600D02*
X367383D01*
G01X374400Y769600D02*
X373900Y769683D01*
X373400Y770017D01*
X373067Y770600D01*
X372900Y771267D01*
X373067Y771933D01*
X373400Y772517D01*
X373900Y772850D01*
X374400Y772933D01*
X374900Y772850D01*
X375400Y772517D01*
X375733Y771933D01*
X375817Y771267D01*
X375733Y770600D01*
X375400Y770017D01*
X374900Y769683D01*
X374400Y769600D01*
G01X378833D02*
Y772933D01*
G01Y772267D02*
X379250Y772600D01*
X379667Y772850D01*
X380250Y772933D01*
X380667Y772850D01*
X381167Y772600D01*
G01X389533Y769600D02*
Y774600D01*
X391617D01*
X392283Y774350D01*
X392700Y774017D01*
X392867Y773350D01*
X392700Y772683D01*
X392200Y772267D01*
X391617Y772017D01*
X389533D01*
G01X391617D02*
X392867Y769600D01*
G01X396800Y772933D02*
Y769600D01*
G01Y774267D02*
X396633Y774350D01*
Y774517D01*
X396800Y774600D01*
X396967Y774517D01*
Y774350D01*
X396800Y774267D01*
G01X401233Y768350D02*
X401817Y768017D01*
X402483Y767933D01*
X403067Y768017D01*
X403567Y768433D01*
X403900Y769017D01*
Y772933D01*
G01Y772267D02*
X403567Y772600D01*
X403067Y772850D01*
X402483Y772933D01*
X401817Y772767D01*
X401400Y772433D01*
X401067Y771850D01*
X400900Y771267D01*
X400983Y770767D01*
X401317Y770183D01*
X401817Y769767D01*
X402483Y769600D01*
X402983Y769683D01*
X403567Y770017D01*
X403900Y770350D01*
G01X408000Y772933D02*
Y769600D01*
G01Y774267D02*
X407833Y774350D01*
Y774517D01*
X408000Y774600D01*
X408167Y774517D01*
Y774350D01*
X408000Y774267D01*
G01X415100Y774600D02*
Y769600D01*
G01Y770350D02*
X414767Y769933D01*
X414267Y769683D01*
X413683Y769600D01*
X413017Y769767D01*
X412517Y770183D01*
X412183Y770683D01*
X412100Y771267D01*
X412183Y771850D01*
X412517Y772350D01*
X413017Y772767D01*
X413683Y772933D01*
X414267Y772850D01*
X414683Y772683D01*
X415100Y772350D01*
G01X423133Y769600D02*
Y774600D01*
X425133D01*
X425800Y774350D01*
X426300Y773767D01*
X426467Y773100D01*
X426300Y772433D01*
X425883Y771933D01*
X425133Y771683D01*
X423133D01*
G01X429233Y769600D02*
Y772933D01*
G01Y772267D02*
X429650Y772600D01*
X430067Y772850D01*
X430650Y772933D01*
X431067Y772850D01*
X431567Y772600D01*
G01X436000Y772933D02*
Y769600D01*
G01Y774267D02*
X435833Y774350D01*
Y774517D01*
X436000Y774600D01*
X436167Y774517D01*
Y774350D01*
X436000Y774267D01*
G01X440183Y769600D02*
Y772933D01*
G01Y772100D02*
X440517Y772517D01*
X441017Y772850D01*
X441683Y772933D01*
X442267Y772850D01*
X442767Y772517D01*
X443017Y771933D01*
Y769600D01*
G01X447200Y774600D02*
Y769600D01*
G01X446033Y772933D02*
X448367D01*
G01X451550Y771850D02*
X454217D01*
X453967Y772433D01*
X453550Y772767D01*
X452967Y772933D01*
X452383Y772850D01*
X451883Y772600D01*
X451550Y772017D01*
X451383Y771517D01*
Y771017D01*
X451550Y770517D01*
X451967Y770017D01*
X452467Y769683D01*
X453050Y769600D01*
X453633Y769767D01*
X454217Y770267D01*
G01X459900Y774600D02*
Y769600D01*
G01Y770350D02*
X459567Y769933D01*
X459067Y769683D01*
X458483Y769600D01*
X457817Y769767D01*
X457317Y770183D01*
X456983Y770683D01*
X456900Y771267D01*
X456983Y771850D01*
X457317Y772350D01*
X457817Y772767D01*
X458483Y772933D01*
X459067Y772850D01*
X459483Y772683D01*
X459900Y772350D01*
G01X470267Y772267D02*
X470600Y772517D01*
X470850Y772933D01*
X471017Y773517D01*
X470850Y774017D01*
X470517Y774350D01*
X469933Y774600D01*
X467683D01*
Y769600D01*
X470433D01*
X471017Y769933D01*
X471350Y770433D01*
X471517Y771017D01*
X471350Y771600D01*
X470850Y772100D01*
X470267Y772267D01*
X467683D01*
G01X475200Y769600D02*
X474700Y769683D01*
X474200Y770017D01*
X473867Y770600D01*
X473700Y771267D01*
X473867Y771933D01*
X474200Y772517D01*
X474700Y772850D01*
X475200Y772933D01*
X475700Y772850D01*
X476200Y772517D01*
X476533Y771933D01*
X476617Y771267D01*
X476533Y770600D01*
X476200Y770017D01*
X475700Y769683D01*
X475200Y769600D01*
G01X482300D02*
Y772933D01*
G01Y772350D02*
X481967Y772683D01*
X481467Y772850D01*
X480883Y772933D01*
X480300Y772767D01*
X479800Y772433D01*
X479467Y771933D01*
X479300Y771267D01*
X479467Y770600D01*
X479800Y770100D01*
X480300Y769767D01*
X480883Y769600D01*
X481467Y769683D01*
X481967Y769933D01*
X482300Y770267D01*
G01X485233Y769600D02*
Y772933D01*
G01Y772267D02*
X485650Y772600D01*
X486067Y772850D01*
X486650Y772933D01*
X487067Y772850D01*
X487567Y772600D01*
G01X493500Y774600D02*
Y769600D01*
G01Y770350D02*
X493167Y769933D01*
X492667Y769683D01*
X492083Y769600D01*
X491417Y769767D01*
X490917Y770183D01*
X490583Y770683D01*
X490500Y771267D01*
X490583Y771850D01*
X490917Y772350D01*
X491417Y772767D01*
X492083Y772933D01*
X492667Y772850D01*
X493083Y772683D01*
X493500Y772350D01*
G01X496350Y770183D02*
X496767Y769850D01*
X497350Y769600D01*
X497850D01*
X498350Y769767D01*
X498683Y770017D01*
X498850Y770350D01*
X498767Y770850D01*
X498433Y771100D01*
X496933Y771600D01*
X496600Y772183D01*
X496767Y772600D01*
X497100Y772850D01*
X497600Y772933D01*
X498100Y772850D01*
X498600Y772600D01*
G01X71000Y783600D02*
X73000D01*
G01X72000D02*
Y778600D01*
G01X71000D02*
X73000D01*
G01X75933D02*
Y783600D01*
X77933D01*
X78600Y783350D01*
X79100Y782767D01*
X79267Y782100D01*
X79100Y781433D01*
X78683Y780933D01*
X77933Y780683D01*
X75933D01*
G01X85033Y783183D02*
X84533Y783433D01*
X83950Y783600D01*
X83283D01*
X82533Y783350D01*
X81950Y782933D01*
X81533Y782433D01*
X81200Y781600D01*
X81117Y780850D01*
X81283Y780100D01*
X81533Y779600D01*
X82033Y779100D01*
X82617Y778767D01*
X83200Y778600D01*
X83783D01*
X84367Y778767D01*
X84867Y779017D01*
X85283Y779350D01*
G01X87717Y780267D02*
X89883D01*
G01X92817Y780683D02*
X93400Y781267D01*
X93900Y781600D01*
X94567Y781767D01*
X95150Y781600D01*
X95567Y781267D01*
X95900Y780767D01*
X95983Y780183D01*
X95900Y779683D01*
X95567Y779183D01*
X95067Y778767D01*
X94483Y778600D01*
X93817Y778767D01*
X93233Y779267D01*
X92900Y780017D01*
X92817Y780850D01*
X92983Y781933D01*
X93233Y782517D01*
X93650Y783100D01*
X94233Y783517D01*
X94817Y783600D01*
X95400Y783433D01*
X95817Y783017D01*
G01X100000Y783600D02*
X99333Y783433D01*
X98833Y783017D01*
X98500Y782517D01*
X98250Y781850D01*
X98167Y781100D01*
X98250Y780350D01*
X98500Y779683D01*
X98833Y779183D01*
X99333Y778767D01*
X100000Y778600D01*
X100667Y778767D01*
X101167Y779183D01*
X101500Y779683D01*
X101750Y780350D01*
X101833Y781100D01*
X101750Y781850D01*
X101500Y782517D01*
X101167Y783017D01*
X100667Y783433D01*
X100000Y783600D01*
G01X105600Y778600D02*
Y783600D01*
X104600Y782600D01*
G01Y778600D02*
X106600D01*
G01X111200D02*
Y783600D01*
X110200Y782600D01*
G01Y778600D02*
X112200D01*
G01X122900Y781100D02*
X124567D01*
Y779600D01*
X124067Y779100D01*
X123483Y778767D01*
X122650Y778600D01*
X121817Y778767D01*
X121233Y779100D01*
X120733Y779600D01*
X120400Y780183D01*
X120233Y780850D01*
Y781433D01*
X120400Y781933D01*
X120733Y782517D01*
X121233Y783017D01*
X121733Y783350D01*
X122400Y783600D01*
X122983D01*
X123650Y783433D01*
X124150Y783100D01*
G01X126750Y780850D02*
X129417D01*
X129167Y781433D01*
X128750Y781767D01*
X128167Y781933D01*
X127583Y781850D01*
X127083Y781600D01*
X126750Y781017D01*
X126583Y780517D01*
Y780017D01*
X126750Y779517D01*
X127167Y779017D01*
X127667Y778683D01*
X128250Y778600D01*
X128833Y778767D01*
X129417Y779267D01*
G01X132183Y778600D02*
Y781933D01*
G01Y781100D02*
X132517Y781517D01*
X133017Y781850D01*
X133683Y781933D01*
X134267Y781850D01*
X134767Y781517D01*
X135017Y780933D01*
Y778600D01*
G01X137950Y780850D02*
X140617D01*
X140367Y781433D01*
X139950Y781767D01*
X139367Y781933D01*
X138783Y781850D01*
X138283Y781600D01*
X137950Y781017D01*
X137783Y780517D01*
Y780017D01*
X137950Y779517D01*
X138367Y779017D01*
X138867Y778683D01*
X139450Y778600D01*
X140033Y778767D01*
X140617Y779267D01*
G01X143633Y778600D02*
Y781933D01*
G01Y781267D02*
X144050Y781600D01*
X144467Y781850D01*
X145050Y781933D01*
X145467Y781850D01*
X145967Y781600D01*
G01X150400Y781933D02*
Y778600D01*
G01Y783267D02*
X150233Y783350D01*
Y783517D01*
X150400Y783600D01*
X150567Y783517D01*
Y783350D01*
X150400Y783267D01*
G01X157333Y781517D02*
X156750Y781850D01*
X156250Y781933D01*
X155583Y781767D01*
X155083Y781433D01*
X154750Y780850D01*
X154667Y780267D01*
X154750Y779683D01*
X155083Y779183D01*
X155583Y778767D01*
X156250Y778600D01*
X156833Y778767D01*
X157333Y779100D01*
G01X165533Y778600D02*
Y783600D01*
X167533D01*
X168200Y783350D01*
X168700Y782767D01*
X168867Y782100D01*
X168700Y781433D01*
X168283Y780933D01*
X167533Y780683D01*
X165533D01*
G01X171550Y780850D02*
X174217D01*
X173967Y781433D01*
X173550Y781767D01*
X172967Y781933D01*
X172383Y781850D01*
X171883Y781600D01*
X171550Y781017D01*
X171383Y780517D01*
Y780017D01*
X171550Y779517D01*
X171967Y779017D01*
X172467Y778683D01*
X173050Y778600D01*
X173633Y778767D01*
X174217Y779267D01*
G01X177233Y778600D02*
Y781933D01*
G01Y781267D02*
X177650Y781600D01*
X178067Y781850D01*
X178650Y781933D01*
X179067Y781850D01*
X179567Y781600D01*
G01X183500Y778600D02*
Y782850D01*
X183667Y783267D01*
X184000Y783517D01*
X184500Y783600D01*
X185000Y783433D01*
X185250Y783017D01*
G01X184250Y781600D02*
X182583D01*
G01X189600Y778600D02*
X189100Y778683D01*
X188600Y779017D01*
X188267Y779600D01*
X188100Y780267D01*
X188267Y780933D01*
X188600Y781517D01*
X189100Y781850D01*
X189600Y781933D01*
X190100Y781850D01*
X190600Y781517D01*
X190933Y780933D01*
X191017Y780267D01*
X190933Y779600D01*
X190600Y779017D01*
X190100Y778683D01*
X189600Y778600D01*
G01X194033D02*
Y781933D01*
G01Y781267D02*
X194450Y781600D01*
X194867Y781850D01*
X195450Y781933D01*
X195867Y781850D01*
X196367Y781600D01*
G01X198300Y778600D02*
Y781933D01*
G01Y781017D02*
X198550Y781433D01*
X198967Y781767D01*
X199550Y781933D01*
X200133Y781767D01*
X200550Y781433D01*
X200800Y781017D01*
Y778600D01*
G01Y781017D02*
X201050Y781433D01*
X201467Y781767D01*
X202050Y781933D01*
X202633Y781767D01*
X203050Y781433D01*
X203300Y780933D01*
Y778600D01*
G01X207900D02*
Y781933D01*
G01Y781350D02*
X207567Y781683D01*
X207067Y781850D01*
X206483Y781933D01*
X205900Y781767D01*
X205400Y781433D01*
X205067Y780933D01*
X204900Y780267D01*
X205067Y779600D01*
X205400Y779100D01*
X205900Y778767D01*
X206483Y778600D01*
X207067Y778683D01*
X207567Y778933D01*
X207900Y779267D01*
G01X210583Y778600D02*
Y781933D01*
G01Y781100D02*
X210917Y781517D01*
X211417Y781850D01*
X212083Y781933D01*
X212667Y781850D01*
X213167Y781517D01*
X213417Y780933D01*
Y778600D01*
G01X218933Y781517D02*
X218350Y781850D01*
X217850Y781933D01*
X217183Y781767D01*
X216683Y781433D01*
X216350Y780850D01*
X216267Y780267D01*
X216350Y779683D01*
X216683Y779183D01*
X217183Y778767D01*
X217850Y778600D01*
X218433Y778767D01*
X218933Y779100D01*
G01X221950Y780850D02*
X224617D01*
X224367Y781433D01*
X223950Y781767D01*
X223367Y781933D01*
X222783Y781850D01*
X222283Y781600D01*
X221950Y781017D01*
X221783Y780517D01*
Y780017D01*
X221950Y779517D01*
X222367Y779017D01*
X222867Y778683D01*
X223450Y778600D01*
X224033Y778767D01*
X224617Y779267D01*
G01X232650D02*
X233317Y778850D01*
X234067Y778600D01*
X234733D01*
X235400Y778850D01*
X235900Y779267D01*
X236150Y779850D01*
X235983Y780433D01*
X235567Y780933D01*
X234817Y781267D01*
X233817Y781433D01*
X233233Y781767D01*
X232983Y782350D01*
X233150Y782933D01*
X233567Y783350D01*
X234150Y783600D01*
X234733D01*
X235317Y783433D01*
X235817Y783017D01*
G01X238500Y776933D02*
Y781933D01*
G01Y781183D02*
X238917Y781600D01*
X239333Y781850D01*
X240000Y781933D01*
X240583Y781850D01*
X241167Y781433D01*
X241417Y780850D01*
X241500Y780267D01*
X241417Y779683D01*
X241167Y779100D01*
X240667Y778767D01*
X240000Y778600D01*
X239417Y778683D01*
X238833Y778933D01*
X238500Y779267D01*
G01X244350Y780850D02*
X247017D01*
X246767Y781433D01*
X246350Y781767D01*
X245767Y781933D01*
X245183Y781850D01*
X244683Y781600D01*
X244350Y781017D01*
X244183Y780517D01*
Y780017D01*
X244350Y779517D01*
X244767Y779017D01*
X245267Y778683D01*
X245850Y778600D01*
X246433Y778767D01*
X247017Y779267D01*
G01X252533Y781517D02*
X251950Y781850D01*
X251450Y781933D01*
X250783Y781767D01*
X250283Y781433D01*
X249950Y780850D01*
X249867Y780267D01*
X249950Y779683D01*
X250283Y779183D01*
X250783Y778767D01*
X251450Y778600D01*
X252033Y778767D01*
X252533Y779100D01*
G01X256800Y781933D02*
Y778600D01*
G01Y783267D02*
X256633Y783350D01*
Y783517D01*
X256800Y783600D01*
X256967Y783517D01*
Y783350D01*
X256800Y783267D01*
G01X261900Y778600D02*
Y782850D01*
X262067Y783267D01*
X262400Y783517D01*
X262900Y783600D01*
X263400Y783433D01*
X263650Y783017D01*
G01X262650Y781600D02*
X260983D01*
G01X268000Y781933D02*
Y778600D01*
G01Y783267D02*
X267833Y783350D01*
Y783517D01*
X268000Y783600D01*
X268167Y783517D01*
Y783350D01*
X268000Y783267D01*
G01X274933Y781517D02*
X274350Y781850D01*
X273850Y781933D01*
X273183Y781767D01*
X272683Y781433D01*
X272350Y780850D01*
X272267Y780267D01*
X272350Y779683D01*
X272683Y779183D01*
X273183Y778767D01*
X273850Y778600D01*
X274433Y778767D01*
X274933Y779100D01*
G01X280700Y778600D02*
Y781933D01*
G01Y781350D02*
X280367Y781683D01*
X279867Y781850D01*
X279283Y781933D01*
X278700Y781767D01*
X278200Y781433D01*
X277867Y780933D01*
X277700Y780267D01*
X277867Y779600D01*
X278200Y779100D01*
X278700Y778767D01*
X279283Y778600D01*
X279867Y778683D01*
X280367Y778933D01*
X280700Y779267D01*
G01X284800Y783600D02*
Y778600D01*
G01X283633Y781933D02*
X285967D01*
G01X290400D02*
Y778600D01*
G01Y783267D02*
X290233Y783350D01*
Y783517D01*
X290400Y783600D01*
X290567Y783517D01*
Y783350D01*
X290400Y783267D01*
G01X296000Y778600D02*
X295500Y778683D01*
X295000Y779017D01*
X294667Y779600D01*
X294500Y780267D01*
X294667Y780933D01*
X295000Y781517D01*
X295500Y781850D01*
X296000Y781933D01*
X296500Y781850D01*
X297000Y781517D01*
X297333Y780933D01*
X297417Y780267D01*
X297333Y779600D01*
X297000Y779017D01*
X296500Y778683D01*
X296000Y778600D01*
G01X300183D02*
Y781933D01*
G01Y781100D02*
X300517Y781517D01*
X301017Y781850D01*
X301683Y781933D01*
X302267Y781850D01*
X302767Y781517D01*
X303017Y780933D01*
Y778600D01*
G01X312300D02*
Y782850D01*
X312467Y783267D01*
X312800Y783517D01*
X313300Y783600D01*
X313800Y783433D01*
X314050Y783017D01*
G01X313050Y781600D02*
X311383D01*
G01X318400Y778600D02*
X317900Y778683D01*
X317400Y779017D01*
X317067Y779600D01*
X316900Y780267D01*
X317067Y780933D01*
X317400Y781517D01*
X317900Y781850D01*
X318400Y781933D01*
X318900Y781850D01*
X319400Y781517D01*
X319733Y780933D01*
X319817Y780267D01*
X319733Y779600D01*
X319400Y779017D01*
X318900Y778683D01*
X318400Y778600D01*
G01X322833D02*
Y781933D01*
G01Y781267D02*
X323250Y781600D01*
X323667Y781850D01*
X324250Y781933D01*
X324667Y781850D01*
X325167Y781600D01*
G01X333533Y778600D02*
Y783600D01*
X335533D01*
X336200Y783350D01*
X336700Y782767D01*
X336867Y782100D01*
X336700Y781433D01*
X336283Y780933D01*
X335533Y780683D01*
X333533D01*
G01X339633Y778600D02*
Y781933D01*
G01Y781267D02*
X340050Y781600D01*
X340467Y781850D01*
X341050Y781933D01*
X341467Y781850D01*
X341967Y781600D01*
G01X346400Y781933D02*
Y778600D01*
G01Y783267D02*
X346233Y783350D01*
Y783517D01*
X346400Y783600D01*
X346567Y783517D01*
Y783350D01*
X346400Y783267D01*
G01X350583Y778600D02*
Y781933D01*
G01Y781100D02*
X350917Y781517D01*
X351417Y781850D01*
X352083Y781933D01*
X352667Y781850D01*
X353167Y781517D01*
X353417Y780933D01*
Y778600D01*
G01X357600Y783600D02*
Y778600D01*
G01X356433Y781933D02*
X358767D01*
G01X361950Y780850D02*
X364617D01*
X364367Y781433D01*
X363950Y781767D01*
X363367Y781933D01*
X362783Y781850D01*
X362283Y781600D01*
X361950Y781017D01*
X361783Y780517D01*
Y780017D01*
X361950Y779517D01*
X362367Y779017D01*
X362867Y778683D01*
X363450Y778600D01*
X364033Y778767D01*
X364617Y779267D01*
G01X370300Y783600D02*
Y778600D01*
G01Y779350D02*
X369967Y778933D01*
X369467Y778683D01*
X368883Y778600D01*
X368217Y778767D01*
X367717Y779183D01*
X367383Y779683D01*
X367300Y780267D01*
X367383Y780850D01*
X367717Y781350D01*
X368217Y781767D01*
X368883Y781933D01*
X369467Y781850D01*
X369883Y781683D01*
X370300Y781350D01*
G01X380667Y781267D02*
X381000Y781517D01*
X381250Y781933D01*
X381417Y782517D01*
X381250Y783017D01*
X380917Y783350D01*
X380333Y783600D01*
X378083D01*
Y778600D01*
X380833D01*
X381417Y778933D01*
X381750Y779433D01*
X381917Y780017D01*
X381750Y780600D01*
X381250Y781100D01*
X380667Y781267D01*
X378083D01*
G01X385600Y778600D02*
X385100Y778683D01*
X384600Y779017D01*
X384267Y779600D01*
X384100Y780267D01*
X384267Y780933D01*
X384600Y781517D01*
X385100Y781850D01*
X385600Y781933D01*
X386100Y781850D01*
X386600Y781517D01*
X386933Y780933D01*
X387017Y780267D01*
X386933Y779600D01*
X386600Y779017D01*
X386100Y778683D01*
X385600Y778600D01*
G01X392700D02*
Y781933D01*
G01Y781350D02*
X392367Y781683D01*
X391867Y781850D01*
X391283Y781933D01*
X390700Y781767D01*
X390200Y781433D01*
X389867Y780933D01*
X389700Y780267D01*
X389867Y779600D01*
X390200Y779100D01*
X390700Y778767D01*
X391283Y778600D01*
X391867Y778683D01*
X392367Y778933D01*
X392700Y779267D01*
G01X395633Y778600D02*
Y781933D01*
G01Y781267D02*
X396050Y781600D01*
X396467Y781850D01*
X397050Y781933D01*
X397467Y781850D01*
X397967Y781600D01*
G01X403900Y783600D02*
Y778600D01*
G01Y779350D02*
X403567Y778933D01*
X403067Y778683D01*
X402483Y778600D01*
X401817Y778767D01*
X401317Y779183D01*
X400983Y779683D01*
X400900Y780267D01*
X400983Y780850D01*
X401317Y781350D01*
X401817Y781767D01*
X402483Y781933D01*
X403067Y781850D01*
X403483Y781683D01*
X403900Y781350D01*
G01X406750Y779183D02*
X407167Y778850D01*
X407750Y778600D01*
X408250D01*
X408750Y778767D01*
X409083Y779017D01*
X409250Y779350D01*
X409167Y779850D01*
X408833Y780100D01*
X407333Y780600D01*
X407000Y781183D01*
X407167Y781600D01*
X407500Y781850D01*
X408000Y781933D01*
X408500Y781850D01*
X409000Y781600D01*
G01X71000Y791500D02*
X73000D01*
G01X72000D02*
Y786500D01*
G01X71000D02*
X73000D01*
G01X75933D02*
Y791500D01*
X77933D01*
X78600Y791250D01*
X79100Y790667D01*
X79267Y790000D01*
X79100Y789333D01*
X78683Y788833D01*
X77933Y788583D01*
X75933D01*
G01X85033Y791083D02*
X84533Y791333D01*
X83950Y791500D01*
X83283D01*
X82533Y791250D01*
X81950Y790833D01*
X81533Y790333D01*
X81200Y789500D01*
X81117Y788750D01*
X81283Y788000D01*
X81533Y787500D01*
X82033Y787000D01*
X82617Y786667D01*
X83200Y786500D01*
X83783D01*
X84367Y786667D01*
X84867Y786917D01*
X85283Y787250D01*
G01X87717Y788167D02*
X89883D01*
G01X92317Y786500D02*
X94400Y791500D01*
X96483Y786500D01*
G01X95733Y788250D02*
X93067D01*
G01X98917Y788167D02*
X101083D01*
G01X104017Y788583D02*
X104600Y789167D01*
X105100Y789500D01*
X105767Y789667D01*
X106350Y789500D01*
X106767Y789167D01*
X107100Y788667D01*
X107183Y788083D01*
X107100Y787583D01*
X106767Y787083D01*
X106267Y786667D01*
X105683Y786500D01*
X105017Y786667D01*
X104433Y787167D01*
X104100Y787917D01*
X104017Y788750D01*
X104183Y789833D01*
X104433Y790417D01*
X104850Y791000D01*
X105433Y791417D01*
X106017Y791500D01*
X106600Y791333D01*
X107017Y790917D01*
G01X111200Y791500D02*
X110533Y791333D01*
X110033Y790917D01*
X109700Y790417D01*
X109450Y789750D01*
X109367Y789000D01*
X109450Y788250D01*
X109700Y787583D01*
X110033Y787083D01*
X110533Y786667D01*
X111200Y786500D01*
X111867Y786667D01*
X112367Y787083D01*
X112700Y787583D01*
X112950Y788250D01*
X113033Y789000D01*
X112950Y789750D01*
X112700Y790417D01*
X112367Y790917D01*
X111867Y791333D01*
X111200Y791500D01*
G01X116800D02*
X116133Y791333D01*
X115633Y790917D01*
X115300Y790417D01*
X115050Y789750D01*
X114967Y789000D01*
X115050Y788250D01*
X115300Y787583D01*
X115633Y787083D01*
X116133Y786667D01*
X116800Y786500D01*
X117467Y786667D01*
X117967Y787083D01*
X118300Y787583D01*
X118550Y788250D01*
X118633Y789000D01*
X118550Y789750D01*
X118300Y790417D01*
X117967Y790917D01*
X117467Y791333D01*
X116800Y791500D01*
G01X125917Y786500D02*
X128000Y791500D01*
X130083Y786500D01*
G01X129333Y788250D02*
X126667D01*
G01X134933Y789417D02*
X134350Y789750D01*
X133850Y789833D01*
X133183Y789667D01*
X132683Y789333D01*
X132350Y788750D01*
X132267Y788167D01*
X132350Y787583D01*
X132683Y787083D01*
X133183Y786667D01*
X133850Y786500D01*
X134433Y786667D01*
X134933Y787000D01*
G01X140533Y789417D02*
X139950Y789750D01*
X139450Y789833D01*
X138783Y789667D01*
X138283Y789333D01*
X137950Y788750D01*
X137867Y788167D01*
X137950Y787583D01*
X138283Y787083D01*
X138783Y786667D01*
X139450Y786500D01*
X140033Y786667D01*
X140533Y787000D01*
G01X143550Y788750D02*
X146217D01*
X145967Y789333D01*
X145550Y789667D01*
X144967Y789833D01*
X144383Y789750D01*
X143883Y789500D01*
X143550Y788917D01*
X143383Y788417D01*
Y787917D01*
X143550Y787417D01*
X143967Y786917D01*
X144467Y786583D01*
X145050Y786500D01*
X145633Y786667D01*
X146217Y787167D01*
G01X148900Y784833D02*
Y789833D01*
G01Y789083D02*
X149317Y789500D01*
X149733Y789750D01*
X150400Y789833D01*
X150983Y789750D01*
X151567Y789333D01*
X151817Y788750D01*
X151900Y788167D01*
X151817Y787583D01*
X151567Y787000D01*
X151067Y786667D01*
X150400Y786500D01*
X149817Y786583D01*
X149233Y786833D01*
X148900Y787167D01*
G01X156000Y791500D02*
Y786500D01*
G01X154833Y789833D02*
X157167D01*
G01X163100Y786500D02*
Y789833D01*
G01Y789250D02*
X162767Y789583D01*
X162267Y789750D01*
X161683Y789833D01*
X161100Y789667D01*
X160600Y789333D01*
X160267Y788833D01*
X160100Y788167D01*
X160267Y787500D01*
X160600Y787000D01*
X161100Y786667D01*
X161683Y786500D01*
X162267Y786583D01*
X162767Y786833D01*
X163100Y787167D01*
G01X165700Y786500D02*
Y791500D01*
G01Y789000D02*
X166117Y789500D01*
X166617Y789750D01*
X167117Y789833D01*
X167867Y789667D01*
X168367Y789333D01*
X168700Y788750D01*
Y788083D01*
X168533Y787417D01*
X168200Y786917D01*
X167617Y786583D01*
X167117Y786500D01*
X166617Y786583D01*
X166117Y786833D01*
X165700Y787250D01*
G01X172800Y789833D02*
Y786500D01*
G01Y791167D02*
X172633Y791250D01*
Y791417D01*
X172800Y791500D01*
X172967Y791417D01*
Y791250D01*
X172800Y791167D01*
G01X178400Y786500D02*
Y791500D01*
G01X184000Y789833D02*
Y786500D01*
G01Y791167D02*
X183833Y791250D01*
Y791417D01*
X184000Y791500D01*
X184167Y791417D01*
Y791250D01*
X184000Y791167D01*
G01X189600Y791500D02*
Y786500D01*
G01X188433Y789833D02*
X190767D01*
G01X193450Y785000D02*
X193950Y784833D01*
X194617Y785000D01*
X195033Y785333D01*
X195367Y785750D01*
X195867Y787083D01*
X196950Y789833D01*
G01X194283D02*
X195867Y787083D01*
G01X206400Y786500D02*
X205900Y786583D01*
X205400Y786917D01*
X205067Y787500D01*
X204900Y788167D01*
X205067Y788833D01*
X205400Y789417D01*
X205900Y789750D01*
X206400Y789833D01*
X206900Y789750D01*
X207400Y789417D01*
X207733Y788833D01*
X207817Y788167D01*
X207733Y787500D01*
X207400Y786917D01*
X206900Y786583D01*
X206400Y786500D01*
G01X211500D02*
Y790750D01*
X211667Y791167D01*
X212000Y791417D01*
X212500Y791500D01*
X213000Y791333D01*
X213250Y790917D01*
G01X212250Y789500D02*
X210583D01*
G01X221533Y786500D02*
Y791500D01*
X223533D01*
X224200Y791250D01*
X224700Y790667D01*
X224867Y790000D01*
X224700Y789333D01*
X224283Y788833D01*
X223533Y788583D01*
X221533D01*
G01X227633Y786500D02*
Y789833D01*
G01Y789167D02*
X228050Y789500D01*
X228467Y789750D01*
X229050Y789833D01*
X229467Y789750D01*
X229967Y789500D01*
G01X234400Y789833D02*
Y786500D01*
G01Y791167D02*
X234233Y791250D01*
Y791417D01*
X234400Y791500D01*
X234567Y791417D01*
Y791250D01*
X234400Y791167D01*
G01X238583Y786500D02*
Y789833D01*
G01Y789000D02*
X238917Y789417D01*
X239417Y789750D01*
X240083Y789833D01*
X240667Y789750D01*
X241167Y789417D01*
X241417Y788833D01*
Y786500D01*
G01X245600Y791500D02*
Y786500D01*
G01X244433Y789833D02*
X246767D01*
G01X249950Y788750D02*
X252617D01*
X252367Y789333D01*
X251950Y789667D01*
X251367Y789833D01*
X250783Y789750D01*
X250283Y789500D01*
X249950Y788917D01*
X249783Y788417D01*
Y787917D01*
X249950Y787417D01*
X250367Y786917D01*
X250867Y786583D01*
X251450Y786500D01*
X252033Y786667D01*
X252617Y787167D01*
G01X258300Y791500D02*
Y786500D01*
G01Y787250D02*
X257967Y786833D01*
X257467Y786583D01*
X256883Y786500D01*
X256217Y786667D01*
X255717Y787083D01*
X255383Y787583D01*
X255300Y788167D01*
X255383Y788750D01*
X255717Y789250D01*
X256217Y789667D01*
X256883Y789833D01*
X257467Y789750D01*
X257883Y789583D01*
X258300Y789250D01*
G01X268667Y789167D02*
X269000Y789417D01*
X269250Y789833D01*
X269417Y790417D01*
X269250Y790917D01*
X268917Y791250D01*
X268333Y791500D01*
X266083D01*
Y786500D01*
X268833D01*
X269417Y786833D01*
X269750Y787333D01*
X269917Y787917D01*
X269750Y788500D01*
X269250Y789000D01*
X268667Y789167D01*
X266083D01*
G01X273600Y786500D02*
X273100Y786583D01*
X272600Y786917D01*
X272267Y787500D01*
X272100Y788167D01*
X272267Y788833D01*
X272600Y789417D01*
X273100Y789750D01*
X273600Y789833D01*
X274100Y789750D01*
X274600Y789417D01*
X274933Y788833D01*
X275017Y788167D01*
X274933Y787500D01*
X274600Y786917D01*
X274100Y786583D01*
X273600Y786500D01*
G01X280700D02*
Y789833D01*
G01Y789250D02*
X280367Y789583D01*
X279867Y789750D01*
X279283Y789833D01*
X278700Y789667D01*
X278200Y789333D01*
X277867Y788833D01*
X277700Y788167D01*
X277867Y787500D01*
X278200Y787000D01*
X278700Y786667D01*
X279283Y786500D01*
X279867Y786583D01*
X280367Y786833D01*
X280700Y787167D01*
G01X283633Y786500D02*
Y789833D01*
G01Y789167D02*
X284050Y789500D01*
X284467Y789750D01*
X285050Y789833D01*
X285467Y789750D01*
X285967Y789500D01*
G01X291900Y791500D02*
Y786500D01*
G01Y787250D02*
X291567Y786833D01*
X291067Y786583D01*
X290483Y786500D01*
X289817Y786667D01*
X289317Y787083D01*
X288983Y787583D01*
X288900Y788167D01*
X288983Y788750D01*
X289317Y789250D01*
X289817Y789667D01*
X290483Y789833D01*
X291067Y789750D01*
X291483Y789583D01*
X291900Y789250D01*
G01X294750Y787083D02*
X295167Y786750D01*
X295750Y786500D01*
X296250D01*
X296750Y786667D01*
X297083Y786917D01*
X297250Y787250D01*
X297167Y787750D01*
X296833Y788000D01*
X295333Y788500D01*
X295000Y789083D01*
X295167Y789500D01*
X295500Y789750D01*
X296000Y789833D01*
X296500Y789750D01*
X297000Y789500D01*
G01X160333Y668083D02*
X159833Y668333D01*
X159250Y668500D01*
X158583D01*
X157833Y668250D01*
X157250Y667833D01*
X156833Y667333D01*
X156500Y666500D01*
X156417Y665750D01*
X156583Y665000D01*
X156833Y664500D01*
X157333Y664000D01*
X157917Y663667D01*
X158500Y663500D01*
X159083D01*
X159667Y663667D01*
X160167Y663917D01*
X160583Y664250D01*
G01X164100Y663500D02*
Y668500D01*
G01X171200Y663500D02*
Y666833D01*
G01Y666250D02*
X170867Y666583D01*
X170367Y666750D01*
X169783Y666833D01*
X169200Y666667D01*
X168700Y666333D01*
X168367Y665833D01*
X168200Y665167D01*
X168367Y664500D01*
X168700Y664000D01*
X169200Y663667D01*
X169783Y663500D01*
X170367Y663583D01*
X170867Y663833D01*
X171200Y664167D01*
G01X174050Y664083D02*
X174467Y663750D01*
X175050Y663500D01*
X175550D01*
X176050Y663667D01*
X176383Y663917D01*
X176550Y664250D01*
X176467Y664750D01*
X176133Y665000D01*
X174633Y665500D01*
X174300Y666083D01*
X174467Y666500D01*
X174800Y666750D01*
X175300Y666833D01*
X175800Y666750D01*
X176300Y666500D01*
G01X179650Y664083D02*
X180067Y663750D01*
X180650Y663500D01*
X181150D01*
X181650Y663667D01*
X181983Y663917D01*
X182150Y664250D01*
X182067Y664750D01*
X181733Y665000D01*
X180233Y665500D01*
X179900Y666083D01*
X180067Y666500D01*
X180400Y666750D01*
X180900Y666833D01*
X181400Y666750D01*
X181900Y666500D01*
G01X186500Y666833D02*
Y663500D01*
G01Y668167D02*
X186333Y668250D01*
Y668417D01*
X186500Y668500D01*
X186667Y668417D01*
Y668250D01*
X186500Y668167D01*
G01X191600Y663500D02*
Y667750D01*
X191767Y668167D01*
X192100Y668417D01*
X192600Y668500D01*
X193100Y668333D01*
X193350Y667917D01*
G01X192350Y666500D02*
X190683D01*
G01X195950Y662000D02*
X196450Y661833D01*
X197117Y662000D01*
X197533Y662333D01*
X197867Y662750D01*
X198367Y664083D01*
X199450Y666833D01*
G01X196783D02*
X198367Y664083D01*
G01X274000Y-63500D02*
Y-60167D01*
G01Y-60750D02*
X273667Y-60417D01*
X273167Y-60250D01*
X272583Y-60167D01*
X272000Y-60333D01*
X271500Y-60667D01*
X271167Y-61167D01*
X271000Y-61833D01*
X271167Y-62500D01*
X271500Y-63000D01*
X272000Y-63333D01*
X272583Y-63500D01*
X273167Y-63417D01*
X273667Y-63167D01*
X274000Y-62833D01*
G01X279600Y-58500D02*
Y-63500D01*
G01Y-62750D02*
X279267Y-63167D01*
X278767Y-63417D01*
X278183Y-63500D01*
X277517Y-63333D01*
X277017Y-62917D01*
X276683Y-62417D01*
X276600Y-61833D01*
X276683Y-61250D01*
X277017Y-60750D01*
X277517Y-60333D01*
X278183Y-60167D01*
X278767Y-60250D01*
X279183Y-60417D01*
X279600Y-60750D01*
G01X285200Y-58500D02*
Y-63500D01*
G01Y-62750D02*
X284867Y-63167D01*
X284367Y-63417D01*
X283783Y-63500D01*
X283117Y-63333D01*
X282617Y-62917D01*
X282283Y-62417D01*
X282200Y-61833D01*
X282283Y-61250D01*
X282617Y-60750D01*
X283117Y-60333D01*
X283783Y-60167D01*
X284367Y-60250D01*
X284783Y-60417D01*
X285200Y-60750D01*
G01X293650Y-62917D02*
X294067Y-63250D01*
X294650Y-63500D01*
X295150D01*
X295650Y-63333D01*
X295983Y-63083D01*
X296150Y-62750D01*
X296067Y-62250D01*
X295733Y-62000D01*
X294233Y-61500D01*
X293900Y-60917D01*
X294067Y-60500D01*
X294400Y-60250D01*
X294900Y-60167D01*
X295400Y-60250D01*
X295900Y-60500D01*
G01X299083Y-60167D02*
Y-62500D01*
X299417Y-63083D01*
X299917Y-63417D01*
X300500Y-63500D01*
X301083Y-63417D01*
X301583Y-63083D01*
X301917Y-62500D01*
G01Y-63500D02*
Y-60167D01*
G01X304600Y-65167D02*
Y-60167D01*
G01Y-60917D02*
X305017Y-60500D01*
X305433Y-60250D01*
X306100Y-60167D01*
X306683Y-60250D01*
X307267Y-60667D01*
X307517Y-61250D01*
X307600Y-61833D01*
X307517Y-62417D01*
X307267Y-63000D01*
X306767Y-63333D01*
X306100Y-63500D01*
X305517Y-63417D01*
X304933Y-63167D01*
X304600Y-62833D01*
G01X310200Y-65167D02*
Y-60167D01*
G01Y-60917D02*
X310617Y-60500D01*
X311033Y-60250D01*
X311700Y-60167D01*
X312283Y-60250D01*
X312867Y-60667D01*
X313117Y-61250D01*
X313200Y-61833D01*
X313117Y-62417D01*
X312867Y-63000D01*
X312367Y-63333D01*
X311700Y-63500D01*
X311117Y-63417D01*
X310533Y-63167D01*
X310200Y-62833D01*
G01X317300Y-63500D02*
Y-58500D01*
G01X322900Y-60167D02*
Y-63500D01*
G01Y-58833D02*
X322733Y-58750D01*
Y-58583D01*
X322900Y-58500D01*
X323067Y-58583D01*
Y-58750D01*
X322900Y-58833D01*
G01X327250Y-61250D02*
X329917D01*
X329667Y-60667D01*
X329250Y-60333D01*
X328667Y-60167D01*
X328083Y-60250D01*
X327583Y-60500D01*
X327250Y-61083D01*
X327083Y-61583D01*
Y-62083D01*
X327250Y-62583D01*
X327667Y-63083D01*
X328167Y-63417D01*
X328750Y-63500D01*
X329333Y-63333D01*
X329917Y-62833D01*
G01X332933Y-63500D02*
Y-60167D01*
G01Y-60833D02*
X333350Y-60500D01*
X333767Y-60250D01*
X334350Y-60167D01*
X334767Y-60250D01*
X335267Y-60500D01*
G01X339700Y-60167D02*
X340533Y-59125D01*
Y-58500D01*
X339908D01*
Y-59125D01*
X340533D01*
G01X344050Y-62917D02*
X344467Y-63250D01*
X345050Y-63500D01*
X345550D01*
X346050Y-63333D01*
X346383Y-63083D01*
X346550Y-62750D01*
X346467Y-62250D01*
X346133Y-62000D01*
X344633Y-61500D01*
X344300Y-60917D01*
X344467Y-60500D01*
X344800Y-60250D01*
X345300Y-60167D01*
X345800Y-60250D01*
X346300Y-60500D01*
G01X354833Y-58500D02*
Y-63500D01*
X358167D01*
G01X362100D02*
X361600Y-63417D01*
X361100Y-63083D01*
X360767Y-62500D01*
X360600Y-61833D01*
X360767Y-61167D01*
X361100Y-60583D01*
X361600Y-60250D01*
X362100Y-60167D01*
X362600Y-60250D01*
X363100Y-60583D01*
X363433Y-61167D01*
X363517Y-61833D01*
X363433Y-62500D01*
X363100Y-63083D01*
X362600Y-63417D01*
X362100Y-63500D01*
G01X366533Y-64750D02*
X367117Y-65083D01*
X367783Y-65167D01*
X368367Y-65083D01*
X368867Y-64667D01*
X369200Y-64083D01*
Y-60167D01*
G01Y-60833D02*
X368867Y-60500D01*
X368367Y-60250D01*
X367783Y-60167D01*
X367117Y-60333D01*
X366700Y-60667D01*
X366367Y-61250D01*
X366200Y-61833D01*
X366283Y-62333D01*
X366617Y-62917D01*
X367117Y-63333D01*
X367783Y-63500D01*
X368283Y-63417D01*
X368867Y-63083D01*
X369200Y-62750D01*
G01X373300Y-63500D02*
X372800Y-63417D01*
X372300Y-63083D01*
X371967Y-62500D01*
X371800Y-61833D01*
X371967Y-61167D01*
X372300Y-60583D01*
X372800Y-60250D01*
X373300Y-60167D01*
X373800Y-60250D01*
X374300Y-60583D01*
X374633Y-61167D01*
X374717Y-61833D01*
X374633Y-62500D01*
X374300Y-63083D01*
X373800Y-63417D01*
X373300Y-63500D01*
G01X386000D02*
Y-60167D01*
G01Y-60750D02*
X385667Y-60417D01*
X385167Y-60250D01*
X384583Y-60167D01*
X384000Y-60333D01*
X383500Y-60667D01*
X383167Y-61167D01*
X383000Y-61833D01*
X383167Y-62500D01*
X383500Y-63000D01*
X384000Y-63333D01*
X384583Y-63500D01*
X385167Y-63417D01*
X385667Y-63167D01*
X386000Y-62833D01*
G01X388683Y-63500D02*
Y-60167D01*
G01Y-61000D02*
X389017Y-60583D01*
X389517Y-60250D01*
X390183Y-60167D01*
X390767Y-60250D01*
X391267Y-60583D01*
X391517Y-61167D01*
Y-63500D01*
G01X397200Y-58500D02*
Y-63500D01*
G01Y-62750D02*
X396867Y-63167D01*
X396367Y-63417D01*
X395783Y-63500D01*
X395117Y-63333D01*
X394617Y-62917D01*
X394283Y-62417D01*
X394200Y-61833D01*
X394283Y-61250D01*
X394617Y-60750D01*
X395117Y-60333D01*
X395783Y-60167D01*
X396367Y-60250D01*
X396783Y-60417D01*
X397200Y-60750D01*
G01X405067Y-58500D02*
Y-62083D01*
X405400Y-62833D01*
X406067Y-63333D01*
X406900Y-63500D01*
X407733Y-63333D01*
X408400Y-62833D01*
X408733Y-62083D01*
Y-58500D01*
G01X410833D02*
Y-63500D01*
X414167D01*
G01X423200D02*
Y-59250D01*
X423367Y-58833D01*
X423700Y-58583D01*
X424200Y-58500D01*
X424700Y-58667D01*
X424950Y-59083D01*
G01X423950Y-60500D02*
X422283D01*
G01X429300Y-60167D02*
Y-63500D01*
G01Y-58833D02*
X429133Y-58750D01*
Y-58583D01*
X429300Y-58500D01*
X429467Y-58583D01*
Y-58750D01*
X429300Y-58833D01*
G01X434900Y-63500D02*
Y-58500D01*
G01X439250Y-61250D02*
X441917D01*
X441667Y-60667D01*
X441250Y-60333D01*
X440667Y-60167D01*
X440083Y-60250D01*
X439583Y-60500D01*
X439250Y-61083D01*
X439083Y-61583D01*
Y-62083D01*
X439250Y-62583D01*
X439667Y-63083D01*
X440167Y-63417D01*
X440750Y-63500D01*
X441333Y-63333D01*
X441917Y-62833D01*
G01X449783Y-63500D02*
Y-58500D01*
X453617Y-63500D01*
Y-58500D01*
G01X455883Y-60167D02*
Y-62500D01*
X456217Y-63083D01*
X456717Y-63417D01*
X457300Y-63500D01*
X457883Y-63417D01*
X458383Y-63083D01*
X458717Y-62500D01*
G01Y-63500D02*
Y-60167D01*
G01X460400Y-63500D02*
Y-60167D01*
G01Y-61083D02*
X460650Y-60667D01*
X461067Y-60333D01*
X461650Y-60167D01*
X462233Y-60333D01*
X462650Y-60667D01*
X462900Y-61083D01*
Y-63500D01*
G01Y-61083D02*
X463150Y-60667D01*
X463567Y-60333D01*
X464150Y-60167D01*
X464733Y-60333D01*
X465150Y-60667D01*
X465400Y-61167D01*
Y-63500D01*
G01X467000D02*
Y-58500D01*
G01Y-61000D02*
X467417Y-60500D01*
X467917Y-60250D01*
X468417Y-60167D01*
X469167Y-60333D01*
X469667Y-60667D01*
X470000Y-61250D01*
Y-61917D01*
X469833Y-62583D01*
X469500Y-63083D01*
X468917Y-63417D01*
X468417Y-63500D01*
X467917Y-63417D01*
X467417Y-63167D01*
X467000Y-62750D01*
G01X472850Y-61250D02*
X475517D01*
X475267Y-60667D01*
X474850Y-60333D01*
X474267Y-60167D01*
X473683Y-60250D01*
X473183Y-60500D01*
X472850Y-61083D01*
X472683Y-61583D01*
Y-62083D01*
X472850Y-62583D01*
X473267Y-63083D01*
X473767Y-63417D01*
X474350Y-63500D01*
X474933Y-63333D01*
X475517Y-62833D01*
G01X478533Y-63500D02*
Y-60167D01*
G01Y-60833D02*
X478950Y-60500D01*
X479367Y-60250D01*
X479950Y-60167D01*
X480367Y-60250D01*
X480867Y-60500D01*
G01X490900Y-60167D02*
Y-63500D01*
G01Y-58833D02*
X490733Y-58750D01*
Y-58583D01*
X490900Y-58500D01*
X491067Y-58583D01*
Y-58750D01*
X490900Y-58833D01*
G01X495083Y-63500D02*
Y-60167D01*
G01Y-61000D02*
X495417Y-60583D01*
X495917Y-60250D01*
X496583Y-60167D01*
X497167Y-60250D01*
X497667Y-60583D01*
X497917Y-61167D01*
Y-63500D01*
G01X506450Y-62917D02*
X506867Y-63250D01*
X507450Y-63500D01*
X507950D01*
X508450Y-63333D01*
X508783Y-63083D01*
X508950Y-62750D01*
X508867Y-62250D01*
X508533Y-62000D01*
X507033Y-61500D01*
X506700Y-60917D01*
X506867Y-60500D01*
X507200Y-60250D01*
X507700Y-60167D01*
X508200Y-60250D01*
X508700Y-60500D01*
G01X513300Y-60167D02*
Y-63500D01*
G01Y-58833D02*
X513133Y-58750D01*
Y-58583D01*
X513300Y-58500D01*
X513467Y-58583D01*
Y-58750D01*
X513300Y-58833D01*
G01X518900Y-63500D02*
Y-58500D01*
G01X523083Y-63500D02*
Y-58500D01*
G01X525750Y-60167D02*
X523083Y-62083D01*
G01X524167Y-61333D02*
X525917Y-63500D01*
G01X528850Y-62917D02*
X529267Y-63250D01*
X529850Y-63500D01*
X530350D01*
X530850Y-63333D01*
X531183Y-63083D01*
X531350Y-62750D01*
X531267Y-62250D01*
X530933Y-62000D01*
X529433Y-61500D01*
X529100Y-60917D01*
X529267Y-60500D01*
X529600Y-60250D01*
X530100Y-60167D01*
X530600Y-60250D01*
X531100Y-60500D01*
G01X537033Y-60583D02*
X536450Y-60250D01*
X535950Y-60167D01*
X535283Y-60333D01*
X534783Y-60667D01*
X534450Y-61250D01*
X534367Y-61833D01*
X534450Y-62417D01*
X534783Y-62917D01*
X535283Y-63333D01*
X535950Y-63500D01*
X536533Y-63333D01*
X537033Y-63000D01*
G01X540133Y-63500D02*
Y-60167D01*
G01Y-60833D02*
X540550Y-60500D01*
X540967Y-60250D01*
X541550Y-60167D01*
X541967Y-60250D01*
X542467Y-60500D01*
G01X545650Y-61250D02*
X548317D01*
X548067Y-60667D01*
X547650Y-60333D01*
X547067Y-60167D01*
X546483Y-60250D01*
X545983Y-60500D01*
X545650Y-61083D01*
X545483Y-61583D01*
Y-62083D01*
X545650Y-62583D01*
X546067Y-63083D01*
X546567Y-63417D01*
X547150Y-63500D01*
X547733Y-63333D01*
X548317Y-62833D01*
G01X551250Y-61250D02*
X553917D01*
X553667Y-60667D01*
X553250Y-60333D01*
X552667Y-60167D01*
X552083Y-60250D01*
X551583Y-60500D01*
X551250Y-61083D01*
X551083Y-61583D01*
Y-62083D01*
X551250Y-62583D01*
X551667Y-63083D01*
X552167Y-63417D01*
X552750Y-63500D01*
X553333Y-63333D01*
X553917Y-62833D01*
G01X556683Y-63500D02*
Y-60167D01*
G01Y-61000D02*
X557017Y-60583D01*
X557517Y-60250D01*
X558183Y-60167D01*
X558767Y-60250D01*
X559267Y-60583D01*
X559517Y-61167D01*
Y-63500D01*
G01X270750Y-47833D02*
X271417Y-48250D01*
X272167Y-48500D01*
X272833D01*
X273500Y-48250D01*
X274000Y-47833D01*
X274250Y-47250D01*
X274083Y-46667D01*
X273667Y-46167D01*
X272917Y-45833D01*
X271917Y-45667D01*
X271333Y-45333D01*
X271083Y-44750D01*
X271250Y-44167D01*
X271667Y-43750D01*
X272250Y-43500D01*
X272833D01*
X273417Y-43667D01*
X273917Y-44083D01*
G01X278100Y-48500D02*
X277600Y-48417D01*
X277100Y-48083D01*
X276767Y-47500D01*
X276600Y-46833D01*
X276767Y-46167D01*
X277100Y-45583D01*
X277600Y-45250D01*
X278100Y-45167D01*
X278600Y-45250D01*
X279100Y-45583D01*
X279433Y-46167D01*
X279517Y-46833D01*
X279433Y-47500D01*
X279100Y-48083D01*
X278600Y-48417D01*
X278100Y-48500D01*
G01X283700D02*
Y-43500D01*
G01X290800D02*
Y-48500D01*
G01Y-47750D02*
X290467Y-48167D01*
X289967Y-48417D01*
X289383Y-48500D01*
X288717Y-48333D01*
X288217Y-47917D01*
X287883Y-47417D01*
X287800Y-46833D01*
X287883Y-46250D01*
X288217Y-45750D01*
X288717Y-45333D01*
X289383Y-45167D01*
X289967Y-45250D01*
X290383Y-45417D01*
X290800Y-45750D01*
G01X293650Y-46250D02*
X296317D01*
X296067Y-45667D01*
X295650Y-45333D01*
X295067Y-45167D01*
X294483Y-45250D01*
X293983Y-45500D01*
X293650Y-46083D01*
X293483Y-46583D01*
Y-47083D01*
X293650Y-47583D01*
X294067Y-48083D01*
X294567Y-48417D01*
X295150Y-48500D01*
X295733Y-48333D01*
X296317Y-47833D01*
G01X299333Y-48500D02*
Y-45167D01*
G01Y-45833D02*
X299750Y-45500D01*
X300167Y-45250D01*
X300750Y-45167D01*
X301167Y-45250D01*
X301667Y-45500D01*
G01X309200Y-48500D02*
Y-45167D01*
G01Y-46083D02*
X309450Y-45667D01*
X309867Y-45333D01*
X310450Y-45167D01*
X311033Y-45333D01*
X311450Y-45667D01*
X311700Y-46083D01*
Y-48500D01*
G01Y-46083D02*
X311950Y-45667D01*
X312367Y-45333D01*
X312950Y-45167D01*
X313533Y-45333D01*
X313950Y-45667D01*
X314200Y-46167D01*
Y-48500D01*
G01X318800D02*
Y-45167D01*
G01Y-45750D02*
X318467Y-45417D01*
X317967Y-45250D01*
X317383Y-45167D01*
X316800Y-45333D01*
X316300Y-45667D01*
X315967Y-46167D01*
X315800Y-46833D01*
X315967Y-47500D01*
X316300Y-48000D01*
X316800Y-48333D01*
X317383Y-48500D01*
X317967Y-48417D01*
X318467Y-48167D01*
X318800Y-47833D01*
G01X321650Y-47917D02*
X322067Y-48250D01*
X322650Y-48500D01*
X323150D01*
X323650Y-48333D01*
X323983Y-48083D01*
X324150Y-47750D01*
X324067Y-47250D01*
X323733Y-47000D01*
X322233Y-46500D01*
X321900Y-45917D01*
X322067Y-45500D01*
X322400Y-45250D01*
X322900Y-45167D01*
X323400Y-45250D01*
X323900Y-45500D01*
G01X327083Y-48500D02*
Y-43500D01*
G01X329750Y-45167D02*
X327083Y-47083D01*
G01X328167Y-46333D02*
X329917Y-48500D01*
G01X339700Y-43500D02*
Y-48500D01*
G01X338533Y-45167D02*
X340867D01*
G01X343883Y-48500D02*
Y-43500D01*
G01Y-45917D02*
X344300Y-45500D01*
X344717Y-45250D01*
X345383Y-45167D01*
X345883Y-45250D01*
X346467Y-45583D01*
X346717Y-46083D01*
Y-48500D01*
G01X350900Y-45167D02*
Y-48500D01*
G01Y-43833D02*
X350733Y-43750D01*
Y-43583D01*
X350900Y-43500D01*
X351067Y-43583D01*
Y-43750D01*
X350900Y-43833D01*
G01X357833Y-45583D02*
X357250Y-45250D01*
X356750Y-45167D01*
X356083Y-45333D01*
X355583Y-45667D01*
X355250Y-46250D01*
X355167Y-46833D01*
X355250Y-47417D01*
X355583Y-47917D01*
X356083Y-48333D01*
X356750Y-48500D01*
X357333Y-48333D01*
X357833Y-48000D01*
G01X360683Y-48500D02*
Y-43500D01*
G01X363350Y-45167D02*
X360683Y-47083D01*
G01X361767Y-46333D02*
X363517Y-48500D01*
G01X366283D02*
Y-45167D01*
G01Y-46000D02*
X366617Y-45583D01*
X367117Y-45250D01*
X367783Y-45167D01*
X368367Y-45250D01*
X368867Y-45583D01*
X369117Y-46167D01*
Y-48500D01*
G01X372050Y-46250D02*
X374717D01*
X374467Y-45667D01*
X374050Y-45333D01*
X373467Y-45167D01*
X372883Y-45250D01*
X372383Y-45500D01*
X372050Y-46083D01*
X371883Y-46583D01*
Y-47083D01*
X372050Y-47583D01*
X372467Y-48083D01*
X372967Y-48417D01*
X373550Y-48500D01*
X374133Y-48333D01*
X374717Y-47833D01*
G01X377650Y-47917D02*
X378067Y-48250D01*
X378650Y-48500D01*
X379150D01*
X379650Y-48333D01*
X379983Y-48083D01*
X380150Y-47750D01*
X380067Y-47250D01*
X379733Y-47000D01*
X378233Y-46500D01*
X377900Y-45917D01*
X378067Y-45500D01*
X378400Y-45250D01*
X378900Y-45167D01*
X379400Y-45250D01*
X379900Y-45500D01*
G01X383250Y-47917D02*
X383667Y-48250D01*
X384250Y-48500D01*
X384750D01*
X385250Y-48333D01*
X385583Y-48083D01*
X385750Y-47750D01*
X385667Y-47250D01*
X385333Y-47000D01*
X383833Y-46500D01*
X383500Y-45917D01*
X383667Y-45500D01*
X384000Y-45250D01*
X384500Y-45167D01*
X385000Y-45250D01*
X385500Y-45500D01*
G01X394200Y-50167D02*
Y-45167D01*
G01Y-45917D02*
X394617Y-45500D01*
X395033Y-45250D01*
X395700Y-45167D01*
X396283Y-45250D01*
X396867Y-45667D01*
X397117Y-46250D01*
X397200Y-46833D01*
X397117Y-47417D01*
X396867Y-48000D01*
X396367Y-48333D01*
X395700Y-48500D01*
X395117Y-48417D01*
X394533Y-48167D01*
X394200Y-47833D01*
G01X401300Y-48500D02*
Y-43500D01*
G01X405483Y-45167D02*
Y-47500D01*
X405817Y-48083D01*
X406317Y-48417D01*
X406900Y-48500D01*
X407483Y-48417D01*
X407983Y-48083D01*
X408317Y-47500D01*
G01Y-48500D02*
Y-45167D01*
G01X411250Y-47917D02*
X411667Y-48250D01*
X412250Y-48500D01*
X412750D01*
X413250Y-48333D01*
X413583Y-48083D01*
X413750Y-47750D01*
X413667Y-47250D01*
X413333Y-47000D01*
X411833Y-46500D01*
X411500Y-45917D01*
X411667Y-45500D01*
X412000Y-45250D01*
X412500Y-45167D01*
X413000Y-45250D01*
X413500Y-45500D01*
G01X423700Y-48500D02*
Y-43500D01*
G01X428050Y-46250D02*
X430717D01*
X430467Y-45667D01*
X430050Y-45333D01*
X429467Y-45167D01*
X428883Y-45250D01*
X428383Y-45500D01*
X428050Y-46083D01*
X427883Y-46583D01*
Y-47083D01*
X428050Y-47583D01*
X428467Y-48083D01*
X428967Y-48417D01*
X429550Y-48500D01*
X430133Y-48333D01*
X430717Y-47833D01*
G01X433733Y-49750D02*
X434317Y-50083D01*
X434983Y-50167D01*
X435567Y-50083D01*
X436067Y-49667D01*
X436400Y-49083D01*
Y-45167D01*
G01Y-45833D02*
X436067Y-45500D01*
X435567Y-45250D01*
X434983Y-45167D01*
X434317Y-45333D01*
X433900Y-45667D01*
X433567Y-46250D01*
X433400Y-46833D01*
X433483Y-47333D01*
X433817Y-47917D01*
X434317Y-48333D01*
X434983Y-48500D01*
X435483Y-48417D01*
X436067Y-48083D01*
X436400Y-47750D01*
G01X439250Y-46250D02*
X441917D01*
X441667Y-45667D01*
X441250Y-45333D01*
X440667Y-45167D01*
X440083Y-45250D01*
X439583Y-45500D01*
X439250Y-46083D01*
X439083Y-46583D01*
Y-47083D01*
X439250Y-47583D01*
X439667Y-48083D01*
X440167Y-48417D01*
X440750Y-48500D01*
X441333Y-48333D01*
X441917Y-47833D01*
G01X444683Y-48500D02*
Y-45167D01*
G01Y-46000D02*
X445017Y-45583D01*
X445517Y-45250D01*
X446183Y-45167D01*
X446767Y-45250D01*
X447267Y-45583D01*
X447517Y-46167D01*
Y-48500D01*
G01X453200Y-43500D02*
Y-48500D01*
G01Y-47750D02*
X452867Y-48167D01*
X452367Y-48417D01*
X451783Y-48500D01*
X451117Y-48333D01*
X450617Y-47917D01*
X450283Y-47417D01*
X450200Y-46833D01*
X450283Y-46250D01*
X450617Y-45750D01*
X451117Y-45333D01*
X451783Y-45167D01*
X452367Y-45250D01*
X452783Y-45417D01*
X453200Y-45750D01*
G01X462900Y-43500D02*
Y-48500D01*
G01X461733Y-45167D02*
X464067D01*
G01X467083Y-48500D02*
Y-43500D01*
G01Y-45917D02*
X467500Y-45500D01*
X467917Y-45250D01*
X468583Y-45167D01*
X469083Y-45250D01*
X469667Y-45583D01*
X469917Y-46083D01*
Y-48500D01*
G01X474100Y-45167D02*
Y-48500D01*
G01Y-43833D02*
X473933Y-43750D01*
Y-43583D01*
X474100Y-43500D01*
X474267Y-43583D01*
Y-43750D01*
X474100Y-43833D01*
G01X481033Y-45583D02*
X480450Y-45250D01*
X479950Y-45167D01*
X479283Y-45333D01*
X478783Y-45667D01*
X478450Y-46250D01*
X478367Y-46833D01*
X478450Y-47417D01*
X478783Y-47917D01*
X479283Y-48333D01*
X479950Y-48500D01*
X480533Y-48333D01*
X481033Y-48000D01*
G01X483883Y-48500D02*
Y-43500D01*
G01X486550Y-45167D02*
X483883Y-47083D01*
G01X484967Y-46333D02*
X486717Y-48500D01*
G01X489483D02*
Y-45167D01*
G01Y-46000D02*
X489817Y-45583D01*
X490317Y-45250D01*
X490983Y-45167D01*
X491567Y-45250D01*
X492067Y-45583D01*
X492317Y-46167D01*
Y-48500D01*
G01X495250Y-46250D02*
X497917D01*
X497667Y-45667D01*
X497250Y-45333D01*
X496667Y-45167D01*
X496083Y-45250D01*
X495583Y-45500D01*
X495250Y-46083D01*
X495083Y-46583D01*
Y-47083D01*
X495250Y-47583D01*
X495667Y-48083D01*
X496167Y-48417D01*
X496750Y-48500D01*
X497333Y-48333D01*
X497917Y-47833D01*
G01X500850Y-47917D02*
X501267Y-48250D01*
X501850Y-48500D01*
X502350D01*
X502850Y-48333D01*
X503183Y-48083D01*
X503350Y-47750D01*
X503267Y-47250D01*
X502933Y-47000D01*
X501433Y-46500D01*
X501100Y-45917D01*
X501267Y-45500D01*
X501600Y-45250D01*
X502100Y-45167D01*
X502600Y-45250D01*
X503100Y-45500D01*
G01X506450Y-47917D02*
X506867Y-48250D01*
X507450Y-48500D01*
X507950D01*
X508450Y-48333D01*
X508783Y-48083D01*
X508950Y-47750D01*
X508867Y-47250D01*
X508533Y-47000D01*
X507033Y-46500D01*
X506700Y-45917D01*
X506867Y-45500D01*
X507200Y-45250D01*
X507700Y-45167D01*
X508200Y-45250D01*
X508700Y-45500D01*
G01X518900Y-48500D02*
X518400Y-48417D01*
X517900Y-48083D01*
X517567Y-47500D01*
X517400Y-46833D01*
X517567Y-46167D01*
X517900Y-45583D01*
X518400Y-45250D01*
X518900Y-45167D01*
X519400Y-45250D01*
X519900Y-45583D01*
X520233Y-46167D01*
X520317Y-46833D01*
X520233Y-47500D01*
X519900Y-48083D01*
X519400Y-48417D01*
X518900Y-48500D01*
G01X523083D02*
Y-45167D01*
G01Y-46000D02*
X523417Y-45583D01*
X523917Y-45250D01*
X524583Y-45167D01*
X525167Y-45250D01*
X525667Y-45583D01*
X525917Y-46167D01*
Y-48500D01*
G01X535700Y-43500D02*
Y-48500D01*
G01X534533Y-45167D02*
X536867D01*
G01X540133Y-48500D02*
Y-45167D01*
G01Y-45833D02*
X540550Y-45500D01*
X540967Y-45250D01*
X541550Y-45167D01*
X541967Y-45250D01*
X542467Y-45500D01*
G01X548400Y-48500D02*
Y-45167D01*
G01Y-45750D02*
X548067Y-45417D01*
X547567Y-45250D01*
X546983Y-45167D01*
X546400Y-45333D01*
X545900Y-45667D01*
X545567Y-46167D01*
X545400Y-46833D01*
X545567Y-47500D01*
X545900Y-48000D01*
X546400Y-48333D01*
X546983Y-48500D01*
X547567Y-48417D01*
X548067Y-48167D01*
X548400Y-47833D01*
G01X553833Y-45583D02*
X553250Y-45250D01*
X552750Y-45167D01*
X552083Y-45333D01*
X551583Y-45667D01*
X551250Y-46250D01*
X551167Y-46833D01*
X551250Y-47417D01*
X551583Y-47917D01*
X552083Y-48333D01*
X552750Y-48500D01*
X553333Y-48333D01*
X553833Y-48000D01*
G01X556850Y-46250D02*
X559517D01*
X559267Y-45667D01*
X558850Y-45333D01*
X558267Y-45167D01*
X557683Y-45250D01*
X557183Y-45500D01*
X556850Y-46083D01*
X556683Y-46583D01*
Y-47083D01*
X556850Y-47583D01*
X557267Y-48083D01*
X557767Y-48417D01*
X558350Y-48500D01*
X558933Y-48333D01*
X559517Y-47833D01*
G01X563700Y-48667D02*
X563533Y-48583D01*
Y-48417D01*
X563700Y-48333D01*
X563867Y-48417D01*
Y-48583D01*
X563700Y-48667D01*
G01X272500Y-33500D02*
Y-28500D01*
G01X276850Y-31250D02*
X279517D01*
X279267Y-30667D01*
X278850Y-30333D01*
X278267Y-30167D01*
X277683Y-30250D01*
X277183Y-30500D01*
X276850Y-31083D01*
X276683Y-31583D01*
Y-32083D01*
X276850Y-32583D01*
X277267Y-33083D01*
X277767Y-33417D01*
X278350Y-33500D01*
X278933Y-33333D01*
X279517Y-32833D01*
G01X282533Y-34750D02*
X283117Y-35083D01*
X283783Y-35167D01*
X284367Y-35083D01*
X284867Y-34667D01*
X285200Y-34083D01*
Y-30167D01*
G01Y-30833D02*
X284867Y-30500D01*
X284367Y-30250D01*
X283783Y-30167D01*
X283117Y-30333D01*
X282700Y-30667D01*
X282367Y-31250D01*
X282200Y-31833D01*
X282283Y-32333D01*
X282617Y-32917D01*
X283117Y-33333D01*
X283783Y-33500D01*
X284283Y-33417D01*
X284867Y-33083D01*
X285200Y-32750D01*
G01X288050Y-31250D02*
X290717D01*
X290467Y-30667D01*
X290050Y-30333D01*
X289467Y-30167D01*
X288883Y-30250D01*
X288383Y-30500D01*
X288050Y-31083D01*
X287883Y-31583D01*
Y-32083D01*
X288050Y-32583D01*
X288467Y-33083D01*
X288967Y-33417D01*
X289550Y-33500D01*
X290133Y-33333D01*
X290717Y-32833D01*
G01X293483Y-33500D02*
Y-30167D01*
G01Y-31000D02*
X293817Y-30583D01*
X294317Y-30250D01*
X294983Y-30167D01*
X295567Y-30250D01*
X296067Y-30583D01*
X296317Y-31167D01*
Y-33500D01*
G01X302000Y-28500D02*
Y-33500D01*
G01Y-32750D02*
X301667Y-33167D01*
X301167Y-33417D01*
X300583Y-33500D01*
X299917Y-33333D01*
X299417Y-32917D01*
X299083Y-32417D01*
X299000Y-31833D01*
X299083Y-31250D01*
X299417Y-30750D01*
X299917Y-30333D01*
X300583Y-30167D01*
X301167Y-30250D01*
X301583Y-30417D01*
X302000Y-30750D01*
G01X311700Y-28500D02*
Y-33500D01*
G01X310533Y-30167D02*
X312867D01*
G01X315883Y-33500D02*
Y-28500D01*
G01Y-30917D02*
X316300Y-30500D01*
X316717Y-30250D01*
X317383Y-30167D01*
X317883Y-30250D01*
X318467Y-30583D01*
X318717Y-31083D01*
Y-33500D01*
G01X322900Y-30167D02*
Y-33500D01*
G01Y-28833D02*
X322733Y-28750D01*
Y-28583D01*
X322900Y-28500D01*
X323067Y-28583D01*
Y-28750D01*
X322900Y-28833D01*
G01X329833Y-30583D02*
X329250Y-30250D01*
X328750Y-30167D01*
X328083Y-30333D01*
X327583Y-30667D01*
X327250Y-31250D01*
X327167Y-31833D01*
X327250Y-32417D01*
X327583Y-32917D01*
X328083Y-33333D01*
X328750Y-33500D01*
X329333Y-33333D01*
X329833Y-33000D01*
G01X332683Y-33500D02*
Y-28500D01*
G01X335350Y-30167D02*
X332683Y-32083D01*
G01X333767Y-31333D02*
X335517Y-33500D01*
G01X338283D02*
Y-30167D01*
G01Y-31000D02*
X338617Y-30583D01*
X339117Y-30250D01*
X339783Y-30167D01*
X340367Y-30250D01*
X340867Y-30583D01*
X341117Y-31167D01*
Y-33500D01*
G01X344050Y-31250D02*
X346717D01*
X346467Y-30667D01*
X346050Y-30333D01*
X345467Y-30167D01*
X344883Y-30250D01*
X344383Y-30500D01*
X344050Y-31083D01*
X343883Y-31583D01*
Y-32083D01*
X344050Y-32583D01*
X344467Y-33083D01*
X344967Y-33417D01*
X345550Y-33500D01*
X346133Y-33333D01*
X346717Y-32833D01*
G01X349650Y-32917D02*
X350067Y-33250D01*
X350650Y-33500D01*
X351150D01*
X351650Y-33333D01*
X351983Y-33083D01*
X352150Y-32750D01*
X352067Y-32250D01*
X351733Y-32000D01*
X350233Y-31500D01*
X349900Y-30917D01*
X350067Y-30500D01*
X350400Y-30250D01*
X350900Y-30167D01*
X351400Y-30250D01*
X351900Y-30500D01*
G01X355250Y-32917D02*
X355667Y-33250D01*
X356250Y-33500D01*
X356750D01*
X357250Y-33333D01*
X357583Y-33083D01*
X357750Y-32750D01*
X357667Y-32250D01*
X357333Y-32000D01*
X355833Y-31500D01*
X355500Y-30917D01*
X355667Y-30500D01*
X356000Y-30250D01*
X356500Y-30167D01*
X357000Y-30250D01*
X357500Y-30500D01*
G01X367700Y-33500D02*
X367200Y-33417D01*
X366700Y-33083D01*
X366367Y-32500D01*
X366200Y-31833D01*
X366367Y-31167D01*
X366700Y-30583D01*
X367200Y-30250D01*
X367700Y-30167D01*
X368200Y-30250D01*
X368700Y-30583D01*
X369033Y-31167D01*
X369117Y-31833D01*
X369033Y-32500D01*
X368700Y-33083D01*
X368200Y-33417D01*
X367700Y-33500D01*
G01X371883D02*
Y-30167D01*
G01Y-31000D02*
X372217Y-30583D01*
X372717Y-30250D01*
X373383Y-30167D01*
X373967Y-30250D01*
X374467Y-30583D01*
X374717Y-31167D01*
Y-33500D01*
G01X385833Y-30583D02*
X385250Y-30250D01*
X384750Y-30167D01*
X384083Y-30333D01*
X383583Y-30667D01*
X383250Y-31250D01*
X383167Y-31833D01*
X383250Y-32417D01*
X383583Y-32917D01*
X384083Y-33333D01*
X384750Y-33500D01*
X385333Y-33333D01*
X385833Y-33000D01*
G01X390100Y-33500D02*
X389600Y-33417D01*
X389100Y-33083D01*
X388767Y-32500D01*
X388600Y-31833D01*
X388767Y-31167D01*
X389100Y-30583D01*
X389600Y-30250D01*
X390100Y-30167D01*
X390600Y-30250D01*
X391100Y-30583D01*
X391433Y-31167D01*
X391517Y-31833D01*
X391433Y-32500D01*
X391100Y-33083D01*
X390600Y-33417D01*
X390100Y-33500D01*
G01X394200Y-35167D02*
Y-30167D01*
G01Y-30917D02*
X394617Y-30500D01*
X395033Y-30250D01*
X395700Y-30167D01*
X396283Y-30250D01*
X396867Y-30667D01*
X397117Y-31250D01*
X397200Y-31833D01*
X397117Y-32417D01*
X396867Y-33000D01*
X396367Y-33333D01*
X395700Y-33500D01*
X395117Y-33417D01*
X394533Y-33167D01*
X394200Y-32833D01*
G01X399800Y-35167D02*
Y-30167D01*
G01Y-30917D02*
X400217Y-30500D01*
X400633Y-30250D01*
X401300Y-30167D01*
X401883Y-30250D01*
X402467Y-30667D01*
X402717Y-31250D01*
X402800Y-31833D01*
X402717Y-32417D01*
X402467Y-33000D01*
X401967Y-33333D01*
X401300Y-33500D01*
X400717Y-33417D01*
X400133Y-33167D01*
X399800Y-32833D01*
G01X405650Y-31250D02*
X408317D01*
X408067Y-30667D01*
X407650Y-30333D01*
X407067Y-30167D01*
X406483Y-30250D01*
X405983Y-30500D01*
X405650Y-31083D01*
X405483Y-31583D01*
Y-32083D01*
X405650Y-32583D01*
X406067Y-33083D01*
X406567Y-33417D01*
X407150Y-33500D01*
X407733Y-33333D01*
X408317Y-32833D01*
G01X411333Y-33500D02*
Y-30167D01*
G01Y-30833D02*
X411750Y-30500D01*
X412167Y-30250D01*
X412750Y-30167D01*
X413167Y-30250D01*
X413667Y-30500D01*
G01X423283Y-35167D02*
X422450Y-34333D01*
X422033Y-33500D01*
Y-30167D01*
X422450Y-29333D01*
X423283Y-28500D01*
G01X427217Y-30167D02*
X428217Y-33500D01*
X429300Y-30167D01*
X430383Y-33500D01*
X431383Y-30167D01*
G01X433483Y-33500D02*
Y-28500D01*
G01Y-30917D02*
X433900Y-30500D01*
X434317Y-30250D01*
X434983Y-30167D01*
X435483Y-30250D01*
X436067Y-30583D01*
X436317Y-31083D01*
Y-33500D01*
G01X440500Y-30167D02*
Y-33500D01*
G01Y-28833D02*
X440333Y-28750D01*
Y-28583D01*
X440500Y-28500D01*
X440667Y-28583D01*
Y-28750D01*
X440500Y-28833D01*
G01X447433Y-30583D02*
X446850Y-30250D01*
X446350Y-30167D01*
X445683Y-30333D01*
X445183Y-30667D01*
X444850Y-31250D01*
X444767Y-31833D01*
X444850Y-32417D01*
X445183Y-32917D01*
X445683Y-33333D01*
X446350Y-33500D01*
X446933Y-33333D01*
X447433Y-33000D01*
G01X450283Y-33500D02*
Y-28500D01*
G01Y-30917D02*
X450700Y-30500D01*
X451117Y-30250D01*
X451783Y-30167D01*
X452283Y-30250D01*
X452867Y-30583D01*
X453117Y-31083D01*
Y-33500D01*
G01X462900Y-30167D02*
Y-33500D01*
G01Y-28833D02*
X462733Y-28750D01*
Y-28583D01*
X462900Y-28500D01*
X463067Y-28583D01*
Y-28750D01*
X462900Y-28833D01*
G01X467250Y-32917D02*
X467667Y-33250D01*
X468250Y-33500D01*
X468750D01*
X469250Y-33333D01*
X469583Y-33083D01*
X469750Y-32750D01*
X469667Y-32250D01*
X469333Y-32000D01*
X467833Y-31500D01*
X467500Y-30917D01*
X467667Y-30500D01*
X468000Y-30250D01*
X468500Y-30167D01*
X469000Y-30250D01*
X469500Y-30500D01*
G01X478200Y-33500D02*
Y-28500D01*
G01Y-31000D02*
X478617Y-30500D01*
X479117Y-30250D01*
X479617Y-30167D01*
X480367Y-30333D01*
X480867Y-30667D01*
X481200Y-31250D01*
Y-31917D01*
X481033Y-32583D01*
X480700Y-33083D01*
X480117Y-33417D01*
X479617Y-33500D01*
X479117Y-33417D01*
X478617Y-33167D01*
X478200Y-32750D01*
G01X484050Y-31250D02*
X486717D01*
X486467Y-30667D01*
X486050Y-30333D01*
X485467Y-30167D01*
X484883Y-30250D01*
X484383Y-30500D01*
X484050Y-31083D01*
X483883Y-31583D01*
Y-32083D01*
X484050Y-32583D01*
X484467Y-33083D01*
X484967Y-33417D01*
X485550Y-33500D01*
X486133Y-33333D01*
X486717Y-32833D01*
G01X490900Y-28500D02*
Y-33500D01*
G01X489733Y-30167D02*
X492067D01*
G01X496500Y-28500D02*
Y-33500D01*
G01X495333Y-30167D02*
X497667D01*
G01X500850Y-31250D02*
X503517D01*
X503267Y-30667D01*
X502850Y-30333D01*
X502267Y-30167D01*
X501683Y-30250D01*
X501183Y-30500D01*
X500850Y-31083D01*
X500683Y-31583D01*
Y-32083D01*
X500850Y-32583D01*
X501267Y-33083D01*
X501767Y-33417D01*
X502350Y-33500D01*
X502933Y-33333D01*
X503517Y-32833D01*
G01X506533Y-33500D02*
Y-30167D01*
G01Y-30833D02*
X506950Y-30500D01*
X507367Y-30250D01*
X507950Y-30167D01*
X508367Y-30250D01*
X508867Y-30500D01*
G01X513717Y-35167D02*
X514550Y-34333D01*
X514967Y-33500D01*
Y-30167D01*
X514550Y-29333D01*
X513717Y-28500D01*
G01X271250Y-19417D02*
X271667Y-19750D01*
X272250Y-20000D01*
X272750D01*
X273250Y-19833D01*
X273583Y-19583D01*
X273750Y-19250D01*
X273667Y-18750D01*
X273333Y-18500D01*
X271833Y-18000D01*
X271500Y-17417D01*
X271667Y-17000D01*
X272000Y-16750D01*
X272500Y-16667D01*
X273000Y-16750D01*
X273500Y-17000D01*
G01X278100Y-20000D02*
X277600Y-19917D01*
X277100Y-19583D01*
X276767Y-19000D01*
X276600Y-18333D01*
X276767Y-17667D01*
X277100Y-17083D01*
X277600Y-16750D01*
X278100Y-16667D01*
X278600Y-16750D01*
X279100Y-17083D01*
X279433Y-17667D01*
X279517Y-18333D01*
X279433Y-19000D01*
X279100Y-19583D01*
X278600Y-19917D01*
X278100Y-20000D01*
G01X283700D02*
Y-15000D01*
G01X290800D02*
Y-20000D01*
G01Y-19250D02*
X290467Y-19667D01*
X289967Y-19917D01*
X289383Y-20000D01*
X288717Y-19833D01*
X288217Y-19417D01*
X287883Y-18917D01*
X287800Y-18333D01*
X287883Y-17750D01*
X288217Y-17250D01*
X288717Y-16833D01*
X289383Y-16667D01*
X289967Y-16750D01*
X290383Y-16917D01*
X290800Y-17250D01*
G01X293650Y-17750D02*
X296317D01*
X296067Y-17167D01*
X295650Y-16833D01*
X295067Y-16667D01*
X294483Y-16750D01*
X293983Y-17000D01*
X293650Y-17583D01*
X293483Y-18083D01*
Y-18583D01*
X293650Y-19083D01*
X294067Y-19583D01*
X294567Y-19917D01*
X295150Y-20000D01*
X295733Y-19833D01*
X296317Y-19333D01*
G01X299333Y-20000D02*
Y-16667D01*
G01Y-17333D02*
X299750Y-17000D01*
X300167Y-16750D01*
X300750Y-16667D01*
X301167Y-16750D01*
X301667Y-17000D01*
G01X309200Y-20000D02*
Y-16667D01*
G01Y-17583D02*
X309450Y-17167D01*
X309867Y-16833D01*
X310450Y-16667D01*
X311033Y-16833D01*
X311450Y-17167D01*
X311700Y-17583D01*
Y-20000D01*
G01Y-17583D02*
X311950Y-17167D01*
X312367Y-16833D01*
X312950Y-16667D01*
X313533Y-16833D01*
X313950Y-17167D01*
X314200Y-17667D01*
Y-20000D01*
G01X318800D02*
Y-16667D01*
G01Y-17250D02*
X318467Y-16917D01*
X317967Y-16750D01*
X317383Y-16667D01*
X316800Y-16833D01*
X316300Y-17167D01*
X315967Y-17667D01*
X315800Y-18333D01*
X315967Y-19000D01*
X316300Y-19500D01*
X316800Y-19833D01*
X317383Y-20000D01*
X317967Y-19917D01*
X318467Y-19667D01*
X318800Y-19333D01*
G01X321650Y-19417D02*
X322067Y-19750D01*
X322650Y-20000D01*
X323150D01*
X323650Y-19833D01*
X323983Y-19583D01*
X324150Y-19250D01*
X324067Y-18750D01*
X323733Y-18500D01*
X322233Y-18000D01*
X321900Y-17417D01*
X322067Y-17000D01*
X322400Y-16750D01*
X322900Y-16667D01*
X323400Y-16750D01*
X323900Y-17000D01*
G01X327083Y-20000D02*
Y-15000D01*
G01X329750Y-16667D02*
X327083Y-18583D01*
G01X328167Y-17833D02*
X329917Y-20000D01*
G01X339700Y-15000D02*
Y-20000D01*
G01X338533Y-16667D02*
X340867D01*
G01X343883Y-20000D02*
Y-15000D01*
G01Y-17417D02*
X344300Y-17000D01*
X344717Y-16750D01*
X345383Y-16667D01*
X345883Y-16750D01*
X346467Y-17083D01*
X346717Y-17583D01*
Y-20000D01*
G01X350900Y-16667D02*
Y-20000D01*
G01Y-15333D02*
X350733Y-15250D01*
Y-15083D01*
X350900Y-15000D01*
X351067Y-15083D01*
Y-15250D01*
X350900Y-15333D01*
G01X357833Y-17083D02*
X357250Y-16750D01*
X356750Y-16667D01*
X356083Y-16833D01*
X355583Y-17167D01*
X355250Y-17750D01*
X355167Y-18333D01*
X355250Y-18917D01*
X355583Y-19417D01*
X356083Y-19833D01*
X356750Y-20000D01*
X357333Y-19833D01*
X357833Y-19500D01*
G01X360683Y-20000D02*
Y-15000D01*
G01X363350Y-16667D02*
X360683Y-18583D01*
G01X361767Y-17833D02*
X363517Y-20000D01*
G01X366283D02*
Y-16667D01*
G01Y-17500D02*
X366617Y-17083D01*
X367117Y-16750D01*
X367783Y-16667D01*
X368367Y-16750D01*
X368867Y-17083D01*
X369117Y-17667D01*
Y-20000D01*
G01X372050Y-17750D02*
X374717D01*
X374467Y-17167D01*
X374050Y-16833D01*
X373467Y-16667D01*
X372883Y-16750D01*
X372383Y-17000D01*
X372050Y-17583D01*
X371883Y-18083D01*
Y-18583D01*
X372050Y-19083D01*
X372467Y-19583D01*
X372967Y-19917D01*
X373550Y-20000D01*
X374133Y-19833D01*
X374717Y-19333D01*
G01X377650Y-19417D02*
X378067Y-19750D01*
X378650Y-20000D01*
X379150D01*
X379650Y-19833D01*
X379983Y-19583D01*
X380150Y-19250D01*
X380067Y-18750D01*
X379733Y-18500D01*
X378233Y-18000D01*
X377900Y-17417D01*
X378067Y-17000D01*
X378400Y-16750D01*
X378900Y-16667D01*
X379400Y-16750D01*
X379900Y-17000D01*
G01X383250Y-19417D02*
X383667Y-19750D01*
X384250Y-20000D01*
X384750D01*
X385250Y-19833D01*
X385583Y-19583D01*
X385750Y-19250D01*
X385667Y-18750D01*
X385333Y-18500D01*
X383833Y-18000D01*
X383500Y-17417D01*
X383667Y-17000D01*
X384000Y-16750D01*
X384500Y-16667D01*
X385000Y-16750D01*
X385500Y-17000D01*
G01X264000Y-39500D02*
X694500D01*
G01X262500Y-69500D02*
Y439000D01*
G01X272500Y0D02*
Y-5000D01*
G01X270583Y0D02*
X274417D01*
G01X276683Y-5000D02*
Y0D01*
G01Y-2417D02*
X277100Y-2000D01*
X277517Y-1750D01*
X278183Y-1667D01*
X278683Y-1750D01*
X279267Y-2083D01*
X279517Y-2583D01*
Y-5000D01*
G01X282450Y-2750D02*
X285117D01*
X284867Y-2167D01*
X284450Y-1833D01*
X283867Y-1667D01*
X283283Y-1750D01*
X282783Y-2000D01*
X282450Y-2583D01*
X282283Y-3083D01*
Y-3583D01*
X282450Y-4083D01*
X282867Y-4583D01*
X283367Y-4917D01*
X283950Y-5000D01*
X284533Y-4833D01*
X285117Y-4333D01*
G01X294900Y-5000D02*
Y0D01*
G01X302000Y-5000D02*
Y-1667D01*
G01Y-2250D02*
X301667Y-1917D01*
X301167Y-1750D01*
X300583Y-1667D01*
X300000Y-1833D01*
X299500Y-2167D01*
X299167Y-2667D01*
X299000Y-3333D01*
X299167Y-4000D01*
X299500Y-4500D01*
X300000Y-4833D01*
X300583Y-5000D01*
X301167Y-4917D01*
X301667Y-4667D01*
X302000Y-4333D01*
G01X304933Y-5000D02*
Y-1667D01*
G01Y-2333D02*
X305350Y-2000D01*
X305767Y-1750D01*
X306350Y-1667D01*
X306767Y-1750D01*
X307267Y-2000D01*
G01X310533Y-6250D02*
X311117Y-6583D01*
X311783Y-6667D01*
X312367Y-6583D01*
X312867Y-6167D01*
X313200Y-5583D01*
Y-1667D01*
G01Y-2333D02*
X312867Y-2000D01*
X312367Y-1750D01*
X311783Y-1667D01*
X311117Y-1833D01*
X310700Y-2167D01*
X310367Y-2750D01*
X310200Y-3333D01*
X310283Y-3833D01*
X310617Y-4417D01*
X311117Y-4833D01*
X311783Y-5000D01*
X312283Y-4917D01*
X312867Y-4583D01*
X313200Y-4250D01*
G01X316050Y-2750D02*
X318717D01*
X318467Y-2167D01*
X318050Y-1833D01*
X317467Y-1667D01*
X316883Y-1750D01*
X316383Y-2000D01*
X316050Y-2583D01*
X315883Y-3083D01*
Y-3583D01*
X316050Y-4083D01*
X316467Y-4583D01*
X316967Y-4917D01*
X317550Y-5000D01*
X318133Y-4833D01*
X318717Y-4333D01*
G01X321650Y-4417D02*
X322067Y-4750D01*
X322650Y-5000D01*
X323150D01*
X323650Y-4833D01*
X323983Y-4583D01*
X324150Y-4250D01*
X324067Y-3750D01*
X323733Y-3500D01*
X322233Y-3000D01*
X321900Y-2417D01*
X322067Y-2000D01*
X322400Y-1750D01*
X322900Y-1667D01*
X323400Y-1750D01*
X323900Y-2000D01*
G01X328500Y0D02*
Y-5000D01*
G01X327333Y-1667D02*
X329667D01*
G01X341200Y0D02*
Y-5000D01*
G01Y-4250D02*
X340867Y-4667D01*
X340367Y-4917D01*
X339783Y-5000D01*
X339117Y-4833D01*
X338617Y-4417D01*
X338283Y-3917D01*
X338200Y-3333D01*
X338283Y-2750D01*
X338617Y-2250D01*
X339117Y-1833D01*
X339783Y-1667D01*
X340367Y-1750D01*
X340783Y-1917D01*
X341200Y-2250D01*
G01X345300Y-1667D02*
Y-5000D01*
G01Y-333D02*
X345133Y-250D01*
Y-83D01*
X345300Y0D01*
X345467Y-83D01*
Y-250D01*
X345300Y-333D01*
G01X348400Y-5000D02*
Y-1667D01*
G01Y-2583D02*
X348650Y-2167D01*
X349067Y-1833D01*
X349650Y-1667D01*
X350233Y-1833D01*
X350650Y-2167D01*
X350900Y-2583D01*
Y-5000D01*
G01Y-2583D02*
X351150Y-2167D01*
X351567Y-1833D01*
X352150Y-1667D01*
X352733Y-1833D01*
X353150Y-2167D01*
X353400Y-2667D01*
Y-5000D01*
G01X355250Y-2750D02*
X357917D01*
X357667Y-2167D01*
X357250Y-1833D01*
X356667Y-1667D01*
X356083Y-1750D01*
X355583Y-2000D01*
X355250Y-2583D01*
X355083Y-3083D01*
Y-3583D01*
X355250Y-4083D01*
X355667Y-4583D01*
X356167Y-4917D01*
X356750Y-5000D01*
X357333Y-4833D01*
X357917Y-4333D01*
G01X360683Y-5000D02*
Y-1667D01*
G01Y-2500D02*
X361017Y-2083D01*
X361517Y-1750D01*
X362183Y-1667D01*
X362767Y-1750D01*
X363267Y-2083D01*
X363517Y-2667D01*
Y-5000D01*
G01X366450Y-4417D02*
X366867Y-4750D01*
X367450Y-5000D01*
X367950D01*
X368450Y-4833D01*
X368783Y-4583D01*
X368950Y-4250D01*
X368867Y-3750D01*
X368533Y-3500D01*
X367033Y-3000D01*
X366700Y-2417D01*
X366867Y-2000D01*
X367200Y-1750D01*
X367700Y-1667D01*
X368200Y-1750D01*
X368700Y-2000D01*
G01X373300Y-1667D02*
Y-5000D01*
G01Y-333D02*
X373133Y-250D01*
Y-83D01*
X373300Y0D01*
X373467Y-83D01*
Y-250D01*
X373300Y-333D01*
G01X378900Y-5000D02*
X378400Y-4917D01*
X377900Y-4583D01*
X377567Y-4000D01*
X377400Y-3333D01*
X377567Y-2667D01*
X377900Y-2083D01*
X378400Y-1750D01*
X378900Y-1667D01*
X379400Y-1750D01*
X379900Y-2083D01*
X380233Y-2667D01*
X380317Y-3333D01*
X380233Y-4000D01*
X379900Y-4583D01*
X379400Y-4917D01*
X378900Y-5000D01*
G01X383083D02*
Y-1667D01*
G01Y-2500D02*
X383417Y-2083D01*
X383917Y-1750D01*
X384583Y-1667D01*
X385167Y-1750D01*
X385667Y-2083D01*
X385917Y-2667D01*
Y-5000D01*
G01X395700D02*
X395200Y-4917D01*
X394700Y-4583D01*
X394367Y-4000D01*
X394200Y-3333D01*
X394367Y-2667D01*
X394700Y-2083D01*
X395200Y-1750D01*
X395700Y-1667D01*
X396200Y-1750D01*
X396700Y-2083D01*
X397033Y-2667D01*
X397117Y-3333D01*
X397033Y-4000D01*
X396700Y-4583D01*
X396200Y-4917D01*
X395700Y-5000D01*
G01X400800D02*
Y-750D01*
X400967Y-333D01*
X401300Y-83D01*
X401800Y0D01*
X402300Y-167D01*
X402550Y-583D01*
G01X401550Y-2000D02*
X399883D01*
G01X411000Y-6667D02*
Y-1667D01*
G01Y-2417D02*
X411417Y-2000D01*
X411833Y-1750D01*
X412500Y-1667D01*
X413083Y-1750D01*
X413667Y-2167D01*
X413917Y-2750D01*
X414000Y-3333D01*
X413917Y-3917D01*
X413667Y-4500D01*
X413167Y-4833D01*
X412500Y-5000D01*
X411917Y-4917D01*
X411333Y-4667D01*
X411000Y-4333D01*
G01X419600Y-5000D02*
Y-1667D01*
G01Y-2250D02*
X419267Y-1917D01*
X418767Y-1750D01*
X418183Y-1667D01*
X417600Y-1833D01*
X417100Y-2167D01*
X416767Y-2667D01*
X416600Y-3333D01*
X416767Y-4000D01*
X417100Y-4500D01*
X417600Y-4833D01*
X418183Y-5000D01*
X418767Y-4917D01*
X419267Y-4667D01*
X419600Y-4333D01*
G01X425200Y0D02*
Y-5000D01*
G01Y-4250D02*
X424867Y-4667D01*
X424367Y-4917D01*
X423783Y-5000D01*
X423117Y-4833D01*
X422617Y-4417D01*
X422283Y-3917D01*
X422200Y-3333D01*
X422283Y-2750D01*
X422617Y-2250D01*
X423117Y-1833D01*
X423783Y-1667D01*
X424367Y-1750D01*
X424783Y-1917D01*
X425200Y-2250D01*
G01X434900Y-5000D02*
X434400Y-4917D01*
X433900Y-4583D01*
X433567Y-4000D01*
X433400Y-3333D01*
X433567Y-2667D01*
X433900Y-2083D01*
X434400Y-1750D01*
X434900Y-1667D01*
X435400Y-1750D01*
X435900Y-2083D01*
X436233Y-2667D01*
X436317Y-3333D01*
X436233Y-4000D01*
X435900Y-4583D01*
X435400Y-4917D01*
X434900Y-5000D01*
G01X439333D02*
Y-1667D01*
G01Y-2333D02*
X439750Y-2000D01*
X440167Y-1750D01*
X440750Y-1667D01*
X441167Y-1750D01*
X441667Y-2000D01*
G01X453200Y0D02*
Y-5000D01*
G01Y-4250D02*
X452867Y-4667D01*
X452367Y-4917D01*
X451783Y-5000D01*
X451117Y-4833D01*
X450617Y-4417D01*
X450283Y-3917D01*
X450200Y-3333D01*
X450283Y-2750D01*
X450617Y-2250D01*
X451117Y-1833D01*
X451783Y-1667D01*
X452367Y-1750D01*
X452783Y-1917D01*
X453200Y-2250D01*
G01X457300Y-1667D02*
Y-5000D01*
G01Y-333D02*
X457133Y-250D01*
Y-83D01*
X457300Y0D01*
X457467Y-83D01*
Y-250D01*
X457300Y-333D01*
G01X464400Y-5000D02*
Y-1667D01*
G01Y-2250D02*
X464067Y-1917D01*
X463567Y-1750D01*
X462983Y-1667D01*
X462400Y-1833D01*
X461900Y-2167D01*
X461567Y-2667D01*
X461400Y-3333D01*
X461567Y-4000D01*
X461900Y-4500D01*
X462400Y-4833D01*
X462983Y-5000D01*
X463567Y-4917D01*
X464067Y-4667D01*
X464400Y-4333D01*
G01X466000Y-5000D02*
Y-1667D01*
G01Y-2583D02*
X466250Y-2167D01*
X466667Y-1833D01*
X467250Y-1667D01*
X467833Y-1833D01*
X468250Y-2167D01*
X468500Y-2583D01*
Y-5000D01*
G01Y-2583D02*
X468750Y-2167D01*
X469167Y-1833D01*
X469750Y-1667D01*
X470333Y-1833D01*
X470750Y-2167D01*
X471000Y-2667D01*
Y-5000D01*
G01X472850Y-2750D02*
X475517D01*
X475267Y-2167D01*
X474850Y-1833D01*
X474267Y-1667D01*
X473683Y-1750D01*
X473183Y-2000D01*
X472850Y-2583D01*
X472683Y-3083D01*
Y-3583D01*
X472850Y-4083D01*
X473267Y-4583D01*
X473767Y-4917D01*
X474350Y-5000D01*
X474933Y-4833D01*
X475517Y-4333D01*
G01X479700Y0D02*
Y-5000D01*
G01X478533Y-1667D02*
X480867D01*
G01X484050Y-2750D02*
X486717D01*
X486467Y-2167D01*
X486050Y-1833D01*
X485467Y-1667D01*
X484883Y-1750D01*
X484383Y-2000D01*
X484050Y-2583D01*
X483883Y-3083D01*
Y-3583D01*
X484050Y-4083D01*
X484467Y-4583D01*
X484967Y-4917D01*
X485550Y-5000D01*
X486133Y-4833D01*
X486717Y-4333D01*
G01X489733Y-5000D02*
Y-1667D01*
G01Y-2333D02*
X490150Y-2000D01*
X490567Y-1750D01*
X491150Y-1667D01*
X491567Y-1750D01*
X492067Y-2000D01*
G01X503767Y-5000D02*
X500433Y-3333D01*
X503767Y-1667D01*
G01X506617Y-4083D02*
X508783D01*
G01Y-2583D02*
X506617D01*
G01X518900Y-5000D02*
Y0D01*
X517900Y-1000D01*
G01Y-5000D02*
X519900D01*
G01X525500D02*
Y0D01*
X522417Y-3583D01*
X526583D01*
G01X533200Y-5000D02*
Y-1667D01*
G01Y-2583D02*
X533450Y-2167D01*
X533867Y-1833D01*
X534450Y-1667D01*
X535033Y-1833D01*
X535450Y-2167D01*
X535700Y-2583D01*
Y-5000D01*
G01Y-2583D02*
X535950Y-2167D01*
X536367Y-1833D01*
X536950Y-1667D01*
X537533Y-1833D01*
X537950Y-2167D01*
X538200Y-2667D01*
Y-5000D01*
G01X541300Y-1667D02*
Y-5000D01*
G01Y-333D02*
X541133Y-250D01*
Y-83D01*
X541300Y0D01*
X541467Y-83D01*
Y-250D01*
X541300Y-333D01*
G01X546900Y-5000D02*
Y0D01*
G01X272500Y52000D02*
Y47000D01*
G01X270583Y52000D02*
X274417D01*
G01X276683Y47000D02*
Y52000D01*
G01Y49583D02*
X277100Y50000D01*
X277517Y50250D01*
X278183Y50333D01*
X278683Y50250D01*
X279267Y49917D01*
X279517Y49417D01*
Y47000D01*
G01X282450Y49250D02*
X285117D01*
X284867Y49833D01*
X284450Y50167D01*
X283867Y50333D01*
X283283Y50250D01*
X282783Y50000D01*
X282450Y49417D01*
X282283Y48917D01*
Y48417D01*
X282450Y47917D01*
X282867Y47417D01*
X283367Y47083D01*
X283950Y47000D01*
X284533Y47167D01*
X285117Y47667D01*
G01X294900Y47000D02*
Y52000D01*
G01X302000Y47000D02*
Y50333D01*
G01Y49750D02*
X301667Y50083D01*
X301167Y50250D01*
X300583Y50333D01*
X300000Y50167D01*
X299500Y49833D01*
X299167Y49333D01*
X299000Y48667D01*
X299167Y48000D01*
X299500Y47500D01*
X300000Y47167D01*
X300583Y47000D01*
X301167Y47083D01*
X301667Y47333D01*
X302000Y47667D01*
G01X304933Y47000D02*
Y50333D01*
G01Y49667D02*
X305350Y50000D01*
X305767Y50250D01*
X306350Y50333D01*
X306767Y50250D01*
X307267Y50000D01*
G01X310533Y45750D02*
X311117Y45417D01*
X311783Y45333D01*
X312367Y45417D01*
X312867Y45833D01*
X313200Y46417D01*
Y50333D01*
G01Y49667D02*
X312867Y50000D01*
X312367Y50250D01*
X311783Y50333D01*
X311117Y50167D01*
X310700Y49833D01*
X310367Y49250D01*
X310200Y48667D01*
X310283Y48167D01*
X310617Y47583D01*
X311117Y47167D01*
X311783Y47000D01*
X312283Y47083D01*
X312867Y47417D01*
X313200Y47750D01*
G01X316050Y49250D02*
X318717D01*
X318467Y49833D01*
X318050Y50167D01*
X317467Y50333D01*
X316883Y50250D01*
X316383Y50000D01*
X316050Y49417D01*
X315883Y48917D01*
Y48417D01*
X316050Y47917D01*
X316467Y47417D01*
X316967Y47083D01*
X317550Y47000D01*
X318133Y47167D01*
X318717Y47667D01*
G01X321650Y47583D02*
X322067Y47250D01*
X322650Y47000D01*
X323150D01*
X323650Y47167D01*
X323983Y47417D01*
X324150Y47750D01*
X324067Y48250D01*
X323733Y48500D01*
X322233Y49000D01*
X321900Y49583D01*
X322067Y50000D01*
X322400Y50250D01*
X322900Y50333D01*
X323400Y50250D01*
X323900Y50000D01*
G01X328500Y52000D02*
Y47000D01*
G01X327333Y50333D02*
X329667D01*
G01X341200Y52000D02*
Y47000D01*
G01Y47750D02*
X340867Y47333D01*
X340367Y47083D01*
X339783Y47000D01*
X339117Y47167D01*
X338617Y47583D01*
X338283Y48083D01*
X338200Y48667D01*
X338283Y49250D01*
X338617Y49750D01*
X339117Y50167D01*
X339783Y50333D01*
X340367Y50250D01*
X340783Y50083D01*
X341200Y49750D01*
G01X345300Y50333D02*
Y47000D01*
G01Y51667D02*
X345133Y51750D01*
Y51917D01*
X345300Y52000D01*
X345467Y51917D01*
Y51750D01*
X345300Y51667D01*
G01X348400Y47000D02*
Y50333D01*
G01Y49417D02*
X348650Y49833D01*
X349067Y50167D01*
X349650Y50333D01*
X350233Y50167D01*
X350650Y49833D01*
X350900Y49417D01*
Y47000D01*
G01Y49417D02*
X351150Y49833D01*
X351567Y50167D01*
X352150Y50333D01*
X352733Y50167D01*
X353150Y49833D01*
X353400Y49333D01*
Y47000D01*
G01X355250Y49250D02*
X357917D01*
X357667Y49833D01*
X357250Y50167D01*
X356667Y50333D01*
X356083Y50250D01*
X355583Y50000D01*
X355250Y49417D01*
X355083Y48917D01*
Y48417D01*
X355250Y47917D01*
X355667Y47417D01*
X356167Y47083D01*
X356750Y47000D01*
X357333Y47167D01*
X357917Y47667D01*
G01X360683Y47000D02*
Y50333D01*
G01Y49500D02*
X361017Y49917D01*
X361517Y50250D01*
X362183Y50333D01*
X362767Y50250D01*
X363267Y49917D01*
X363517Y49333D01*
Y47000D01*
G01X366450Y47583D02*
X366867Y47250D01*
X367450Y47000D01*
X367950D01*
X368450Y47167D01*
X368783Y47417D01*
X368950Y47750D01*
X368867Y48250D01*
X368533Y48500D01*
X367033Y49000D01*
X366700Y49583D01*
X366867Y50000D01*
X367200Y50250D01*
X367700Y50333D01*
X368200Y50250D01*
X368700Y50000D01*
G01X373300Y50333D02*
Y47000D01*
G01Y51667D02*
X373133Y51750D01*
Y51917D01*
X373300Y52000D01*
X373467Y51917D01*
Y51750D01*
X373300Y51667D01*
G01X378900Y47000D02*
X378400Y47083D01*
X377900Y47417D01*
X377567Y48000D01*
X377400Y48667D01*
X377567Y49333D01*
X377900Y49917D01*
X378400Y50250D01*
X378900Y50333D01*
X379400Y50250D01*
X379900Y49917D01*
X380233Y49333D01*
X380317Y48667D01*
X380233Y48000D01*
X379900Y47417D01*
X379400Y47083D01*
X378900Y47000D01*
G01X383083D02*
Y50333D01*
G01Y49500D02*
X383417Y49917D01*
X383917Y50250D01*
X384583Y50333D01*
X385167Y50250D01*
X385667Y49917D01*
X385917Y49333D01*
Y47000D01*
G01X395700D02*
X395200Y47083D01*
X394700Y47417D01*
X394367Y48000D01*
X394200Y48667D01*
X394367Y49333D01*
X394700Y49917D01*
X395200Y50250D01*
X395700Y50333D01*
X396200Y50250D01*
X396700Y49917D01*
X397033Y49333D01*
X397117Y48667D01*
X397033Y48000D01*
X396700Y47417D01*
X396200Y47083D01*
X395700Y47000D01*
G01X400800D02*
Y51250D01*
X400967Y51667D01*
X401300Y51917D01*
X401800Y52000D01*
X402300Y51833D01*
X402550Y51417D01*
G01X401550Y50000D02*
X399883D01*
G01X411000Y45333D02*
Y50333D01*
G01Y49583D02*
X411417Y50000D01*
X411833Y50250D01*
X412500Y50333D01*
X413083Y50250D01*
X413667Y49833D01*
X413917Y49250D01*
X414000Y48667D01*
X413917Y48083D01*
X413667Y47500D01*
X413167Y47167D01*
X412500Y47000D01*
X411917Y47083D01*
X411333Y47333D01*
X411000Y47667D01*
G01X419600Y47000D02*
Y50333D01*
G01Y49750D02*
X419267Y50083D01*
X418767Y50250D01*
X418183Y50333D01*
X417600Y50167D01*
X417100Y49833D01*
X416767Y49333D01*
X416600Y48667D01*
X416767Y48000D01*
X417100Y47500D01*
X417600Y47167D01*
X418183Y47000D01*
X418767Y47083D01*
X419267Y47333D01*
X419600Y47667D01*
G01X425200Y52000D02*
Y47000D01*
G01Y47750D02*
X424867Y47333D01*
X424367Y47083D01*
X423783Y47000D01*
X423117Y47167D01*
X422617Y47583D01*
X422283Y48083D01*
X422200Y48667D01*
X422283Y49250D01*
X422617Y49750D01*
X423117Y50167D01*
X423783Y50333D01*
X424367Y50250D01*
X424783Y50083D01*
X425200Y49750D01*
G01X434900Y47000D02*
X434400Y47083D01*
X433900Y47417D01*
X433567Y48000D01*
X433400Y48667D01*
X433567Y49333D01*
X433900Y49917D01*
X434400Y50250D01*
X434900Y50333D01*
X435400Y50250D01*
X435900Y49917D01*
X436233Y49333D01*
X436317Y48667D01*
X436233Y48000D01*
X435900Y47417D01*
X435400Y47083D01*
X434900Y47000D01*
G01X439333D02*
Y50333D01*
G01Y49667D02*
X439750Y50000D01*
X440167Y50250D01*
X440750Y50333D01*
X441167Y50250D01*
X441667Y50000D01*
G01X453200Y52000D02*
Y47000D01*
G01Y47750D02*
X452867Y47333D01*
X452367Y47083D01*
X451783Y47000D01*
X451117Y47167D01*
X450617Y47583D01*
X450283Y48083D01*
X450200Y48667D01*
X450283Y49250D01*
X450617Y49750D01*
X451117Y50167D01*
X451783Y50333D01*
X452367Y50250D01*
X452783Y50083D01*
X453200Y49750D01*
G01X457300Y50333D02*
Y47000D01*
G01Y51667D02*
X457133Y51750D01*
Y51917D01*
X457300Y52000D01*
X457467Y51917D01*
Y51750D01*
X457300Y51667D01*
G01X464400Y47000D02*
Y50333D01*
G01Y49750D02*
X464067Y50083D01*
X463567Y50250D01*
X462983Y50333D01*
X462400Y50167D01*
X461900Y49833D01*
X461567Y49333D01*
X461400Y48667D01*
X461567Y48000D01*
X461900Y47500D01*
X462400Y47167D01*
X462983Y47000D01*
X463567Y47083D01*
X464067Y47333D01*
X464400Y47667D01*
G01X466000Y47000D02*
Y50333D01*
G01Y49417D02*
X466250Y49833D01*
X466667Y50167D01*
X467250Y50333D01*
X467833Y50167D01*
X468250Y49833D01*
X468500Y49417D01*
Y47000D01*
G01Y49417D02*
X468750Y49833D01*
X469167Y50167D01*
X469750Y50333D01*
X470333Y50167D01*
X470750Y49833D01*
X471000Y49333D01*
Y47000D01*
G01X472850Y49250D02*
X475517D01*
X475267Y49833D01*
X474850Y50167D01*
X474267Y50333D01*
X473683Y50250D01*
X473183Y50000D01*
X472850Y49417D01*
X472683Y48917D01*
Y48417D01*
X472850Y47917D01*
X473267Y47417D01*
X473767Y47083D01*
X474350Y47000D01*
X474933Y47167D01*
X475517Y47667D01*
G01X479700Y52000D02*
Y47000D01*
G01X478533Y50333D02*
X480867D01*
G01X484050Y49250D02*
X486717D01*
X486467Y49833D01*
X486050Y50167D01*
X485467Y50333D01*
X484883Y50250D01*
X484383Y50000D01*
X484050Y49417D01*
X483883Y48917D01*
Y48417D01*
X484050Y47917D01*
X484467Y47417D01*
X484967Y47083D01*
X485550Y47000D01*
X486133Y47167D01*
X486717Y47667D01*
G01X489733Y47000D02*
Y50333D01*
G01Y49667D02*
X490150Y50000D01*
X490567Y50250D01*
X491150Y50333D01*
X491567Y50250D01*
X492067Y50000D01*
G01X500433Y47000D02*
X503767Y48667D01*
X500433Y50333D01*
G01X513300Y47000D02*
Y52000D01*
X512300Y51000D01*
G01Y47000D02*
X514300D01*
G01X519900D02*
Y52000D01*
X516817Y48417D01*
X520983D01*
G01X527600Y47000D02*
Y50333D01*
G01Y49417D02*
X527850Y49833D01*
X528267Y50167D01*
X528850Y50333D01*
X529433Y50167D01*
X529850Y49833D01*
X530100Y49417D01*
Y47000D01*
G01Y49417D02*
X530350Y49833D01*
X530767Y50167D01*
X531350Y50333D01*
X531933Y50167D01*
X532350Y49833D01*
X532600Y49333D01*
Y47000D01*
G01X535700Y50333D02*
Y47000D01*
G01Y51667D02*
X535533Y51750D01*
Y51917D01*
X535700Y52000D01*
X535867Y51917D01*
Y51750D01*
X535700Y51667D01*
G01X541300Y47000D02*
Y52000D01*
G01X273580Y32670D02*
Y27670D01*
G01X271663Y32670D02*
X275497D01*
G01X277763Y27670D02*
Y32670D01*
G01Y30253D02*
X278180Y30670D01*
X278597Y30920D01*
X279263Y31003D01*
X279763Y30920D01*
X280347Y30587D01*
X280597Y30087D01*
Y27670D01*
G01X283530Y29920D02*
X286197D01*
X285947Y30503D01*
X285530Y30837D01*
X284947Y31003D01*
X284363Y30920D01*
X283863Y30670D01*
X283530Y30087D01*
X283363Y29587D01*
Y29087D01*
X283530Y28587D01*
X283947Y28087D01*
X284447Y27753D01*
X285030Y27670D01*
X285613Y27837D01*
X286197Y28337D01*
G01X295980Y27670D02*
Y32670D01*
G01X303080Y27670D02*
Y31003D01*
G01Y30420D02*
X302747Y30753D01*
X302247Y30920D01*
X301663Y31003D01*
X301080Y30837D01*
X300580Y30503D01*
X300247Y30003D01*
X300080Y29337D01*
X300247Y28670D01*
X300580Y28170D01*
X301080Y27837D01*
X301663Y27670D01*
X302247Y27753D01*
X302747Y28003D01*
X303080Y28337D01*
G01X306013Y27670D02*
Y31003D01*
G01Y30337D02*
X306430Y30670D01*
X306847Y30920D01*
X307430Y31003D01*
X307847Y30920D01*
X308347Y30670D01*
G01X311613Y26420D02*
X312197Y26087D01*
X312863Y26003D01*
X313447Y26087D01*
X313947Y26503D01*
X314280Y27087D01*
Y31003D01*
G01Y30337D02*
X313947Y30670D01*
X313447Y30920D01*
X312863Y31003D01*
X312197Y30837D01*
X311780Y30503D01*
X311447Y29920D01*
X311280Y29337D01*
X311363Y28837D01*
X311697Y28253D01*
X312197Y27837D01*
X312863Y27670D01*
X313363Y27753D01*
X313947Y28087D01*
X314280Y28420D01*
G01X317130Y29920D02*
X319797D01*
X319547Y30503D01*
X319130Y30837D01*
X318547Y31003D01*
X317963Y30920D01*
X317463Y30670D01*
X317130Y30087D01*
X316963Y29587D01*
Y29087D01*
X317130Y28587D01*
X317547Y28087D01*
X318047Y27753D01*
X318630Y27670D01*
X319213Y27837D01*
X319797Y28337D01*
G01X322730Y28253D02*
X323147Y27920D01*
X323730Y27670D01*
X324230D01*
X324730Y27837D01*
X325063Y28087D01*
X325230Y28420D01*
X325147Y28920D01*
X324813Y29170D01*
X323313Y29670D01*
X322980Y30253D01*
X323147Y30670D01*
X323480Y30920D01*
X323980Y31003D01*
X324480Y30920D01*
X324980Y30670D01*
G01X329580Y32670D02*
Y27670D01*
G01X328413Y31003D02*
X330747D01*
G01X342280Y32670D02*
Y27670D01*
G01Y28420D02*
X341947Y28003D01*
X341447Y27753D01*
X340863Y27670D01*
X340197Y27837D01*
X339697Y28253D01*
X339363Y28753D01*
X339280Y29337D01*
X339363Y29920D01*
X339697Y30420D01*
X340197Y30837D01*
X340863Y31003D01*
X341447Y30920D01*
X341863Y30753D01*
X342280Y30420D01*
G01X346380Y31003D02*
Y27670D01*
G01Y32337D02*
X346213Y32420D01*
Y32587D01*
X346380Y32670D01*
X346547Y32587D01*
Y32420D01*
X346380Y32337D01*
G01X349480Y27670D02*
Y31003D01*
G01Y30087D02*
X349730Y30503D01*
X350147Y30837D01*
X350730Y31003D01*
X351313Y30837D01*
X351730Y30503D01*
X351980Y30087D01*
Y27670D01*
G01Y30087D02*
X352230Y30503D01*
X352647Y30837D01*
X353230Y31003D01*
X353813Y30837D01*
X354230Y30503D01*
X354480Y30003D01*
Y27670D01*
G01X356330Y29920D02*
X358997D01*
X358747Y30503D01*
X358330Y30837D01*
X357747Y31003D01*
X357163Y30920D01*
X356663Y30670D01*
X356330Y30087D01*
X356163Y29587D01*
Y29087D01*
X356330Y28587D01*
X356747Y28087D01*
X357247Y27753D01*
X357830Y27670D01*
X358413Y27837D01*
X358997Y28337D01*
G01X361763Y27670D02*
Y31003D01*
G01Y30170D02*
X362097Y30587D01*
X362597Y30920D01*
X363263Y31003D01*
X363847Y30920D01*
X364347Y30587D01*
X364597Y30003D01*
Y27670D01*
G01X367530Y28253D02*
X367947Y27920D01*
X368530Y27670D01*
X369030D01*
X369530Y27837D01*
X369863Y28087D01*
X370030Y28420D01*
X369947Y28920D01*
X369613Y29170D01*
X368113Y29670D01*
X367780Y30253D01*
X367947Y30670D01*
X368280Y30920D01*
X368780Y31003D01*
X369280Y30920D01*
X369780Y30670D01*
G01X374380Y31003D02*
Y27670D01*
G01Y32337D02*
X374213Y32420D01*
Y32587D01*
X374380Y32670D01*
X374547Y32587D01*
Y32420D01*
X374380Y32337D01*
G01X379980Y27670D02*
X379480Y27753D01*
X378980Y28087D01*
X378647Y28670D01*
X378480Y29337D01*
X378647Y30003D01*
X378980Y30587D01*
X379480Y30920D01*
X379980Y31003D01*
X380480Y30920D01*
X380980Y30587D01*
X381313Y30003D01*
X381397Y29337D01*
X381313Y28670D01*
X380980Y28087D01*
X380480Y27753D01*
X379980Y27670D01*
G01X384163D02*
Y31003D01*
G01Y30170D02*
X384497Y30587D01*
X384997Y30920D01*
X385663Y31003D01*
X386247Y30920D01*
X386747Y30587D01*
X386997Y30003D01*
Y27670D01*
G01X396780D02*
X396280Y27753D01*
X395780Y28087D01*
X395447Y28670D01*
X395280Y29337D01*
X395447Y30003D01*
X395780Y30587D01*
X396280Y30920D01*
X396780Y31003D01*
X397280Y30920D01*
X397780Y30587D01*
X398113Y30003D01*
X398197Y29337D01*
X398113Y28670D01*
X397780Y28087D01*
X397280Y27753D01*
X396780Y27670D01*
G01X401880D02*
Y31920D01*
X402047Y32337D01*
X402380Y32587D01*
X402880Y32670D01*
X403380Y32503D01*
X403630Y32087D01*
G01X402630Y30670D02*
X400963D01*
G01X412080Y26003D02*
Y31003D01*
G01Y30253D02*
X412497Y30670D01*
X412913Y30920D01*
X413580Y31003D01*
X414163Y30920D01*
X414747Y30503D01*
X414997Y29920D01*
X415080Y29337D01*
X414997Y28753D01*
X414747Y28170D01*
X414247Y27837D01*
X413580Y27670D01*
X412997Y27753D01*
X412413Y28003D01*
X412080Y28337D01*
G01X420680Y27670D02*
Y31003D01*
G01Y30420D02*
X420347Y30753D01*
X419847Y30920D01*
X419263Y31003D01*
X418680Y30837D01*
X418180Y30503D01*
X417847Y30003D01*
X417680Y29337D01*
X417847Y28670D01*
X418180Y28170D01*
X418680Y27837D01*
X419263Y27670D01*
X419847Y27753D01*
X420347Y28003D01*
X420680Y28337D01*
G01X426280Y32670D02*
Y27670D01*
G01Y28420D02*
X425947Y28003D01*
X425447Y27753D01*
X424863Y27670D01*
X424197Y27837D01*
X423697Y28253D01*
X423363Y28753D01*
X423280Y29337D01*
X423363Y29920D01*
X423697Y30420D01*
X424197Y30837D01*
X424863Y31003D01*
X425447Y30920D01*
X425863Y30753D01*
X426280Y30420D01*
G01X435980Y27670D02*
X435480Y27753D01*
X434980Y28087D01*
X434647Y28670D01*
X434480Y29337D01*
X434647Y30003D01*
X434980Y30587D01*
X435480Y30920D01*
X435980Y31003D01*
X436480Y30920D01*
X436980Y30587D01*
X437313Y30003D01*
X437397Y29337D01*
X437313Y28670D01*
X436980Y28087D01*
X436480Y27753D01*
X435980Y27670D01*
G01X440413D02*
Y31003D01*
G01Y30337D02*
X440830Y30670D01*
X441247Y30920D01*
X441830Y31003D01*
X442247Y30920D01*
X442747Y30670D01*
G01X454280Y32670D02*
Y27670D01*
G01Y28420D02*
X453947Y28003D01*
X453447Y27753D01*
X452863Y27670D01*
X452197Y27837D01*
X451697Y28253D01*
X451363Y28753D01*
X451280Y29337D01*
X451363Y29920D01*
X451697Y30420D01*
X452197Y30837D01*
X452863Y31003D01*
X453447Y30920D01*
X453863Y30753D01*
X454280Y30420D01*
G01X458380Y31003D02*
Y27670D01*
G01Y32337D02*
X458213Y32420D01*
Y32587D01*
X458380Y32670D01*
X458547Y32587D01*
Y32420D01*
X458380Y32337D01*
G01X465480Y27670D02*
Y31003D01*
G01Y30420D02*
X465147Y30753D01*
X464647Y30920D01*
X464063Y31003D01*
X463480Y30837D01*
X462980Y30503D01*
X462647Y30003D01*
X462480Y29337D01*
X462647Y28670D01*
X462980Y28170D01*
X463480Y27837D01*
X464063Y27670D01*
X464647Y27753D01*
X465147Y28003D01*
X465480Y28337D01*
G01X467080Y27670D02*
Y31003D01*
G01Y30087D02*
X467330Y30503D01*
X467747Y30837D01*
X468330Y31003D01*
X468913Y30837D01*
X469330Y30503D01*
X469580Y30087D01*
Y27670D01*
G01Y30087D02*
X469830Y30503D01*
X470247Y30837D01*
X470830Y31003D01*
X471413Y30837D01*
X471830Y30503D01*
X472080Y30003D01*
Y27670D01*
G01X473930Y29920D02*
X476597D01*
X476347Y30503D01*
X475930Y30837D01*
X475347Y31003D01*
X474763Y30920D01*
X474263Y30670D01*
X473930Y30087D01*
X473763Y29587D01*
Y29087D01*
X473930Y28587D01*
X474347Y28087D01*
X474847Y27753D01*
X475430Y27670D01*
X476013Y27837D01*
X476597Y28337D01*
G01X480780Y32670D02*
Y27670D01*
G01X479613Y31003D02*
X481947D01*
G01X485130Y29920D02*
X487797D01*
X487547Y30503D01*
X487130Y30837D01*
X486547Y31003D01*
X485963Y30920D01*
X485463Y30670D01*
X485130Y30087D01*
X484963Y29587D01*
Y29087D01*
X485130Y28587D01*
X485547Y28087D01*
X486047Y27753D01*
X486630Y27670D01*
X487213Y27837D01*
X487797Y28337D01*
G01X490813Y27670D02*
Y31003D01*
G01Y30337D02*
X491230Y30670D01*
X491647Y30920D01*
X492230Y31003D01*
X492647Y30920D01*
X493147Y30670D01*
G01X504847Y27670D02*
X501513Y29337D01*
X504847Y31003D01*
G01X507697Y28587D02*
X509863D01*
G01Y30087D02*
X507697D01*
G01X519980Y27670D02*
Y32670D01*
X518980Y31670D01*
G01Y27670D02*
X520980D01*
G01X526580D02*
Y32670D01*
X523497Y29087D01*
X527663D01*
G01X534280Y27670D02*
Y31003D01*
G01Y30087D02*
X534530Y30503D01*
X534947Y30837D01*
X535530Y31003D01*
X536113Y30837D01*
X536530Y30503D01*
X536780Y30087D01*
Y27670D01*
G01Y30087D02*
X537030Y30503D01*
X537447Y30837D01*
X538030Y31003D01*
X538613Y30837D01*
X539030Y30503D01*
X539280Y30003D01*
Y27670D01*
G01X542380Y31003D02*
Y27670D01*
G01Y32337D02*
X542213Y32420D01*
Y32587D01*
X542380Y32670D01*
X542547Y32587D01*
Y32420D01*
X542380Y32337D01*
G01X547980Y27670D02*
Y32670D01*
G01X272500Y15000D02*
Y10000D01*
G01X270583Y15000D02*
X274417D01*
G01X276683Y10000D02*
Y15000D01*
G01Y12583D02*
X277100Y13000D01*
X277517Y13250D01*
X278183Y13333D01*
X278683Y13250D01*
X279267Y12917D01*
X279517Y12417D01*
Y10000D01*
G01X282450Y12250D02*
X285117D01*
X284867Y12833D01*
X284450Y13167D01*
X283867Y13333D01*
X283283Y13250D01*
X282783Y13000D01*
X282450Y12417D01*
X282283Y11917D01*
Y11417D01*
X282450Y10917D01*
X282867Y10417D01*
X283367Y10083D01*
X283950Y10000D01*
X284533Y10167D01*
X285117Y10667D01*
G01X294900Y10000D02*
Y15000D01*
G01X302000Y10000D02*
Y13333D01*
G01Y12750D02*
X301667Y13083D01*
X301167Y13250D01*
X300583Y13333D01*
X300000Y13167D01*
X299500Y12833D01*
X299167Y12333D01*
X299000Y11667D01*
X299167Y11000D01*
X299500Y10500D01*
X300000Y10167D01*
X300583Y10000D01*
X301167Y10083D01*
X301667Y10333D01*
X302000Y10667D01*
G01X304933Y10000D02*
Y13333D01*
G01Y12667D02*
X305350Y13000D01*
X305767Y13250D01*
X306350Y13333D01*
X306767Y13250D01*
X307267Y13000D01*
G01X310533Y8750D02*
X311117Y8417D01*
X311783Y8333D01*
X312367Y8417D01*
X312867Y8833D01*
X313200Y9417D01*
Y13333D01*
G01Y12667D02*
X312867Y13000D01*
X312367Y13250D01*
X311783Y13333D01*
X311117Y13167D01*
X310700Y12833D01*
X310367Y12250D01*
X310200Y11667D01*
X310283Y11167D01*
X310617Y10583D01*
X311117Y10167D01*
X311783Y10000D01*
X312283Y10083D01*
X312867Y10417D01*
X313200Y10750D01*
G01X316050Y12250D02*
X318717D01*
X318467Y12833D01*
X318050Y13167D01*
X317467Y13333D01*
X316883Y13250D01*
X316383Y13000D01*
X316050Y12417D01*
X315883Y11917D01*
Y11417D01*
X316050Y10917D01*
X316467Y10417D01*
X316967Y10083D01*
X317550Y10000D01*
X318133Y10167D01*
X318717Y10667D01*
G01X321650Y10583D02*
X322067Y10250D01*
X322650Y10000D01*
X323150D01*
X323650Y10167D01*
X323983Y10417D01*
X324150Y10750D01*
X324067Y11250D01*
X323733Y11500D01*
X322233Y12000D01*
X321900Y12583D01*
X322067Y13000D01*
X322400Y13250D01*
X322900Y13333D01*
X323400Y13250D01*
X323900Y13000D01*
G01X328500Y15000D02*
Y10000D01*
G01X327333Y13333D02*
X329667D01*
G01X341200Y15000D02*
Y10000D01*
G01Y10750D02*
X340867Y10333D01*
X340367Y10083D01*
X339783Y10000D01*
X339117Y10167D01*
X338617Y10583D01*
X338283Y11083D01*
X338200Y11667D01*
X338283Y12250D01*
X338617Y12750D01*
X339117Y13167D01*
X339783Y13333D01*
X340367Y13250D01*
X340783Y13083D01*
X341200Y12750D01*
G01X345300Y13333D02*
Y10000D01*
G01Y14667D02*
X345133Y14750D01*
Y14917D01*
X345300Y15000D01*
X345467Y14917D01*
Y14750D01*
X345300Y14667D01*
G01X348400Y10000D02*
Y13333D01*
G01Y12417D02*
X348650Y12833D01*
X349067Y13167D01*
X349650Y13333D01*
X350233Y13167D01*
X350650Y12833D01*
X350900Y12417D01*
Y10000D01*
G01Y12417D02*
X351150Y12833D01*
X351567Y13167D01*
X352150Y13333D01*
X352733Y13167D01*
X353150Y12833D01*
X353400Y12333D01*
Y10000D01*
G01X355250Y12250D02*
X357917D01*
X357667Y12833D01*
X357250Y13167D01*
X356667Y13333D01*
X356083Y13250D01*
X355583Y13000D01*
X355250Y12417D01*
X355083Y11917D01*
Y11417D01*
X355250Y10917D01*
X355667Y10417D01*
X356167Y10083D01*
X356750Y10000D01*
X357333Y10167D01*
X357917Y10667D01*
G01X360683Y10000D02*
Y13333D01*
G01Y12500D02*
X361017Y12917D01*
X361517Y13250D01*
X362183Y13333D01*
X362767Y13250D01*
X363267Y12917D01*
X363517Y12333D01*
Y10000D01*
G01X366450Y10583D02*
X366867Y10250D01*
X367450Y10000D01*
X367950D01*
X368450Y10167D01*
X368783Y10417D01*
X368950Y10750D01*
X368867Y11250D01*
X368533Y11500D01*
X367033Y12000D01*
X366700Y12583D01*
X366867Y13000D01*
X367200Y13250D01*
X367700Y13333D01*
X368200Y13250D01*
X368700Y13000D01*
G01X373300Y13333D02*
Y10000D01*
G01Y14667D02*
X373133Y14750D01*
Y14917D01*
X373300Y15000D01*
X373467Y14917D01*
Y14750D01*
X373300Y14667D01*
G01X378900Y10000D02*
X378400Y10083D01*
X377900Y10417D01*
X377567Y11000D01*
X377400Y11667D01*
X377567Y12333D01*
X377900Y12917D01*
X378400Y13250D01*
X378900Y13333D01*
X379400Y13250D01*
X379900Y12917D01*
X380233Y12333D01*
X380317Y11667D01*
X380233Y11000D01*
X379900Y10417D01*
X379400Y10083D01*
X378900Y10000D01*
G01X383083D02*
Y13333D01*
G01Y12500D02*
X383417Y12917D01*
X383917Y13250D01*
X384583Y13333D01*
X385167Y13250D01*
X385667Y12917D01*
X385917Y12333D01*
Y10000D01*
G01X395700D02*
X395200Y10083D01*
X394700Y10417D01*
X394367Y11000D01*
X394200Y11667D01*
X394367Y12333D01*
X394700Y12917D01*
X395200Y13250D01*
X395700Y13333D01*
X396200Y13250D01*
X396700Y12917D01*
X397033Y12333D01*
X397117Y11667D01*
X397033Y11000D01*
X396700Y10417D01*
X396200Y10083D01*
X395700Y10000D01*
G01X400800D02*
Y14250D01*
X400967Y14667D01*
X401300Y14917D01*
X401800Y15000D01*
X402300Y14833D01*
X402550Y14417D01*
G01X401550Y13000D02*
X399883D01*
G01X411000Y8333D02*
Y13333D01*
G01Y12583D02*
X411417Y13000D01*
X411833Y13250D01*
X412500Y13333D01*
X413083Y13250D01*
X413667Y12833D01*
X413917Y12250D01*
X414000Y11667D01*
X413917Y11083D01*
X413667Y10500D01*
X413167Y10167D01*
X412500Y10000D01*
X411917Y10083D01*
X411333Y10333D01*
X411000Y10667D01*
G01X419600Y10000D02*
Y13333D01*
G01Y12750D02*
X419267Y13083D01*
X418767Y13250D01*
X418183Y13333D01*
X417600Y13167D01*
X417100Y12833D01*
X416767Y12333D01*
X416600Y11667D01*
X416767Y11000D01*
X417100Y10500D01*
X417600Y10167D01*
X418183Y10000D01*
X418767Y10083D01*
X419267Y10333D01*
X419600Y10667D01*
G01X425200Y15000D02*
Y10000D01*
G01Y10750D02*
X424867Y10333D01*
X424367Y10083D01*
X423783Y10000D01*
X423117Y10167D01*
X422617Y10583D01*
X422283Y11083D01*
X422200Y11667D01*
X422283Y12250D01*
X422617Y12750D01*
X423117Y13167D01*
X423783Y13333D01*
X424367Y13250D01*
X424783Y13083D01*
X425200Y12750D01*
G01X434900Y10000D02*
X434400Y10083D01*
X433900Y10417D01*
X433567Y11000D01*
X433400Y11667D01*
X433567Y12333D01*
X433900Y12917D01*
X434400Y13250D01*
X434900Y13333D01*
X435400Y13250D01*
X435900Y12917D01*
X436233Y12333D01*
X436317Y11667D01*
X436233Y11000D01*
X435900Y10417D01*
X435400Y10083D01*
X434900Y10000D01*
G01X439333D02*
Y13333D01*
G01Y12667D02*
X439750Y13000D01*
X440167Y13250D01*
X440750Y13333D01*
X441167Y13250D01*
X441667Y13000D01*
G01X453200Y15000D02*
Y10000D01*
G01Y10750D02*
X452867Y10333D01*
X452367Y10083D01*
X451783Y10000D01*
X451117Y10167D01*
X450617Y10583D01*
X450283Y11083D01*
X450200Y11667D01*
X450283Y12250D01*
X450617Y12750D01*
X451117Y13167D01*
X451783Y13333D01*
X452367Y13250D01*
X452783Y13083D01*
X453200Y12750D01*
G01X457300Y13333D02*
Y10000D01*
G01Y14667D02*
X457133Y14750D01*
Y14917D01*
X457300Y15000D01*
X457467Y14917D01*
Y14750D01*
X457300Y14667D01*
G01X464400Y10000D02*
Y13333D01*
G01Y12750D02*
X464067Y13083D01*
X463567Y13250D01*
X462983Y13333D01*
X462400Y13167D01*
X461900Y12833D01*
X461567Y12333D01*
X461400Y11667D01*
X461567Y11000D01*
X461900Y10500D01*
X462400Y10167D01*
X462983Y10000D01*
X463567Y10083D01*
X464067Y10333D01*
X464400Y10667D01*
G01X466000Y10000D02*
Y13333D01*
G01Y12417D02*
X466250Y12833D01*
X466667Y13167D01*
X467250Y13333D01*
X467833Y13167D01*
X468250Y12833D01*
X468500Y12417D01*
Y10000D01*
G01Y12417D02*
X468750Y12833D01*
X469167Y13167D01*
X469750Y13333D01*
X470333Y13167D01*
X470750Y12833D01*
X471000Y12333D01*
Y10000D01*
G01X472850Y12250D02*
X475517D01*
X475267Y12833D01*
X474850Y13167D01*
X474267Y13333D01*
X473683Y13250D01*
X473183Y13000D01*
X472850Y12417D01*
X472683Y11917D01*
Y11417D01*
X472850Y10917D01*
X473267Y10417D01*
X473767Y10083D01*
X474350Y10000D01*
X474933Y10167D01*
X475517Y10667D01*
G01X479700Y15000D02*
Y10000D01*
G01X478533Y13333D02*
X480867D01*
G01X484050Y12250D02*
X486717D01*
X486467Y12833D01*
X486050Y13167D01*
X485467Y13333D01*
X484883Y13250D01*
X484383Y13000D01*
X484050Y12417D01*
X483883Y11917D01*
Y11417D01*
X484050Y10917D01*
X484467Y10417D01*
X484967Y10083D01*
X485550Y10000D01*
X486133Y10167D01*
X486717Y10667D01*
G01X489733Y10000D02*
Y13333D01*
G01Y12667D02*
X490150Y13000D01*
X490567Y13250D01*
X491150Y13333D01*
X491567Y13250D01*
X492067Y13000D01*
G01X500433Y10000D02*
X503767Y11667D01*
X500433Y13333D01*
G01X507700Y10000D02*
Y15000D01*
X506700Y14000D01*
G01Y10000D02*
X508700D01*
G01X514300D02*
Y15000D01*
X511217Y11417D01*
X515383D01*
G01X522000Y10000D02*
Y13333D01*
G01Y12417D02*
X522250Y12833D01*
X522667Y13167D01*
X523250Y13333D01*
X523833Y13167D01*
X524250Y12833D01*
X524500Y12417D01*
Y10000D01*
G01Y12417D02*
X524750Y12833D01*
X525167Y13167D01*
X525750Y13333D01*
X526333Y13167D01*
X526750Y12833D01*
X527000Y12333D01*
Y10000D01*
G01X530100Y13333D02*
Y10000D01*
G01Y14667D02*
X529933Y14750D01*
Y14917D01*
X530100Y15000D01*
X530267Y14917D01*
Y14750D01*
X530100Y14667D01*
G01X535700Y10000D02*
Y15000D01*
G01X264000Y5500D02*
X694500D01*
G01X264000Y40500D02*
X694500D01*
G01X272500Y101500D02*
Y96500D01*
G01X271333Y99833D02*
X273667D01*
G01X276933Y96500D02*
Y99833D01*
G01Y99167D02*
X277350Y99500D01*
X277767Y99750D01*
X278350Y99833D01*
X278767Y99750D01*
X279267Y99500D01*
G01X285200Y96500D02*
Y99833D01*
G01Y99250D02*
X284867Y99583D01*
X284367Y99750D01*
X283783Y99833D01*
X283200Y99667D01*
X282700Y99333D01*
X282367Y98833D01*
X282200Y98167D01*
X282367Y97500D01*
X282700Y97000D01*
X283200Y96667D01*
X283783Y96500D01*
X284367Y96583D01*
X284867Y96833D01*
X285200Y97167D01*
G01X290633Y99417D02*
X290050Y99750D01*
X289550Y99833D01*
X288883Y99667D01*
X288383Y99333D01*
X288050Y98750D01*
X287967Y98167D01*
X288050Y97583D01*
X288383Y97083D01*
X288883Y96667D01*
X289550Y96500D01*
X290133Y96667D01*
X290633Y97000D01*
G01X293650Y98750D02*
X296317D01*
X296067Y99333D01*
X295650Y99667D01*
X295067Y99833D01*
X294483Y99750D01*
X293983Y99500D01*
X293650Y98917D01*
X293483Y98417D01*
Y97917D01*
X293650Y97417D01*
X294067Y96917D01*
X294567Y96583D01*
X295150Y96500D01*
X295733Y96667D01*
X296317Y97167D01*
G01X304017Y99833D02*
X305017Y96500D01*
X306100Y99833D01*
X307183Y96500D01*
X308183Y99833D01*
G01X311700D02*
Y96500D01*
G01Y101167D02*
X311533Y101250D01*
Y101417D01*
X311700Y101500D01*
X311867Y101417D01*
Y101250D01*
X311700Y101167D01*
G01X318800Y101500D02*
Y96500D01*
G01Y97250D02*
X318467Y96833D01*
X317967Y96583D01*
X317383Y96500D01*
X316717Y96667D01*
X316217Y97083D01*
X315883Y97583D01*
X315800Y98167D01*
X315883Y98750D01*
X316217Y99250D01*
X316717Y99667D01*
X317383Y99833D01*
X317967Y99750D01*
X318383Y99583D01*
X318800Y99250D01*
G01X322900Y101500D02*
Y96500D01*
G01X321733Y99833D02*
X324067D01*
G01X327083Y96500D02*
Y101500D01*
G01Y99083D02*
X327500Y99500D01*
X327917Y99750D01*
X328583Y99833D01*
X329083Y99750D01*
X329667Y99417D01*
X329917Y98917D01*
Y96500D01*
G01X341367D02*
X338033Y98167D01*
X341367Y99833D01*
G01X344217Y97417D02*
X346383D01*
G01Y98917D02*
X344217D01*
G01X354667Y97250D02*
X355167Y96833D01*
X355750Y96583D01*
X356500Y96500D01*
X357250Y96667D01*
X357833Y97000D01*
X358250Y97583D01*
X358333Y98250D01*
X358167Y98917D01*
X357750Y99333D01*
X357167Y99667D01*
X356583Y99750D01*
X356000Y99667D01*
X355250Y99333D01*
X355500Y101500D01*
X357750D01*
G01X365200Y96500D02*
Y99833D01*
G01Y98917D02*
X365450Y99333D01*
X365867Y99667D01*
X366450Y99833D01*
X367033Y99667D01*
X367450Y99333D01*
X367700Y98917D01*
Y96500D01*
G01Y98917D02*
X367950Y99333D01*
X368367Y99667D01*
X368950Y99833D01*
X369533Y99667D01*
X369950Y99333D01*
X370200Y98833D01*
Y96500D01*
G01X373300Y99833D02*
Y96500D01*
G01Y101167D02*
X373133Y101250D01*
Y101417D01*
X373300Y101500D01*
X373467Y101417D01*
Y101250D01*
X373300Y101167D01*
G01X378900Y96500D02*
Y101500D01*
G01X270667Y82250D02*
X271167Y81833D01*
X271750Y81583D01*
X272500Y81500D01*
X273250Y81667D01*
X273833Y82000D01*
X274250Y82583D01*
X274333Y83250D01*
X274167Y83917D01*
X273750Y84333D01*
X273167Y84667D01*
X272583Y84750D01*
X272000Y84667D01*
X271250Y84333D01*
X271500Y86500D01*
X273750D01*
G01X281200Y81500D02*
Y84833D01*
G01Y83917D02*
X281450Y84333D01*
X281867Y84667D01*
X282450Y84833D01*
X283033Y84667D01*
X283450Y84333D01*
X283700Y83917D01*
Y81500D01*
G01Y83917D02*
X283950Y84333D01*
X284367Y84667D01*
X284950Y84833D01*
X285533Y84667D01*
X285950Y84333D01*
X286200Y83833D01*
Y81500D01*
G01X289300Y84833D02*
Y81500D01*
G01Y86167D02*
X289133Y86250D01*
Y86417D01*
X289300Y86500D01*
X289467Y86417D01*
Y86250D01*
X289300Y86167D01*
G01X294900Y81500D02*
Y86500D01*
G01X307767Y81500D02*
X304433Y83167D01*
X307767Y84833D01*
G01X317300Y86500D02*
Y81500D01*
G01X316133Y84833D02*
X318467D01*
G01X321733Y81500D02*
Y84833D01*
G01Y84167D02*
X322150Y84500D01*
X322567Y84750D01*
X323150Y84833D01*
X323567Y84750D01*
X324067Y84500D01*
G01X330000Y81500D02*
Y84833D01*
G01Y84250D02*
X329667Y84583D01*
X329167Y84750D01*
X328583Y84833D01*
X328000Y84667D01*
X327500Y84333D01*
X327167Y83833D01*
X327000Y83167D01*
X327167Y82500D01*
X327500Y82000D01*
X328000Y81667D01*
X328583Y81500D01*
X329167Y81583D01*
X329667Y81833D01*
X330000Y82167D01*
G01X335433Y84417D02*
X334850Y84750D01*
X334350Y84833D01*
X333683Y84667D01*
X333183Y84333D01*
X332850Y83750D01*
X332767Y83167D01*
X332850Y82583D01*
X333183Y82083D01*
X333683Y81667D01*
X334350Y81500D01*
X334933Y81667D01*
X335433Y82000D01*
G01X338450Y83750D02*
X341117D01*
X340867Y84333D01*
X340450Y84667D01*
X339867Y84833D01*
X339283Y84750D01*
X338783Y84500D01*
X338450Y83917D01*
X338283Y83417D01*
Y82917D01*
X338450Y82417D01*
X338867Y81917D01*
X339367Y81583D01*
X339950Y81500D01*
X340533Y81667D01*
X341117Y82167D01*
G01X348817Y84833D02*
X349817Y81500D01*
X350900Y84833D01*
X351983Y81500D01*
X352983Y84833D01*
G01X356500D02*
Y81500D01*
G01Y86167D02*
X356333Y86250D01*
Y86417D01*
X356500Y86500D01*
X356667Y86417D01*
Y86250D01*
X356500Y86167D01*
G01X363600Y86500D02*
Y81500D01*
G01Y82250D02*
X363267Y81833D01*
X362767Y81583D01*
X362183Y81500D01*
X361517Y81667D01*
X361017Y82083D01*
X360683Y82583D01*
X360600Y83167D01*
X360683Y83750D01*
X361017Y84250D01*
X361517Y84667D01*
X362183Y84833D01*
X362767Y84750D01*
X363183Y84583D01*
X363600Y84250D01*
G01X367700Y86500D02*
Y81500D01*
G01X366533Y84833D02*
X368867D01*
G01X371883Y81500D02*
Y86500D01*
G01Y84083D02*
X372300Y84500D01*
X372717Y84750D01*
X373383Y84833D01*
X373883Y84750D01*
X374467Y84417D01*
X374717Y83917D01*
Y81500D01*
G01X386167D02*
X382833Y83167D01*
X386167Y84833D01*
G01X389017Y82417D02*
X391183D01*
G01Y83917D02*
X389017D01*
G01X401133Y81500D02*
X401300Y82583D01*
X401550Y83500D01*
X401883Y84333D01*
X402300Y85250D01*
X402967Y86500D01*
X399633D01*
G01X410000Y81500D02*
Y84833D01*
G01Y83917D02*
X410250Y84333D01*
X410667Y84667D01*
X411250Y84833D01*
X411833Y84667D01*
X412250Y84333D01*
X412500Y83917D01*
Y81500D01*
G01Y83917D02*
X412750Y84333D01*
X413167Y84667D01*
X413750Y84833D01*
X414333Y84667D01*
X414750Y84333D01*
X415000Y83833D01*
Y81500D01*
G01X418100Y84833D02*
Y81500D01*
G01Y86167D02*
X417933Y86250D01*
Y86417D01*
X418100Y86500D01*
X418267Y86417D01*
Y86250D01*
X418100Y86167D01*
G01X423700Y81500D02*
Y86500D01*
G01X272500Y71500D02*
Y66500D01*
G01X271333Y69833D02*
X273667D01*
G01X276933Y66500D02*
Y69833D01*
G01Y69167D02*
X277350Y69500D01*
X277767Y69750D01*
X278350Y69833D01*
X278767Y69750D01*
X279267Y69500D01*
G01X285200Y66500D02*
Y69833D01*
G01Y69250D02*
X284867Y69583D01*
X284367Y69750D01*
X283783Y69833D01*
X283200Y69667D01*
X282700Y69333D01*
X282367Y68833D01*
X282200Y68167D01*
X282367Y67500D01*
X282700Y67000D01*
X283200Y66667D01*
X283783Y66500D01*
X284367Y66583D01*
X284867Y66833D01*
X285200Y67167D01*
G01X290633Y69417D02*
X290050Y69750D01*
X289550Y69833D01*
X288883Y69667D01*
X288383Y69333D01*
X288050Y68750D01*
X287967Y68167D01*
X288050Y67583D01*
X288383Y67083D01*
X288883Y66667D01*
X289550Y66500D01*
X290133Y66667D01*
X290633Y67000D01*
G01X293650Y68750D02*
X296317D01*
X296067Y69333D01*
X295650Y69667D01*
X295067Y69833D01*
X294483Y69750D01*
X293983Y69500D01*
X293650Y68917D01*
X293483Y68417D01*
Y67917D01*
X293650Y67417D01*
X294067Y66917D01*
X294567Y66583D01*
X295150Y66500D01*
X295733Y66667D01*
X296317Y67167D01*
G01X304017Y69833D02*
X305017Y66500D01*
X306100Y69833D01*
X307183Y66500D01*
X308183Y69833D01*
G01X311700D02*
Y66500D01*
G01Y71167D02*
X311533Y71250D01*
Y71417D01*
X311700Y71500D01*
X311867Y71417D01*
Y71250D01*
X311700Y71167D01*
G01X318800Y71500D02*
Y66500D01*
G01Y67250D02*
X318467Y66833D01*
X317967Y66583D01*
X317383Y66500D01*
X316717Y66667D01*
X316217Y67083D01*
X315883Y67583D01*
X315800Y68167D01*
X315883Y68750D01*
X316217Y69250D01*
X316717Y69667D01*
X317383Y69833D01*
X317967Y69750D01*
X318383Y69583D01*
X318800Y69250D01*
G01X322900Y71500D02*
Y66500D01*
G01X321733Y69833D02*
X324067D01*
G01X327083Y66500D02*
Y71500D01*
G01Y69083D02*
X327500Y69500D01*
X327917Y69750D01*
X328583Y69833D01*
X329083Y69750D01*
X329667Y69417D01*
X329917Y68917D01*
Y66500D01*
G01X338033D02*
X341367Y68167D01*
X338033Y69833D01*
G01X350733Y66500D02*
X350900Y67583D01*
X351150Y68500D01*
X351483Y69333D01*
X351900Y70250D01*
X352567Y71500D01*
X349233D01*
G01X359600Y66500D02*
Y69833D01*
G01Y68917D02*
X359850Y69333D01*
X360267Y69667D01*
X360850Y69833D01*
X361433Y69667D01*
X361850Y69333D01*
X362100Y68917D01*
Y66500D01*
G01Y68917D02*
X362350Y69333D01*
X362767Y69667D01*
X363350Y69833D01*
X363933Y69667D01*
X364350Y69333D01*
X364600Y68833D01*
Y66500D01*
G01X367700Y69833D02*
Y66500D01*
G01Y71167D02*
X367533Y71250D01*
Y71417D01*
X367700Y71500D01*
X367867Y71417D01*
Y71250D01*
X367700Y71167D01*
G01X373300Y66500D02*
Y71500D01*
G01X270833Y110000D02*
Y115000D01*
X272917D01*
X273583Y114750D01*
X274000Y114417D01*
X274167Y113750D01*
X274000Y113083D01*
X273500Y112667D01*
X272917Y112417D01*
X270833D01*
G01X272917D02*
X274167Y110000D01*
G01X276850Y112250D02*
X279517D01*
X279267Y112833D01*
X278850Y113167D01*
X278267Y113333D01*
X277683Y113250D01*
X277183Y113000D01*
X276850Y112417D01*
X276683Y111917D01*
Y111417D01*
X276850Y110917D01*
X277267Y110417D01*
X277767Y110083D01*
X278350Y110000D01*
X278933Y110167D01*
X279517Y110667D01*
G01X283700Y110000D02*
Y115000D01*
G01X290800Y110000D02*
Y113333D01*
G01Y112750D02*
X290467Y113083D01*
X289967Y113250D01*
X289383Y113333D01*
X288800Y113167D01*
X288300Y112833D01*
X287967Y112333D01*
X287800Y111667D01*
X287967Y111000D01*
X288300Y110500D01*
X288800Y110167D01*
X289383Y110000D01*
X289967Y110083D01*
X290467Y110333D01*
X290800Y110667D01*
G01X294900Y115000D02*
Y110000D01*
G01X293733Y113333D02*
X296067D01*
G01X300500D02*
Y110000D01*
G01Y114667D02*
X300333Y114750D01*
Y114917D01*
X300500Y115000D01*
X300667Y114917D01*
Y114750D01*
X300500Y114667D01*
G01X304600Y113333D02*
X306100Y110000D01*
X307600Y113333D01*
G01X310450Y112250D02*
X313117D01*
X312867Y112833D01*
X312450Y113167D01*
X311867Y113333D01*
X311283Y113250D01*
X310783Y113000D01*
X310450Y112417D01*
X310283Y111917D01*
Y111417D01*
X310450Y110917D01*
X310867Y110417D01*
X311367Y110083D01*
X311950Y110000D01*
X312533Y110167D01*
X313117Y110667D01*
G01X321400Y108333D02*
Y113333D01*
G01Y112583D02*
X321817Y113000D01*
X322233Y113250D01*
X322900Y113333D01*
X323483Y113250D01*
X324067Y112833D01*
X324317Y112250D01*
X324400Y111667D01*
X324317Y111083D01*
X324067Y110500D01*
X323567Y110167D01*
X322900Y110000D01*
X322317Y110083D01*
X321733Y110333D01*
X321400Y110667D01*
G01X328500Y110000D02*
X328000Y110083D01*
X327500Y110417D01*
X327167Y111000D01*
X327000Y111667D01*
X327167Y112333D01*
X327500Y112917D01*
X328000Y113250D01*
X328500Y113333D01*
X329000Y113250D01*
X329500Y112917D01*
X329833Y112333D01*
X329917Y111667D01*
X329833Y111000D01*
X329500Y110417D01*
X329000Y110083D01*
X328500Y110000D01*
G01X332850Y110583D02*
X333267Y110250D01*
X333850Y110000D01*
X334350D01*
X334850Y110167D01*
X335183Y110417D01*
X335350Y110750D01*
X335267Y111250D01*
X334933Y111500D01*
X333433Y112000D01*
X333100Y112583D01*
X333267Y113000D01*
X333600Y113250D01*
X334100Y113333D01*
X334600Y113250D01*
X335100Y113000D01*
G01X339700Y113333D02*
Y110000D01*
G01Y114667D02*
X339533Y114750D01*
Y114917D01*
X339700Y115000D01*
X339867Y114917D01*
Y114750D01*
X339700Y114667D01*
G01X345300Y115000D02*
Y110000D01*
G01X344133Y113333D02*
X346467D01*
G01X350900D02*
Y110000D01*
G01Y114667D02*
X350733Y114750D01*
Y114917D01*
X350900Y115000D01*
X351067Y114917D01*
Y114750D01*
X350900Y114667D01*
G01X356500Y110000D02*
X356000Y110083D01*
X355500Y110417D01*
X355167Y111000D01*
X355000Y111667D01*
X355167Y112333D01*
X355500Y112917D01*
X356000Y113250D01*
X356500Y113333D01*
X357000Y113250D01*
X357500Y112917D01*
X357833Y112333D01*
X357917Y111667D01*
X357833Y111000D01*
X357500Y110417D01*
X357000Y110083D01*
X356500Y110000D01*
G01X360683D02*
Y113333D01*
G01Y112500D02*
X361017Y112917D01*
X361517Y113250D01*
X362183Y113333D01*
X362767Y113250D01*
X363267Y112917D01*
X363517Y112333D01*
Y110000D01*
G01X371800D02*
Y115000D01*
G01Y112500D02*
X372217Y113000D01*
X372717Y113250D01*
X373217Y113333D01*
X373967Y113167D01*
X374467Y112833D01*
X374800Y112250D01*
Y111583D01*
X374633Y110917D01*
X374300Y110417D01*
X373717Y110083D01*
X373217Y110000D01*
X372717Y110083D01*
X372217Y110333D01*
X371800Y110750D01*
G01X377650Y112250D02*
X380317D01*
X380067Y112833D01*
X379650Y113167D01*
X379067Y113333D01*
X378483Y113250D01*
X377983Y113000D01*
X377650Y112417D01*
X377483Y111917D01*
Y111417D01*
X377650Y110917D01*
X378067Y110417D01*
X378567Y110083D01*
X379150Y110000D01*
X379733Y110167D01*
X380317Y110667D01*
G01X384500Y115000D02*
Y110000D01*
G01X383333Y113333D02*
X385667D01*
G01X388017D02*
X389017Y110000D01*
X390100Y113333D01*
X391183Y110000D01*
X392183Y113333D01*
G01X394450Y112250D02*
X397117D01*
X396867Y112833D01*
X396450Y113167D01*
X395867Y113333D01*
X395283Y113250D01*
X394783Y113000D01*
X394450Y112417D01*
X394283Y111917D01*
Y111417D01*
X394450Y110917D01*
X394867Y110417D01*
X395367Y110083D01*
X395950Y110000D01*
X396533Y110167D01*
X397117Y110667D01*
G01X400050Y112250D02*
X402717D01*
X402467Y112833D01*
X402050Y113167D01*
X401467Y113333D01*
X400883Y113250D01*
X400383Y113000D01*
X400050Y112417D01*
X399883Y111917D01*
Y111417D01*
X400050Y110917D01*
X400467Y110417D01*
X400967Y110083D01*
X401550Y110000D01*
X402133Y110167D01*
X402717Y110667D01*
G01X405483Y110000D02*
Y113333D01*
G01Y112500D02*
X405817Y112917D01*
X406317Y113250D01*
X406983Y113333D01*
X407567Y113250D01*
X408067Y112917D01*
X408317Y112333D01*
Y110000D01*
G01X419600D02*
Y113333D01*
G01Y112750D02*
X419267Y113083D01*
X418767Y113250D01*
X418183Y113333D01*
X417600Y113167D01*
X417100Y112833D01*
X416767Y112333D01*
X416600Y111667D01*
X416767Y111000D01*
X417100Y110500D01*
X417600Y110167D01*
X418183Y110000D01*
X418767Y110083D01*
X419267Y110333D01*
X419600Y110667D01*
G01X422283Y110000D02*
Y113333D01*
G01Y112500D02*
X422617Y112917D01*
X423117Y113250D01*
X423783Y113333D01*
X424367Y113250D01*
X424867Y112917D01*
X425117Y112333D01*
Y110000D01*
G01X427550Y108500D02*
X428050Y108333D01*
X428717Y108500D01*
X429133Y108833D01*
X429467Y109250D01*
X429967Y110583D01*
X431050Y113333D01*
G01X428383D02*
X429967Y110583D01*
G01X439000Y108333D02*
Y113333D01*
G01Y112583D02*
X439417Y113000D01*
X439833Y113250D01*
X440500Y113333D01*
X441083Y113250D01*
X441667Y112833D01*
X441917Y112250D01*
X442000Y111667D01*
X441917Y111083D01*
X441667Y110500D01*
X441167Y110167D01*
X440500Y110000D01*
X439917Y110083D01*
X439333Y110333D01*
X439000Y110667D01*
G01X447600Y110000D02*
Y113333D01*
G01Y112750D02*
X447267Y113083D01*
X446767Y113250D01*
X446183Y113333D01*
X445600Y113167D01*
X445100Y112833D01*
X444767Y112333D01*
X444600Y111667D01*
X444767Y111000D01*
X445100Y110500D01*
X445600Y110167D01*
X446183Y110000D01*
X446767Y110083D01*
X447267Y110333D01*
X447600Y110667D01*
G01X453200Y115000D02*
Y110000D01*
G01Y110750D02*
X452867Y110333D01*
X452367Y110083D01*
X451783Y110000D01*
X451117Y110167D01*
X450617Y110583D01*
X450283Y111083D01*
X450200Y111667D01*
X450283Y112250D01*
X450617Y112750D01*
X451117Y113167D01*
X451783Y113333D01*
X452367Y113250D01*
X452783Y113083D01*
X453200Y112750D01*
G01X462900Y115000D02*
Y110000D01*
G01X461733Y113333D02*
X464067D01*
G01X468500Y110000D02*
X468000Y110083D01*
X467500Y110417D01*
X467167Y111000D01*
X467000Y111667D01*
X467167Y112333D01*
X467500Y112917D01*
X468000Y113250D01*
X468500Y113333D01*
X469000Y113250D01*
X469500Y112917D01*
X469833Y112333D01*
X469917Y111667D01*
X469833Y111000D01*
X469500Y110417D01*
X469000Y110083D01*
X468500Y110000D01*
G01X478200Y108333D02*
Y113333D01*
G01Y112583D02*
X478617Y113000D01*
X479033Y113250D01*
X479700Y113333D01*
X480283Y113250D01*
X480867Y112833D01*
X481117Y112250D01*
X481200Y111667D01*
X481117Y111083D01*
X480867Y110500D01*
X480367Y110167D01*
X479700Y110000D01*
X479117Y110083D01*
X478533Y110333D01*
X478200Y110667D01*
G01X486800Y110000D02*
Y113333D01*
G01Y112750D02*
X486467Y113083D01*
X485967Y113250D01*
X485383Y113333D01*
X484800Y113167D01*
X484300Y112833D01*
X483967Y112333D01*
X483800Y111667D01*
X483967Y111000D01*
X484300Y110500D01*
X484800Y110167D01*
X485383Y110000D01*
X485967Y110083D01*
X486467Y110333D01*
X486800Y110667D01*
G01X492400Y115000D02*
Y110000D01*
G01Y110750D02*
X492067Y110333D01*
X491567Y110083D01*
X490983Y110000D01*
X490317Y110167D01*
X489817Y110583D01*
X489483Y111083D01*
X489400Y111667D01*
X489483Y112250D01*
X489817Y112750D01*
X490317Y113167D01*
X490983Y113333D01*
X491567Y113250D01*
X491983Y113083D01*
X492400Y112750D01*
G01X270750Y125000D02*
Y130000D01*
G01X274250D02*
Y125000D01*
G01Y127500D02*
X270750D01*
G01X276267Y125000D02*
Y130000D01*
X277933D01*
X278600Y129750D01*
X279100Y129417D01*
X279517Y128917D01*
X279850Y128333D01*
X279933Y127500D01*
X279850Y126667D01*
X279517Y126083D01*
X279100Y125583D01*
X278600Y125250D01*
X277933Y125000D01*
X276267D01*
G01X282700Y130000D02*
X284700D01*
G01X283700D02*
Y125000D01*
G01X282700D02*
X284700D01*
G01X293233D02*
Y130000D01*
X295233D01*
X295900Y129750D01*
X296400Y129167D01*
X296567Y128500D01*
X296400Y127833D01*
X295983Y127333D01*
X295233Y127083D01*
X293233D01*
G01X302333Y129583D02*
X301833Y129833D01*
X301250Y130000D01*
X300583D01*
X299833Y129750D01*
X299250Y129333D01*
X298833Y128833D01*
X298500Y128000D01*
X298417Y127250D01*
X298583Y126500D01*
X298833Y126000D01*
X299333Y125500D01*
X299917Y125167D01*
X300500Y125000D01*
X301083D01*
X301667Y125167D01*
X302167Y125417D01*
X302583Y125750D01*
G01X306767Y127667D02*
X307100Y127917D01*
X307350Y128333D01*
X307517Y128917D01*
X307350Y129417D01*
X307017Y129750D01*
X306433Y130000D01*
X304183D01*
Y125000D01*
X306933D01*
X307517Y125333D01*
X307850Y125833D01*
X308017Y126417D01*
X307850Y127000D01*
X307350Y127500D01*
X306767Y127667D01*
X304183D01*
G01X311700Y124833D02*
X311533Y124917D01*
Y125083D01*
X311700Y125167D01*
X311867Y125083D01*
Y124917D01*
X311700Y124833D01*
G01X264000Y75500D02*
X694500D01*
G01X264000Y90500D02*
X694500D01*
G01X271250Y141583D02*
X271667Y141250D01*
X272250Y141000D01*
X272750D01*
X273250Y141167D01*
X273583Y141417D01*
X273750Y141750D01*
X273667Y142250D01*
X273333Y142500D01*
X271833Y143000D01*
X271500Y143583D01*
X271667Y144000D01*
X272000Y144250D01*
X272500Y144333D01*
X273000Y144250D01*
X273500Y144000D01*
G01X276600Y139333D02*
Y144333D01*
G01Y143583D02*
X277017Y144000D01*
X277433Y144250D01*
X278100Y144333D01*
X278683Y144250D01*
X279267Y143833D01*
X279517Y143250D01*
X279600Y142667D01*
X279517Y142083D01*
X279267Y141500D01*
X278767Y141167D01*
X278100Y141000D01*
X277517Y141083D01*
X276933Y141333D01*
X276600Y141667D01*
G01X282450Y143250D02*
X285117D01*
X284867Y143833D01*
X284450Y144167D01*
X283867Y144333D01*
X283283Y144250D01*
X282783Y144000D01*
X282450Y143417D01*
X282283Y142917D01*
Y142417D01*
X282450Y141917D01*
X282867Y141417D01*
X283367Y141083D01*
X283950Y141000D01*
X284533Y141167D01*
X285117Y141667D01*
G01X290633Y143917D02*
X290050Y144250D01*
X289550Y144333D01*
X288883Y144167D01*
X288383Y143833D01*
X288050Y143250D01*
X287967Y142667D01*
X288050Y142083D01*
X288383Y141583D01*
X288883Y141167D01*
X289550Y141000D01*
X290133Y141167D01*
X290633Y141500D01*
G01X294900Y144333D02*
Y141000D01*
G01Y145667D02*
X294733Y145750D01*
Y145917D01*
X294900Y146000D01*
X295067Y145917D01*
Y145750D01*
X294900Y145667D01*
G01X300000Y141000D02*
Y145250D01*
X300167Y145667D01*
X300500Y145917D01*
X301000Y146000D01*
X301500Y145833D01*
X301750Y145417D01*
G01X300750Y144000D02*
X299083D01*
G01X306100Y144333D02*
Y141000D01*
G01Y145667D02*
X305933Y145750D01*
Y145917D01*
X306100Y146000D01*
X306267Y145917D01*
Y145750D01*
X306100Y145667D01*
G01X313033Y143917D02*
X312450Y144250D01*
X311950Y144333D01*
X311283Y144167D01*
X310783Y143833D01*
X310450Y143250D01*
X310367Y142667D01*
X310450Y142083D01*
X310783Y141583D01*
X311283Y141167D01*
X311950Y141000D01*
X312533Y141167D01*
X313033Y141500D01*
G01X318800Y141000D02*
Y144333D01*
G01Y143750D02*
X318467Y144083D01*
X317967Y144250D01*
X317383Y144333D01*
X316800Y144167D01*
X316300Y143833D01*
X315967Y143333D01*
X315800Y142667D01*
X315967Y142000D01*
X316300Y141500D01*
X316800Y141167D01*
X317383Y141000D01*
X317967Y141083D01*
X318467Y141333D01*
X318800Y141667D01*
G01X322900Y146000D02*
Y141000D01*
G01X321733Y144333D02*
X324067D01*
G01X328500D02*
Y141000D01*
G01Y145667D02*
X328333Y145750D01*
Y145917D01*
X328500Y146000D01*
X328667Y145917D01*
Y145750D01*
X328500Y145667D01*
G01X334100Y141000D02*
X333600Y141083D01*
X333100Y141417D01*
X332767Y142000D01*
X332600Y142667D01*
X332767Y143333D01*
X333100Y143917D01*
X333600Y144250D01*
X334100Y144333D01*
X334600Y144250D01*
X335100Y143917D01*
X335433Y143333D01*
X335517Y142667D01*
X335433Y142000D01*
X335100Y141417D01*
X334600Y141083D01*
X334100Y141000D01*
G01X338283D02*
Y144333D01*
G01Y143500D02*
X338617Y143917D01*
X339117Y144250D01*
X339783Y144333D01*
X340367Y144250D01*
X340867Y143917D01*
X341117Y143333D01*
Y141000D01*
G01X345300Y140833D02*
X345133Y140917D01*
Y141083D01*
X345300Y141167D01*
X345467Y141083D01*
Y140917D01*
X345300Y140833D01*
G01X270750Y150667D02*
X271417Y150250D01*
X272167Y150000D01*
X272833D01*
X273500Y150250D01*
X274000Y150667D01*
X274250Y151250D01*
X274083Y151833D01*
X273667Y152333D01*
X272917Y152667D01*
X271917Y152833D01*
X271333Y153167D01*
X271083Y153750D01*
X271250Y154333D01*
X271667Y154750D01*
X272250Y155000D01*
X272833D01*
X273417Y154833D01*
X273917Y154417D01*
G01X276850Y152250D02*
X279517D01*
X279267Y152833D01*
X278850Y153167D01*
X278267Y153333D01*
X277683Y153250D01*
X277183Y153000D01*
X276850Y152417D01*
X276683Y151917D01*
Y151417D01*
X276850Y150917D01*
X277267Y150417D01*
X277767Y150083D01*
X278350Y150000D01*
X278933Y150167D01*
X279517Y150667D01*
G01X282533Y150000D02*
Y153333D01*
G01Y152667D02*
X282950Y153000D01*
X283367Y153250D01*
X283950Y153333D01*
X284367Y153250D01*
X284867Y153000D01*
G01X287800Y153333D02*
X289300Y150000D01*
X290800Y153333D01*
G01X293650Y152250D02*
X296317D01*
X296067Y152833D01*
X295650Y153167D01*
X295067Y153333D01*
X294483Y153250D01*
X293983Y153000D01*
X293650Y152417D01*
X293483Y151917D01*
Y151417D01*
X293650Y150917D01*
X294067Y150417D01*
X294567Y150083D01*
X295150Y150000D01*
X295733Y150167D01*
X296317Y150667D01*
G01X299333Y150000D02*
Y153333D01*
G01Y152667D02*
X299750Y153000D01*
X300167Y153250D01*
X300750Y153333D01*
X301167Y153250D01*
X301667Y153000D01*
G01X310033Y150000D02*
Y155000D01*
X312033D01*
X312700Y154750D01*
X313200Y154167D01*
X313367Y153500D01*
X313200Y152833D01*
X312783Y152333D01*
X312033Y152083D01*
X310033D01*
G01X319133Y154583D02*
X318633Y154833D01*
X318050Y155000D01*
X317383D01*
X316633Y154750D01*
X316050Y154333D01*
X315633Y153833D01*
X315300Y153000D01*
X315217Y152250D01*
X315383Y151500D01*
X315633Y151000D01*
X316133Y150500D01*
X316717Y150167D01*
X317300Y150000D01*
X317883D01*
X318467Y150167D01*
X318967Y150417D01*
X319383Y150750D01*
G01X323567Y152667D02*
X323900Y152917D01*
X324150Y153333D01*
X324317Y153917D01*
X324150Y154417D01*
X323817Y154750D01*
X323233Y155000D01*
X320983D01*
Y150000D01*
X323733D01*
X324317Y150333D01*
X324650Y150833D01*
X324817Y151417D01*
X324650Y152000D01*
X324150Y152500D01*
X323567Y152667D01*
X320983D01*
G01X328500Y149833D02*
X328333Y149917D01*
Y150083D01*
X328500Y150167D01*
X328667Y150083D01*
Y149917D01*
X328500Y149833D01*
G01Y152083D02*
X328333Y152167D01*
Y152333D01*
X328500Y152417D01*
X328667Y152333D01*
Y152167D01*
X328500Y152083D01*
G01X332517Y150000D02*
Y155000D01*
X335683D01*
G01X334517Y152583D02*
X332517D01*
G01X339700Y150000D02*
X339200Y150083D01*
X338700Y150417D01*
X338367Y151000D01*
X338200Y151667D01*
X338367Y152333D01*
X338700Y152917D01*
X339200Y153250D01*
X339700Y153333D01*
X340200Y153250D01*
X340700Y152917D01*
X341033Y152333D01*
X341117Y151667D01*
X341033Y151000D01*
X340700Y150417D01*
X340200Y150083D01*
X339700Y150000D01*
G01X345300D02*
Y155000D01*
G01X350900Y150000D02*
Y155000D01*
G01X356500Y150000D02*
X356000Y150083D01*
X355500Y150417D01*
X355167Y151000D01*
X355000Y151667D01*
X355167Y152333D01*
X355500Y152917D01*
X356000Y153250D01*
X356500Y153333D01*
X357000Y153250D01*
X357500Y152917D01*
X357833Y152333D01*
X357917Y151667D01*
X357833Y151000D01*
X357500Y150417D01*
X357000Y150083D01*
X356500Y150000D01*
G01X360017Y153333D02*
X361017Y150000D01*
X362100Y153333D01*
X363183Y150000D01*
X364183Y153333D01*
G01X372133Y150000D02*
Y153333D01*
G01Y152667D02*
X372550Y153000D01*
X372967Y153250D01*
X373550Y153333D01*
X373967Y153250D01*
X374467Y153000D01*
G01X378900Y153333D02*
Y150000D01*
G01Y154667D02*
X378733Y154750D01*
Y154917D01*
X378900Y155000D01*
X379067Y154917D01*
Y154750D01*
X378900Y154667D01*
G01X383333Y148750D02*
X383917Y148417D01*
X384583Y148333D01*
X385167Y148417D01*
X385667Y148833D01*
X386000Y149417D01*
Y153333D01*
G01Y152667D02*
X385667Y153000D01*
X385167Y153250D01*
X384583Y153333D01*
X383917Y153167D01*
X383500Y152833D01*
X383167Y152250D01*
X383000Y151667D01*
X383083Y151167D01*
X383417Y150583D01*
X383917Y150167D01*
X384583Y150000D01*
X385083Y150083D01*
X385667Y150417D01*
X386000Y150750D01*
G01X388683Y150000D02*
Y155000D01*
G01Y152583D02*
X389100Y153000D01*
X389517Y153250D01*
X390183Y153333D01*
X390683Y153250D01*
X391267Y152917D01*
X391517Y152417D01*
Y150000D01*
G01X395700Y155000D02*
Y150000D01*
G01X394533Y153333D02*
X396867D01*
G01X405650Y150583D02*
X406067Y150250D01*
X406650Y150000D01*
X407150D01*
X407650Y150167D01*
X407983Y150417D01*
X408150Y150750D01*
X408067Y151250D01*
X407733Y151500D01*
X406233Y152000D01*
X405900Y152583D01*
X406067Y153000D01*
X406400Y153250D01*
X406900Y153333D01*
X407400Y153250D01*
X407900Y153000D01*
G01X412500Y153333D02*
Y150000D01*
G01Y154667D02*
X412333Y154750D01*
Y154917D01*
X412500Y155000D01*
X412667Y154917D01*
Y154750D01*
X412500Y154667D01*
G01X419600Y155000D02*
Y150000D01*
G01Y150750D02*
X419267Y150333D01*
X418767Y150083D01*
X418183Y150000D01*
X417517Y150167D01*
X417017Y150583D01*
X416683Y151083D01*
X416600Y151667D01*
X416683Y152250D01*
X417017Y152750D01*
X417517Y153167D01*
X418183Y153333D01*
X418767Y153250D01*
X419183Y153083D01*
X419600Y152750D01*
G01X422450Y152250D02*
X425117D01*
X424867Y152833D01*
X424450Y153167D01*
X423867Y153333D01*
X423283Y153250D01*
X422783Y153000D01*
X422450Y152417D01*
X422283Y151917D01*
Y151417D01*
X422450Y150917D01*
X422867Y150417D01*
X423367Y150083D01*
X423950Y150000D01*
X424533Y150167D01*
X425117Y150667D01*
G01X433650Y150583D02*
X434067Y150250D01*
X434650Y150000D01*
X435150D01*
X435650Y150167D01*
X435983Y150417D01*
X436150Y150750D01*
X436067Y151250D01*
X435733Y151500D01*
X434233Y152000D01*
X433900Y152583D01*
X434067Y153000D01*
X434400Y153250D01*
X434900Y153333D01*
X435400Y153250D01*
X435900Y153000D01*
G01X439000Y148333D02*
Y153333D01*
G01Y152583D02*
X439417Y153000D01*
X439833Y153250D01*
X440500Y153333D01*
X441083Y153250D01*
X441667Y152833D01*
X441917Y152250D01*
X442000Y151667D01*
X441917Y151083D01*
X441667Y150500D01*
X441167Y150167D01*
X440500Y150000D01*
X439917Y150083D01*
X439333Y150333D01*
X439000Y150667D01*
G01X444850Y152250D02*
X447517D01*
X447267Y152833D01*
X446850Y153167D01*
X446267Y153333D01*
X445683Y153250D01*
X445183Y153000D01*
X444850Y152417D01*
X444683Y151917D01*
Y151417D01*
X444850Y150917D01*
X445267Y150417D01*
X445767Y150083D01*
X446350Y150000D01*
X446933Y150167D01*
X447517Y150667D01*
G01X453033Y152917D02*
X452450Y153250D01*
X451950Y153333D01*
X451283Y153167D01*
X450783Y152833D01*
X450450Y152250D01*
X450367Y151667D01*
X450450Y151083D01*
X450783Y150583D01*
X451283Y150167D01*
X451950Y150000D01*
X452533Y150167D01*
X453033Y150500D01*
G01X462733Y149083D02*
X463067Y150167D01*
G01X468500Y153333D02*
Y150000D01*
G01Y154667D02*
X468333Y154750D01*
Y154917D01*
X468500Y155000D01*
X468667Y154917D01*
Y154750D01*
X468500Y154667D01*
G01X473600Y150000D02*
Y154250D01*
X473767Y154667D01*
X474100Y154917D01*
X474600Y155000D01*
X475100Y154833D01*
X475350Y154417D01*
G01X474350Y153000D02*
X472683D01*
G01X484050Y150583D02*
X484467Y150250D01*
X485050Y150000D01*
X485550D01*
X486050Y150167D01*
X486383Y150417D01*
X486550Y150750D01*
X486467Y151250D01*
X486133Y151500D01*
X484633Y152000D01*
X484300Y152583D01*
X484467Y153000D01*
X484800Y153250D01*
X485300Y153333D01*
X485800Y153250D01*
X486300Y153000D01*
G01X490900Y155000D02*
Y150000D01*
G01X489733Y153333D02*
X492067D01*
G01X498000Y150000D02*
Y153333D01*
G01Y152750D02*
X497667Y153083D01*
X497167Y153250D01*
X496583Y153333D01*
X496000Y153167D01*
X495500Y152833D01*
X495167Y152333D01*
X495000Y151667D01*
X495167Y151000D01*
X495500Y150500D01*
X496000Y150167D01*
X496583Y150000D01*
X497167Y150083D01*
X497667Y150333D01*
X498000Y150667D01*
G01X503433Y152917D02*
X502850Y153250D01*
X502350Y153333D01*
X501683Y153167D01*
X501183Y152833D01*
X500850Y152250D01*
X500767Y151667D01*
X500850Y151083D01*
X501183Y150583D01*
X501683Y150167D01*
X502350Y150000D01*
X502933Y150167D01*
X503433Y150500D01*
G01X506283Y150000D02*
Y155000D01*
G01X508950Y153333D02*
X506283Y151417D01*
G01X507367Y152167D02*
X509117Y150000D01*
G01X517483Y153333D02*
Y151000D01*
X517817Y150417D01*
X518317Y150083D01*
X518900Y150000D01*
X519483Y150083D01*
X519983Y150417D01*
X520317Y151000D01*
G01Y150000D02*
Y153333D01*
G01X523000Y148333D02*
Y153333D01*
G01Y152583D02*
X523417Y153000D01*
X523833Y153250D01*
X524500Y153333D01*
X525083Y153250D01*
X525667Y152833D01*
X525917Y152250D01*
X526000Y151667D01*
X525917Y151083D01*
X525667Y150500D01*
X525167Y150167D01*
X524500Y150000D01*
X523917Y150083D01*
X523333Y150333D01*
X523000Y150667D01*
G01X533617Y153333D02*
X534617Y150000D01*
X535700Y153333D01*
X536783Y150000D01*
X537783Y153333D01*
G01X541300D02*
Y150000D01*
G01Y154667D02*
X541133Y154750D01*
Y154917D01*
X541300Y155000D01*
X541467Y154917D01*
Y154750D01*
X541300Y154667D01*
G01X546900Y155000D02*
Y150000D01*
G01X545733Y153333D02*
X548067D01*
G01X551083Y150000D02*
Y155000D01*
G01Y152583D02*
X551500Y153000D01*
X551917Y153250D01*
X552583Y153333D01*
X553083Y153250D01*
X553667Y152917D01*
X553917Y152417D01*
Y150000D01*
G01X558100D02*
X557600Y150083D01*
X557100Y150417D01*
X556767Y151000D01*
X556600Y151667D01*
X556767Y152333D01*
X557100Y152917D01*
X557600Y153250D01*
X558100Y153333D01*
X558600Y153250D01*
X559100Y152917D01*
X559433Y152333D01*
X559517Y151667D01*
X559433Y151000D01*
X559100Y150417D01*
X558600Y150083D01*
X558100Y150000D01*
G01X562283Y153333D02*
Y151000D01*
X562617Y150417D01*
X563117Y150083D01*
X563700Y150000D01*
X564283Y150083D01*
X564783Y150417D01*
X565117Y151000D01*
G01Y150000D02*
Y153333D01*
G01X569300Y155000D02*
Y150000D01*
G01X568133Y153333D02*
X570467D01*
G01X272500Y170000D02*
Y165000D01*
G01X270583Y170000D02*
X274417D01*
G01X276933Y165000D02*
Y168333D01*
G01Y167667D02*
X277350Y168000D01*
X277767Y168250D01*
X278350Y168333D01*
X278767Y168250D01*
X279267Y168000D01*
G01X285200Y165000D02*
Y168333D01*
G01Y167750D02*
X284867Y168083D01*
X284367Y168250D01*
X283783Y168333D01*
X283200Y168167D01*
X282700Y167833D01*
X282367Y167333D01*
X282200Y166667D01*
X282367Y166000D01*
X282700Y165500D01*
X283200Y165167D01*
X283783Y165000D01*
X284367Y165083D01*
X284867Y165333D01*
X285200Y165667D01*
G01X290800Y170000D02*
Y165000D01*
G01Y165750D02*
X290467Y165333D01*
X289967Y165083D01*
X289383Y165000D01*
X288717Y165167D01*
X288217Y165583D01*
X287883Y166083D01*
X287800Y166667D01*
X287883Y167250D01*
X288217Y167750D01*
X288717Y168167D01*
X289383Y168333D01*
X289967Y168250D01*
X290383Y168083D01*
X290800Y167750D01*
G01X294900Y168333D02*
Y165000D01*
G01Y169667D02*
X294733Y169750D01*
Y169917D01*
X294900Y170000D01*
X295067Y169917D01*
Y169750D01*
X294900Y169667D01*
G01X300500Y170000D02*
Y165000D01*
G01X299333Y168333D02*
X301667D01*
G01X306100D02*
Y165000D01*
G01Y169667D02*
X305933Y169750D01*
Y169917D01*
X306100Y170000D01*
X306267Y169917D01*
Y169750D01*
X306100Y169667D01*
G01X311700Y165000D02*
X311200Y165083D01*
X310700Y165417D01*
X310367Y166000D01*
X310200Y166667D01*
X310367Y167333D01*
X310700Y167917D01*
X311200Y168250D01*
X311700Y168333D01*
X312200Y168250D01*
X312700Y167917D01*
X313033Y167333D01*
X313117Y166667D01*
X313033Y166000D01*
X312700Y165417D01*
X312200Y165083D01*
X311700Y165000D01*
G01X315883D02*
Y168333D01*
G01Y167500D02*
X316217Y167917D01*
X316717Y168250D01*
X317383Y168333D01*
X317967Y168250D01*
X318467Y167917D01*
X318717Y167333D01*
Y165000D01*
G01X324400D02*
Y168333D01*
G01Y167750D02*
X324067Y168083D01*
X323567Y168250D01*
X322983Y168333D01*
X322400Y168167D01*
X321900Y167833D01*
X321567Y167333D01*
X321400Y166667D01*
X321567Y166000D01*
X321900Y165500D01*
X322400Y165167D01*
X322983Y165000D01*
X323567Y165083D01*
X324067Y165333D01*
X324400Y165667D01*
G01X328500Y165000D02*
Y170000D01*
G01X338033Y165000D02*
Y170000D01*
X340033D01*
X340700Y169750D01*
X341200Y169167D01*
X341367Y168500D01*
X341200Y167833D01*
X340783Y167333D01*
X340033Y167083D01*
X338033D01*
G01X347133Y169583D02*
X346633Y169833D01*
X346050Y170000D01*
X345383D01*
X344633Y169750D01*
X344050Y169333D01*
X343633Y168833D01*
X343300Y168000D01*
X343217Y167250D01*
X343383Y166500D01*
X343633Y166000D01*
X344133Y165500D01*
X344717Y165167D01*
X345300Y165000D01*
X345883D01*
X346467Y165167D01*
X346967Y165417D01*
X347383Y165750D01*
G01X351567Y167667D02*
X351900Y167917D01*
X352150Y168333D01*
X352317Y168917D01*
X352150Y169417D01*
X351817Y169750D01*
X351233Y170000D01*
X348983D01*
Y165000D01*
X351733D01*
X352317Y165333D01*
X352650Y165833D01*
X352817Y166417D01*
X352650Y167000D01*
X352150Y167500D01*
X351567Y167667D01*
X348983D01*
G01X356500Y164833D02*
X356333Y164917D01*
Y165083D01*
X356500Y165167D01*
X356667Y165083D01*
Y164917D01*
X356500Y164833D01*
G01X264000Y135500D02*
X694500D01*
G01X264000Y160500D02*
X694500D01*
G01X262500Y237500D02*
X694500D01*
G01X262500Y290500D02*
X694500D01*
G01X270000Y374000D02*
Y369000D01*
G01X268833Y372333D02*
X271167D01*
G01X275600Y369000D02*
X275100Y369083D01*
X274600Y369417D01*
X274267Y370000D01*
X274100Y370667D01*
X274267Y371333D01*
X274600Y371917D01*
X275100Y372250D01*
X275600Y372333D01*
X276100Y372250D01*
X276600Y371917D01*
X276933Y371333D01*
X277017Y370667D01*
X276933Y370000D01*
X276600Y369417D01*
X276100Y369083D01*
X275600Y369000D01*
G01X281200D02*
Y374000D01*
G01X285550Y371250D02*
X288217D01*
X287967Y371833D01*
X287550Y372167D01*
X286967Y372333D01*
X286383Y372250D01*
X285883Y372000D01*
X285550Y371417D01*
X285383Y370917D01*
Y370417D01*
X285550Y369917D01*
X285967Y369417D01*
X286467Y369083D01*
X287050Y369000D01*
X287633Y369167D01*
X288217Y369667D01*
G01X291233Y369000D02*
Y372333D01*
G01Y371667D02*
X291650Y372000D01*
X292067Y372250D01*
X292650Y372333D01*
X293067Y372250D01*
X293567Y372000D01*
G01X299500Y369000D02*
Y372333D01*
G01Y371750D02*
X299167Y372083D01*
X298667Y372250D01*
X298083Y372333D01*
X297500Y372167D01*
X297000Y371833D01*
X296667Y371333D01*
X296500Y370667D01*
X296667Y370000D01*
X297000Y369500D01*
X297500Y369167D01*
X298083Y369000D01*
X298667Y369083D01*
X299167Y369333D01*
X299500Y369667D01*
G01X302183Y369000D02*
Y372333D01*
G01Y371500D02*
X302517Y371917D01*
X303017Y372250D01*
X303683Y372333D01*
X304267Y372250D01*
X304767Y371917D01*
X305017Y371333D01*
Y369000D01*
G01X310533Y371917D02*
X309950Y372250D01*
X309450Y372333D01*
X308783Y372167D01*
X308283Y371833D01*
X307950Y371250D01*
X307867Y370667D01*
X307950Y370083D01*
X308283Y369583D01*
X308783Y369167D01*
X309450Y369000D01*
X310033Y369167D01*
X310533Y369500D01*
G01X313550Y371250D02*
X316217D01*
X315967Y371833D01*
X315550Y372167D01*
X314967Y372333D01*
X314383Y372250D01*
X313883Y372000D01*
X313550Y371417D01*
X313383Y370917D01*
Y370417D01*
X313550Y369917D01*
X313967Y369417D01*
X314467Y369083D01*
X315050Y369000D01*
X315633Y369167D01*
X316217Y369667D01*
G01X326000Y374000D02*
Y369000D01*
G01X324833Y372333D02*
X327167D01*
G01X333100Y369000D02*
Y372333D01*
G01Y371750D02*
X332767Y372083D01*
X332267Y372250D01*
X331683Y372333D01*
X331100Y372167D01*
X330600Y371833D01*
X330267Y371333D01*
X330100Y370667D01*
X330267Y370000D01*
X330600Y369500D01*
X331100Y369167D01*
X331683Y369000D01*
X332267Y369083D01*
X332767Y369333D01*
X333100Y369667D01*
G01X335700Y369000D02*
Y374000D01*
G01Y371500D02*
X336117Y372000D01*
X336617Y372250D01*
X337117Y372333D01*
X337867Y372167D01*
X338367Y371833D01*
X338700Y371250D01*
Y370583D01*
X338533Y369917D01*
X338200Y369417D01*
X337617Y369083D01*
X337117Y369000D01*
X336617Y369083D01*
X336117Y369333D01*
X335700Y369750D01*
G01X342800Y369000D02*
Y374000D01*
G01X347150Y371250D02*
X349817D01*
X349567Y371833D01*
X349150Y372167D01*
X348567Y372333D01*
X347983Y372250D01*
X347483Y372000D01*
X347150Y371417D01*
X346983Y370917D01*
Y370417D01*
X347150Y369917D01*
X347567Y369417D01*
X348067Y369083D01*
X348650Y369000D01*
X349233Y369167D01*
X349817Y369667D01*
G01X354000Y368833D02*
X353833Y368917D01*
Y369083D01*
X354000Y369167D01*
X354167Y369083D01*
Y368917D01*
X354000Y368833D01*
G01X268667Y379750D02*
X269250Y379417D01*
X269750Y379333D01*
X270417Y379500D01*
X270917Y379917D01*
X271167Y380667D01*
Y384333D01*
G01Y385667D02*
X271000Y385750D01*
Y385917D01*
X271167Y386000D01*
X271333Y385917D01*
Y385750D01*
X271167Y385667D01*
G01X274183Y384333D02*
Y382000D01*
X274517Y381417D01*
X275017Y381083D01*
X275600Y381000D01*
X276183Y381083D01*
X276683Y381417D01*
X277017Y382000D01*
G01Y381000D02*
Y384333D01*
G01X279783Y381000D02*
Y384333D01*
G01Y383500D02*
X280117Y383917D01*
X280617Y384250D01*
X281283Y384333D01*
X281867Y384250D01*
X282367Y383917D01*
X282617Y383333D01*
Y381000D01*
G01X288133Y383917D02*
X287550Y384250D01*
X287050Y384333D01*
X286383Y384167D01*
X285883Y383833D01*
X285550Y383250D01*
X285467Y382667D01*
X285550Y382083D01*
X285883Y381583D01*
X286383Y381167D01*
X287050Y381000D01*
X287633Y381167D01*
X288133Y381500D01*
G01X292400Y386000D02*
Y381000D01*
G01X291233Y384333D02*
X293567D01*
G01X298000D02*
Y381000D01*
G01Y385667D02*
X297833Y385750D01*
Y385917D01*
X298000Y386000D01*
X298167Y385917D01*
Y385750D01*
X298000Y385667D01*
G01X303600Y381000D02*
X303100Y381083D01*
X302600Y381417D01*
X302267Y382000D01*
X302100Y382667D01*
X302267Y383333D01*
X302600Y383917D01*
X303100Y384250D01*
X303600Y384333D01*
X304100Y384250D01*
X304600Y383917D01*
X304933Y383333D01*
X305017Y382667D01*
X304933Y382000D01*
X304600Y381417D01*
X304100Y381083D01*
X303600Y381000D01*
G01X307783D02*
Y384333D01*
G01Y383500D02*
X308117Y383917D01*
X308617Y384250D01*
X309283Y384333D01*
X309867Y384250D01*
X310367Y383917D01*
X310617Y383333D01*
Y381000D01*
G01X318900D02*
Y386000D01*
G01Y383500D02*
X319317Y384000D01*
X319817Y384250D01*
X320317Y384333D01*
X321067Y384167D01*
X321567Y383833D01*
X321900Y383250D01*
Y382583D01*
X321733Y381917D01*
X321400Y381417D01*
X320817Y381083D01*
X320317Y381000D01*
X319817Y381083D01*
X319317Y381333D01*
X318900Y381750D01*
G01X324750Y383250D02*
X327417D01*
X327167Y383833D01*
X326750Y384167D01*
X326167Y384333D01*
X325583Y384250D01*
X325083Y384000D01*
X324750Y383417D01*
X324583Y382917D01*
Y382417D01*
X324750Y381917D01*
X325167Y381417D01*
X325667Y381083D01*
X326250Y381000D01*
X326833Y381167D01*
X327417Y381667D01*
G01X331600Y381000D02*
Y386000D01*
G01X337200Y381000D02*
X336700Y381083D01*
X336200Y381417D01*
X335867Y382000D01*
X335700Y382667D01*
X335867Y383333D01*
X336200Y383917D01*
X336700Y384250D01*
X337200Y384333D01*
X337700Y384250D01*
X338200Y383917D01*
X338533Y383333D01*
X338617Y382667D01*
X338533Y382000D01*
X338200Y381417D01*
X337700Y381083D01*
X337200Y381000D01*
G01X340717Y384333D02*
X341717Y381000D01*
X342800Y384333D01*
X343883Y381000D01*
X344883Y384333D01*
G01X354000Y386000D02*
Y381000D01*
G01X352833Y384333D02*
X355167D01*
G01X358183Y381000D02*
Y386000D01*
G01Y383583D02*
X358600Y384000D01*
X359017Y384250D01*
X359683Y384333D01*
X360183Y384250D01*
X360767Y383917D01*
X361017Y383417D01*
Y381000D01*
G01X363950Y383250D02*
X366617D01*
X366367Y383833D01*
X365950Y384167D01*
X365367Y384333D01*
X364783Y384250D01*
X364283Y384000D01*
X363950Y383417D01*
X363783Y382917D01*
Y382417D01*
X363950Y381917D01*
X364367Y381417D01*
X364867Y381083D01*
X365450Y381000D01*
X366033Y381167D01*
X366617Y381667D01*
G01X373900Y381000D02*
Y384333D01*
G01Y383417D02*
X374150Y383833D01*
X374567Y384167D01*
X375150Y384333D01*
X375733Y384167D01*
X376150Y383833D01*
X376400Y383417D01*
Y381000D01*
G01Y383417D02*
X376650Y383833D01*
X377067Y384167D01*
X377650Y384333D01*
X378233Y384167D01*
X378650Y383833D01*
X378900Y383333D01*
Y381000D01*
G01X382000Y384333D02*
Y381000D01*
G01Y385667D02*
X381833Y385750D01*
Y385917D01*
X382000Y386000D01*
X382167Y385917D01*
Y385750D01*
X382000Y385667D01*
G01X386183Y381000D02*
Y384333D01*
G01Y383500D02*
X386517Y383917D01*
X387017Y384250D01*
X387683Y384333D01*
X388267Y384250D01*
X388767Y383917D01*
X389017Y383333D01*
Y381000D01*
G01X400133Y383917D02*
X399550Y384250D01*
X399050Y384333D01*
X398383Y384167D01*
X397883Y383833D01*
X397550Y383250D01*
X397467Y382667D01*
X397550Y382083D01*
X397883Y381583D01*
X398383Y381167D01*
X399050Y381000D01*
X399633Y381167D01*
X400133Y381500D01*
G01X404400Y381000D02*
X403900Y381083D01*
X403400Y381417D01*
X403067Y382000D01*
X402900Y382667D01*
X403067Y383333D01*
X403400Y383917D01*
X403900Y384250D01*
X404400Y384333D01*
X404900Y384250D01*
X405400Y383917D01*
X405733Y383333D01*
X405817Y382667D01*
X405733Y382000D01*
X405400Y381417D01*
X404900Y381083D01*
X404400Y381000D01*
G01X408583D02*
Y384333D01*
G01Y383500D02*
X408917Y383917D01*
X409417Y384250D01*
X410083Y384333D01*
X410667Y384250D01*
X411167Y383917D01*
X411417Y383333D01*
Y381000D01*
G01X417100Y386000D02*
Y381000D01*
G01Y381750D02*
X416767Y381333D01*
X416267Y381083D01*
X415683Y381000D01*
X415017Y381167D01*
X414517Y381583D01*
X414183Y382083D01*
X414100Y382667D01*
X414183Y383250D01*
X414517Y383750D01*
X415017Y384167D01*
X415683Y384333D01*
X416267Y384250D01*
X416683Y384083D01*
X417100Y383750D01*
G01X419783Y384333D02*
Y382000D01*
X420117Y381417D01*
X420617Y381083D01*
X421200Y381000D01*
X421783Y381083D01*
X422283Y381417D01*
X422617Y382000D01*
G01Y381000D02*
Y384333D01*
G01X428133Y383917D02*
X427550Y384250D01*
X427050Y384333D01*
X426383Y384167D01*
X425883Y383833D01*
X425550Y383250D01*
X425467Y382667D01*
X425550Y382083D01*
X425883Y381583D01*
X426383Y381167D01*
X427050Y381000D01*
X427633Y381167D01*
X428133Y381500D01*
G01X432400Y386000D02*
Y381000D01*
G01X431233Y384333D02*
X433567D01*
G01X438000Y381000D02*
X437500Y381083D01*
X437000Y381417D01*
X436667Y382000D01*
X436500Y382667D01*
X436667Y383333D01*
X437000Y383917D01*
X437500Y384250D01*
X438000Y384333D01*
X438500Y384250D01*
X439000Y383917D01*
X439333Y383333D01*
X439417Y382667D01*
X439333Y382000D01*
X439000Y381417D01*
X438500Y381083D01*
X438000Y381000D01*
G01X442433D02*
Y384333D01*
G01Y383667D02*
X442850Y384000D01*
X443267Y384250D01*
X443850Y384333D01*
X444267Y384250D01*
X444767Y384000D01*
G01X452717Y384333D02*
X453717Y381000D01*
X454800Y384333D01*
X455883Y381000D01*
X456883Y384333D01*
G01X460400D02*
Y381000D01*
G01Y385667D02*
X460233Y385750D01*
Y385917D01*
X460400Y386000D01*
X460567Y385917D01*
Y385750D01*
X460400Y385667D01*
G01X467500Y386000D02*
Y381000D01*
G01Y381750D02*
X467167Y381333D01*
X466667Y381083D01*
X466083Y381000D01*
X465417Y381167D01*
X464917Y381583D01*
X464583Y382083D01*
X464500Y382667D01*
X464583Y383250D01*
X464917Y383750D01*
X465417Y384167D01*
X466083Y384333D01*
X466667Y384250D01*
X467083Y384083D01*
X467500Y383750D01*
G01X471600Y386000D02*
Y381000D01*
G01X470433Y384333D02*
X472767D01*
G01X475783Y381000D02*
Y386000D01*
G01Y383583D02*
X476200Y384000D01*
X476617Y384250D01*
X477283Y384333D01*
X477783Y384250D01*
X478367Y383917D01*
X478617Y383417D01*
Y381000D01*
G01X487150Y381583D02*
X487567Y381250D01*
X488150Y381000D01*
X488650D01*
X489150Y381167D01*
X489483Y381417D01*
X489650Y381750D01*
X489567Y382250D01*
X489233Y382500D01*
X487733Y383000D01*
X487400Y383583D01*
X487567Y384000D01*
X487900Y384250D01*
X488400Y384333D01*
X488900Y384250D01*
X489400Y384000D01*
G01X492500Y379333D02*
Y384333D01*
G01Y383583D02*
X492917Y384000D01*
X493333Y384250D01*
X494000Y384333D01*
X494583Y384250D01*
X495167Y383833D01*
X495417Y383250D01*
X495500Y382667D01*
X495417Y382083D01*
X495167Y381500D01*
X494667Y381167D01*
X494000Y381000D01*
X493417Y381083D01*
X492833Y381333D01*
X492500Y381667D01*
G01X498350Y383250D02*
X501017D01*
X500767Y383833D01*
X500350Y384167D01*
X499767Y384333D01*
X499183Y384250D01*
X498683Y384000D01*
X498350Y383417D01*
X498183Y382917D01*
Y382417D01*
X498350Y381917D01*
X498767Y381417D01*
X499267Y381083D01*
X499850Y381000D01*
X500433Y381167D01*
X501017Y381667D01*
G01X506533Y383917D02*
X505950Y384250D01*
X505450Y384333D01*
X504783Y384167D01*
X504283Y383833D01*
X503950Y383250D01*
X503867Y382667D01*
X503950Y382083D01*
X504283Y381583D01*
X504783Y381167D01*
X505450Y381000D01*
X506033Y381167D01*
X506533Y381500D01*
G01X510800Y384333D02*
Y381000D01*
G01Y385667D02*
X510633Y385750D01*
Y385917D01*
X510800Y386000D01*
X510967Y385917D01*
Y385750D01*
X510800Y385667D01*
G01X515900Y381000D02*
Y385250D01*
X516067Y385667D01*
X516400Y385917D01*
X516900Y386000D01*
X517400Y385833D01*
X517650Y385417D01*
G01X516650Y384000D02*
X514983D01*
G01X522000Y384333D02*
Y381000D01*
G01Y385667D02*
X521833Y385750D01*
Y385917D01*
X522000Y386000D01*
X522167Y385917D01*
Y385750D01*
X522000Y385667D01*
G01X526350Y383250D02*
X529017D01*
X528767Y383833D01*
X528350Y384167D01*
X527767Y384333D01*
X527183Y384250D01*
X526683Y384000D01*
X526350Y383417D01*
X526183Y382917D01*
Y382417D01*
X526350Y381917D01*
X526767Y381417D01*
X527267Y381083D01*
X527850Y381000D01*
X528433Y381167D01*
X529017Y381667D01*
G01X534700Y386000D02*
Y381000D01*
G01Y381750D02*
X534367Y381333D01*
X533867Y381083D01*
X533283Y381000D01*
X532617Y381167D01*
X532117Y381583D01*
X531783Y382083D01*
X531700Y382667D01*
X531783Y383250D01*
X532117Y383750D01*
X532617Y384167D01*
X533283Y384333D01*
X533867Y384250D01*
X534283Y384083D01*
X534700Y383750D01*
G01X544400Y381000D02*
X543900Y381083D01*
X543400Y381417D01*
X543067Y382000D01*
X542900Y382667D01*
X543067Y383333D01*
X543400Y383917D01*
X543900Y384250D01*
X544400Y384333D01*
X544900Y384250D01*
X545400Y383917D01*
X545733Y383333D01*
X545817Y382667D01*
X545733Y382000D01*
X545400Y381417D01*
X544900Y381083D01*
X544400Y381000D01*
G01X548583D02*
Y384333D01*
G01Y383500D02*
X548917Y383917D01*
X549417Y384250D01*
X550083Y384333D01*
X550667Y384250D01*
X551167Y383917D01*
X551417Y383333D01*
Y381000D01*
G01X561200Y386000D02*
Y381000D01*
G01X560033Y384333D02*
X562367D01*
G01X565383Y381000D02*
Y386000D01*
G01Y383583D02*
X565800Y384000D01*
X566217Y384250D01*
X566883Y384333D01*
X567383Y384250D01*
X567967Y383917D01*
X568217Y383417D01*
Y381000D01*
G01X571150Y383250D02*
X573817D01*
X573567Y383833D01*
X573150Y384167D01*
X572567Y384333D01*
X571983Y384250D01*
X571483Y384000D01*
X571150Y383417D01*
X570983Y382917D01*
Y382417D01*
X571150Y381917D01*
X571567Y381417D01*
X572067Y381083D01*
X572650Y381000D01*
X573233Y381167D01*
X573817Y381667D01*
G01X268250Y391500D02*
Y396500D01*
G01X271750D02*
Y391500D01*
G01Y394000D02*
X268250D01*
G01X275600Y391500D02*
X275100Y391583D01*
X274600Y391917D01*
X274267Y392500D01*
X274100Y393167D01*
X274267Y393833D01*
X274600Y394417D01*
X275100Y394750D01*
X275600Y394833D01*
X276100Y394750D01*
X276600Y394417D01*
X276933Y393833D01*
X277017Y393167D01*
X276933Y392500D01*
X276600Y391917D01*
X276100Y391583D01*
X275600Y391500D01*
G01X279117Y394833D02*
X280117Y391500D01*
X281200Y394833D01*
X282283Y391500D01*
X283283Y394833D01*
G01X285550Y393750D02*
X288217D01*
X287967Y394333D01*
X287550Y394667D01*
X286967Y394833D01*
X286383Y394750D01*
X285883Y394500D01*
X285550Y393917D01*
X285383Y393417D01*
Y392917D01*
X285550Y392417D01*
X285967Y391917D01*
X286467Y391583D01*
X287050Y391500D01*
X287633Y391667D01*
X288217Y392167D01*
G01X290900Y394833D02*
X292400Y391500D01*
X293900Y394833D01*
G01X296750Y393750D02*
X299417D01*
X299167Y394333D01*
X298750Y394667D01*
X298167Y394833D01*
X297583Y394750D01*
X297083Y394500D01*
X296750Y393917D01*
X296583Y393417D01*
Y392917D01*
X296750Y392417D01*
X297167Y391917D01*
X297667Y391583D01*
X298250Y391500D01*
X298833Y391667D01*
X299417Y392167D01*
G01X302433Y391500D02*
Y394833D01*
G01Y394167D02*
X302850Y394500D01*
X303267Y394750D01*
X303850Y394833D01*
X304267Y394750D01*
X304767Y394500D01*
G01X309033Y390583D02*
X309367Y391667D01*
G01X314800Y396500D02*
Y391500D01*
G01X313633Y394833D02*
X315967D01*
G01X318983Y391500D02*
Y396500D01*
G01Y394083D02*
X319400Y394500D01*
X319817Y394750D01*
X320483Y394833D01*
X320983Y394750D01*
X321567Y394417D01*
X321817Y393917D01*
Y391500D01*
G01X324750Y393750D02*
X327417D01*
X327167Y394333D01*
X326750Y394667D01*
X326167Y394833D01*
X325583Y394750D01*
X325083Y394500D01*
X324750Y393917D01*
X324583Y393417D01*
Y392917D01*
X324750Y392417D01*
X325167Y391917D01*
X325667Y391583D01*
X326250Y391500D01*
X326833Y391667D01*
X327417Y392167D01*
G01X337200Y396500D02*
Y391500D01*
G01X336033Y394833D02*
X338367D01*
G01X344300Y391500D02*
Y394833D01*
G01Y394250D02*
X343967Y394583D01*
X343467Y394750D01*
X342883Y394833D01*
X342300Y394667D01*
X341800Y394333D01*
X341467Y393833D01*
X341300Y393167D01*
X341467Y392500D01*
X341800Y392000D01*
X342300Y391667D01*
X342883Y391500D01*
X343467Y391583D01*
X343967Y391833D01*
X344300Y392167D01*
G01X346983Y391500D02*
Y394833D01*
G01Y394000D02*
X347317Y394417D01*
X347817Y394750D01*
X348483Y394833D01*
X349067Y394750D01*
X349567Y394417D01*
X349817Y393833D01*
Y391500D01*
G01X352833Y390250D02*
X353417Y389917D01*
X354083Y389833D01*
X354667Y389917D01*
X355167Y390333D01*
X355500Y390917D01*
Y394833D01*
G01Y394167D02*
X355167Y394500D01*
X354667Y394750D01*
X354083Y394833D01*
X353417Y394667D01*
X353000Y394333D01*
X352667Y393750D01*
X352500Y393167D01*
X352583Y392667D01*
X352917Y392083D01*
X353417Y391667D01*
X354083Y391500D01*
X354583Y391583D01*
X355167Y391917D01*
X355500Y392250D01*
G01X358350Y393750D02*
X361017D01*
X360767Y394333D01*
X360350Y394667D01*
X359767Y394833D01*
X359183Y394750D01*
X358683Y394500D01*
X358350Y393917D01*
X358183Y393417D01*
Y392917D01*
X358350Y392417D01*
X358767Y391917D01*
X359267Y391583D01*
X359850Y391500D01*
X360433Y391667D01*
X361017Y392167D01*
G01X363783Y391500D02*
Y394833D01*
G01Y394000D02*
X364117Y394417D01*
X364617Y394750D01*
X365283Y394833D01*
X365867Y394750D01*
X366367Y394417D01*
X366617Y393833D01*
Y391500D01*
G01X372133Y394417D02*
X371550Y394750D01*
X371050Y394833D01*
X370383Y394667D01*
X369883Y394333D01*
X369550Y393750D01*
X369467Y393167D01*
X369550Y392583D01*
X369883Y392083D01*
X370383Y391667D01*
X371050Y391500D01*
X371633Y391667D01*
X372133Y392000D01*
G01X374650Y390000D02*
X375150Y389833D01*
X375817Y390000D01*
X376233Y390333D01*
X376567Y390750D01*
X377067Y392083D01*
X378150Y394833D01*
G01X375483D02*
X377067Y392083D01*
G01X386350D02*
X386767Y391750D01*
X387350Y391500D01*
X387850D01*
X388350Y391667D01*
X388683Y391917D01*
X388850Y392250D01*
X388767Y392750D01*
X388433Y393000D01*
X386933Y393500D01*
X386600Y394083D01*
X386767Y394500D01*
X387100Y394750D01*
X387600Y394833D01*
X388100Y394750D01*
X388600Y394500D01*
G01X391783Y391500D02*
Y396500D01*
G01Y394083D02*
X392200Y394500D01*
X392617Y394750D01*
X393283Y394833D01*
X393783Y394750D01*
X394367Y394417D01*
X394617Y393917D01*
Y391500D01*
G01X398800D02*
X398300Y391583D01*
X397800Y391917D01*
X397467Y392500D01*
X397300Y393167D01*
X397467Y393833D01*
X397800Y394417D01*
X398300Y394750D01*
X398800Y394833D01*
X399300Y394750D01*
X399800Y394417D01*
X400133Y393833D01*
X400217Y393167D01*
X400133Y392500D01*
X399800Y391917D01*
X399300Y391583D01*
X398800Y391500D01*
G01X402983Y394833D02*
Y392500D01*
X403317Y391917D01*
X403817Y391583D01*
X404400Y391500D01*
X404983Y391583D01*
X405483Y391917D01*
X405817Y392500D01*
G01Y391500D02*
Y394833D01*
G01X410000Y391500D02*
Y396500D01*
G01X417100D02*
Y391500D01*
G01Y392250D02*
X416767Y391833D01*
X416267Y391583D01*
X415683Y391500D01*
X415017Y391667D01*
X414517Y392083D01*
X414183Y392583D01*
X414100Y393167D01*
X414183Y393750D01*
X414517Y394250D01*
X415017Y394667D01*
X415683Y394833D01*
X416267Y394750D01*
X416683Y394583D01*
X417100Y394250D01*
G01X425383Y391500D02*
Y394833D01*
G01Y394000D02*
X425717Y394417D01*
X426217Y394750D01*
X426883Y394833D01*
X427467Y394750D01*
X427967Y394417D01*
X428217Y393833D01*
Y391500D01*
G01X432400D02*
X431900Y391583D01*
X431400Y391917D01*
X431067Y392500D01*
X430900Y393167D01*
X431067Y393833D01*
X431400Y394417D01*
X431900Y394750D01*
X432400Y394833D01*
X432900Y394750D01*
X433400Y394417D01*
X433733Y393833D01*
X433817Y393167D01*
X433733Y392500D01*
X433400Y391917D01*
X432900Y391583D01*
X432400Y391500D01*
G01X438000Y396500D02*
Y391500D01*
G01X436833Y394833D02*
X439167D01*
G01X448033Y391500D02*
Y394833D01*
G01Y394167D02*
X448450Y394500D01*
X448867Y394750D01*
X449450Y394833D01*
X449867Y394750D01*
X450367Y394500D01*
G01X453550Y393750D02*
X456217D01*
X455967Y394333D01*
X455550Y394667D01*
X454967Y394833D01*
X454383Y394750D01*
X453883Y394500D01*
X453550Y393917D01*
X453383Y393417D01*
Y392917D01*
X453550Y392417D01*
X453967Y391917D01*
X454467Y391583D01*
X455050Y391500D01*
X455633Y391667D01*
X456217Y392167D01*
G01X461900Y396500D02*
Y391500D01*
G01Y392250D02*
X461567Y391833D01*
X461067Y391583D01*
X460483Y391500D01*
X459817Y391667D01*
X459317Y392083D01*
X458983Y392583D01*
X458900Y393167D01*
X458983Y393750D01*
X459317Y394250D01*
X459817Y394667D01*
X460483Y394833D01*
X461067Y394750D01*
X461483Y394583D01*
X461900Y394250D01*
G01X464583Y394833D02*
Y392500D01*
X464917Y391917D01*
X465417Y391583D01*
X466000Y391500D01*
X466583Y391583D01*
X467083Y391917D01*
X467417Y392500D01*
G01Y391500D02*
Y394833D01*
G01X472933Y394417D02*
X472350Y394750D01*
X471850Y394833D01*
X471183Y394667D01*
X470683Y394333D01*
X470350Y393750D01*
X470267Y393167D01*
X470350Y392583D01*
X470683Y392083D01*
X471183Y391667D01*
X471850Y391500D01*
X472433Y391667D01*
X472933Y392000D01*
G01X475950Y393750D02*
X478617D01*
X478367Y394333D01*
X477950Y394667D01*
X477367Y394833D01*
X476783Y394750D01*
X476283Y394500D01*
X475950Y393917D01*
X475783Y393417D01*
Y392917D01*
X475950Y392417D01*
X476367Y391917D01*
X476867Y391583D01*
X477450Y391500D01*
X478033Y391667D01*
X478617Y392167D01*
G01X488400Y396500D02*
Y391500D01*
G01X487233Y394833D02*
X489567D01*
G01X492583Y391500D02*
Y396500D01*
G01Y394083D02*
X493000Y394500D01*
X493417Y394750D01*
X494083Y394833D01*
X494583Y394750D01*
X495167Y394417D01*
X495417Y393917D01*
Y391500D01*
G01X498350Y393750D02*
X501017D01*
X500767Y394333D01*
X500350Y394667D01*
X499767Y394833D01*
X499183Y394750D01*
X498683Y394500D01*
X498350Y393917D01*
X498183Y393417D01*
Y392917D01*
X498350Y392417D01*
X498767Y391917D01*
X499267Y391583D01*
X499850Y391500D01*
X500433Y391667D01*
X501017Y392167D01*
G01X510800Y391500D02*
Y396500D01*
G01X517900Y391500D02*
Y394833D01*
G01Y394250D02*
X517567Y394583D01*
X517067Y394750D01*
X516483Y394833D01*
X515900Y394667D01*
X515400Y394333D01*
X515067Y393833D01*
X514900Y393167D01*
X515067Y392500D01*
X515400Y392000D01*
X515900Y391667D01*
X516483Y391500D01*
X517067Y391583D01*
X517567Y391833D01*
X517900Y392167D01*
G01X520583Y391500D02*
Y394833D01*
G01Y394000D02*
X520917Y394417D01*
X521417Y394750D01*
X522083Y394833D01*
X522667Y394750D01*
X523167Y394417D01*
X523417Y393833D01*
Y391500D01*
G01X529100Y396500D02*
Y391500D01*
G01Y392250D02*
X528767Y391833D01*
X528267Y391583D01*
X527683Y391500D01*
X527017Y391667D01*
X526517Y392083D01*
X526183Y392583D01*
X526100Y393167D01*
X526183Y393750D01*
X526517Y394250D01*
X527017Y394667D01*
X527683Y394833D01*
X528267Y394750D01*
X528683Y394583D01*
X529100Y394250D01*
G01X531700Y391333D02*
X534700Y396500D01*
G01X540133Y394417D02*
X539550Y394750D01*
X539050Y394833D01*
X538383Y394667D01*
X537883Y394333D01*
X537550Y393750D01*
X537467Y393167D01*
X537550Y392583D01*
X537883Y392083D01*
X538383Y391667D01*
X539050Y391500D01*
X539633Y391667D01*
X540133Y392000D01*
G01X544400Y391500D02*
X543900Y391583D01*
X543400Y391917D01*
X543067Y392500D01*
X542900Y393167D01*
X543067Y393833D01*
X543400Y394417D01*
X543900Y394750D01*
X544400Y394833D01*
X544900Y394750D01*
X545400Y394417D01*
X545733Y393833D01*
X545817Y393167D01*
X545733Y392500D01*
X545400Y391917D01*
X544900Y391583D01*
X544400Y391500D01*
G01X548583D02*
Y394833D01*
G01Y394000D02*
X548917Y394417D01*
X549417Y394750D01*
X550083Y394833D01*
X550667Y394750D01*
X551167Y394417D01*
X551417Y393833D01*
Y391500D01*
G01X557100Y396500D02*
Y391500D01*
G01Y392250D02*
X556767Y391833D01*
X556267Y391583D01*
X555683Y391500D01*
X555017Y391667D01*
X554517Y392083D01*
X554183Y392583D01*
X554100Y393167D01*
X554183Y393750D01*
X554517Y394250D01*
X555017Y394667D01*
X555683Y394833D01*
X556267Y394750D01*
X556683Y394583D01*
X557100Y394250D01*
G01X559783Y394833D02*
Y392500D01*
X560117Y391917D01*
X560617Y391583D01*
X561200Y391500D01*
X561783Y391583D01*
X562283Y391917D01*
X562617Y392500D01*
G01Y391500D02*
Y394833D01*
G01X568133Y394417D02*
X567550Y394750D01*
X567050Y394833D01*
X566383Y394667D01*
X565883Y394333D01*
X565550Y393750D01*
X565467Y393167D01*
X565550Y392583D01*
X565883Y392083D01*
X566383Y391667D01*
X567050Y391500D01*
X567633Y391667D01*
X568133Y392000D01*
G01X572400Y396500D02*
Y391500D01*
G01X571233Y394833D02*
X573567D01*
G01X578000Y391500D02*
X577500Y391583D01*
X577000Y391917D01*
X576667Y392500D01*
X576500Y393167D01*
X576667Y393833D01*
X577000Y394417D01*
X577500Y394750D01*
X578000Y394833D01*
X578500Y394750D01*
X579000Y394417D01*
X579333Y393833D01*
X579417Y393167D01*
X579333Y392500D01*
X579000Y391917D01*
X578500Y391583D01*
X578000Y391500D01*
G01X582433D02*
Y394833D01*
G01Y394167D02*
X582850Y394500D01*
X583267Y394750D01*
X583850Y394833D01*
X584267Y394750D01*
X584767Y394500D01*
G01X271500Y402000D02*
Y405333D01*
G01Y404750D02*
X271167Y405083D01*
X270667Y405250D01*
X270083Y405333D01*
X269500Y405167D01*
X269000Y404833D01*
X268667Y404333D01*
X268500Y403667D01*
X268667Y403000D01*
X269000Y402500D01*
X269500Y402167D01*
X270083Y402000D01*
X270667Y402083D01*
X271167Y402333D01*
X271500Y402667D01*
G01X276933Y404917D02*
X276350Y405250D01*
X275850Y405333D01*
X275183Y405167D01*
X274683Y404833D01*
X274350Y404250D01*
X274267Y403667D01*
X274350Y403083D01*
X274683Y402583D01*
X275183Y402167D01*
X275850Y402000D01*
X276433Y402167D01*
X276933Y402500D01*
G01X282533Y404917D02*
X281950Y405250D01*
X281450Y405333D01*
X280783Y405167D01*
X280283Y404833D01*
X279950Y404250D01*
X279867Y403667D01*
X279950Y403083D01*
X280283Y402583D01*
X280783Y402167D01*
X281450Y402000D01*
X282033Y402167D01*
X282533Y402500D01*
G01X285550Y404250D02*
X288217D01*
X287967Y404833D01*
X287550Y405167D01*
X286967Y405333D01*
X286383Y405250D01*
X285883Y405000D01*
X285550Y404417D01*
X285383Y403917D01*
Y403417D01*
X285550Y402917D01*
X285967Y402417D01*
X286467Y402083D01*
X287050Y402000D01*
X287633Y402167D01*
X288217Y402667D01*
G01X290900Y400333D02*
Y405333D01*
G01Y404583D02*
X291317Y405000D01*
X291733Y405250D01*
X292400Y405333D01*
X292983Y405250D01*
X293567Y404833D01*
X293817Y404250D01*
X293900Y403667D01*
X293817Y403083D01*
X293567Y402500D01*
X293067Y402167D01*
X292400Y402000D01*
X291817Y402083D01*
X291233Y402333D01*
X290900Y402667D01*
G01X298000Y407000D02*
Y402000D01*
G01X296833Y405333D02*
X299167D01*
G01X305100Y402000D02*
Y405333D01*
G01Y404750D02*
X304767Y405083D01*
X304267Y405250D01*
X303683Y405333D01*
X303100Y405167D01*
X302600Y404833D01*
X302267Y404333D01*
X302100Y403667D01*
X302267Y403000D01*
X302600Y402500D01*
X303100Y402167D01*
X303683Y402000D01*
X304267Y402083D01*
X304767Y402333D01*
X305100Y402667D01*
G01X307700Y402000D02*
Y407000D01*
G01Y404500D02*
X308117Y405000D01*
X308617Y405250D01*
X309117Y405333D01*
X309867Y405167D01*
X310367Y404833D01*
X310700Y404250D01*
Y403583D01*
X310533Y402917D01*
X310200Y402417D01*
X309617Y402083D01*
X309117Y402000D01*
X308617Y402083D01*
X308117Y402333D01*
X307700Y402750D01*
G01X314800Y402000D02*
Y407000D01*
G01X319150Y404250D02*
X321817D01*
X321567Y404833D01*
X321150Y405167D01*
X320567Y405333D01*
X319983Y405250D01*
X319483Y405000D01*
X319150Y404417D01*
X318983Y403917D01*
Y403417D01*
X319150Y402917D01*
X319567Y402417D01*
X320067Y402083D01*
X320650Y402000D01*
X321233Y402167D01*
X321817Y402667D01*
G01X326000Y401833D02*
X325833Y401917D01*
Y402083D01*
X326000Y402167D01*
X326167Y402083D01*
Y401917D01*
X326000Y401833D01*
G01X270000Y417500D02*
Y412500D01*
G01X268083Y417500D02*
X271917D01*
G01X274183Y412500D02*
Y417500D01*
G01Y415083D02*
X274600Y415500D01*
X275017Y415750D01*
X275683Y415833D01*
X276183Y415750D01*
X276767Y415417D01*
X277017Y414917D01*
Y412500D01*
G01X279950Y414750D02*
X282617D01*
X282367Y415333D01*
X281950Y415667D01*
X281367Y415833D01*
X280783Y415750D01*
X280283Y415500D01*
X279950Y414917D01*
X279783Y414417D01*
Y413917D01*
X279950Y413417D01*
X280367Y412917D01*
X280867Y412583D01*
X281450Y412500D01*
X282033Y412667D01*
X282617Y413167D01*
G01X290900Y412500D02*
Y417500D01*
G01Y415000D02*
X291317Y415500D01*
X291817Y415750D01*
X292317Y415833D01*
X293067Y415667D01*
X293567Y415333D01*
X293900Y414750D01*
Y414083D01*
X293733Y413417D01*
X293400Y412917D01*
X292817Y412583D01*
X292317Y412500D01*
X291817Y412583D01*
X291317Y412833D01*
X290900Y413250D01*
G01X296833Y412500D02*
Y415833D01*
G01Y415167D02*
X297250Y415500D01*
X297667Y415750D01*
X298250Y415833D01*
X298667Y415750D01*
X299167Y415500D01*
G01X302350Y414750D02*
X305017D01*
X304767Y415333D01*
X304350Y415667D01*
X303767Y415833D01*
X303183Y415750D01*
X302683Y415500D01*
X302350Y414917D01*
X302183Y414417D01*
Y413917D01*
X302350Y413417D01*
X302767Y412917D01*
X303267Y412583D01*
X303850Y412500D01*
X304433Y412667D01*
X305017Y413167D01*
G01X310700Y412500D02*
Y415833D01*
G01Y415250D02*
X310367Y415583D01*
X309867Y415750D01*
X309283Y415833D01*
X308700Y415667D01*
X308200Y415333D01*
X307867Y414833D01*
X307700Y414167D01*
X307867Y413500D01*
X308200Y413000D01*
X308700Y412667D01*
X309283Y412500D01*
X309867Y412583D01*
X310367Y412833D01*
X310700Y413167D01*
G01X313383Y412500D02*
Y417500D01*
G01X316050Y415833D02*
X313383Y413917D01*
G01X314467Y414667D02*
X316217Y412500D01*
G01X320400D02*
X319900Y412583D01*
X319400Y412917D01*
X319067Y413500D01*
X318900Y414167D01*
X319067Y414833D01*
X319400Y415417D01*
X319900Y415750D01*
X320400Y415833D01*
X320900Y415750D01*
X321400Y415417D01*
X321733Y414833D01*
X321817Y414167D01*
X321733Y413500D01*
X321400Y412917D01*
X320900Y412583D01*
X320400Y412500D01*
G01X324583Y415833D02*
Y413500D01*
X324917Y412917D01*
X325417Y412583D01*
X326000Y412500D01*
X326583Y412583D01*
X327083Y412917D01*
X327417Y413500D01*
G01Y412500D02*
Y415833D01*
G01X331600Y417500D02*
Y412500D01*
G01X330433Y415833D02*
X332767D01*
G01X342800D02*
Y412500D01*
G01Y417167D02*
X342633Y417250D01*
Y417417D01*
X342800Y417500D01*
X342967Y417417D01*
Y417250D01*
X342800Y417167D01*
G01X347150Y413083D02*
X347567Y412750D01*
X348150Y412500D01*
X348650D01*
X349150Y412667D01*
X349483Y412917D01*
X349650Y413250D01*
X349567Y413750D01*
X349233Y414000D01*
X347733Y414500D01*
X347400Y415083D01*
X347567Y415500D01*
X347900Y415750D01*
X348400Y415833D01*
X348900Y415750D01*
X349400Y415500D01*
G01X358183Y412500D02*
Y415833D01*
G01Y415000D02*
X358517Y415417D01*
X359017Y415750D01*
X359683Y415833D01*
X360267Y415750D01*
X360767Y415417D01*
X361017Y414833D01*
Y412500D01*
G01X365200D02*
X364700Y412583D01*
X364200Y412917D01*
X363867Y413500D01*
X363700Y414167D01*
X363867Y414833D01*
X364200Y415417D01*
X364700Y415750D01*
X365200Y415833D01*
X365700Y415750D01*
X366200Y415417D01*
X366533Y414833D01*
X366617Y414167D01*
X366533Y413500D01*
X366200Y412917D01*
X365700Y412583D01*
X365200Y412500D01*
G01X370800Y417500D02*
Y412500D01*
G01X369633Y415833D02*
X371967D01*
G01X383500Y412500D02*
Y415833D01*
G01Y415250D02*
X383167Y415583D01*
X382667Y415750D01*
X382083Y415833D01*
X381500Y415667D01*
X381000Y415333D01*
X380667Y414833D01*
X380500Y414167D01*
X380667Y413500D01*
X381000Y413000D01*
X381500Y412667D01*
X382083Y412500D01*
X382667Y412583D01*
X383167Y412833D01*
X383500Y413167D01*
G01X387600Y412500D02*
Y417500D01*
G01X393200Y412500D02*
Y417500D01*
G01X398800Y412500D02*
X398300Y412583D01*
X397800Y412917D01*
X397467Y413500D01*
X397300Y414167D01*
X397467Y414833D01*
X397800Y415417D01*
X398300Y415750D01*
X398800Y415833D01*
X399300Y415750D01*
X399800Y415417D01*
X400133Y414833D01*
X400217Y414167D01*
X400133Y413500D01*
X399800Y412917D01*
X399300Y412583D01*
X398800Y412500D01*
G01X402317Y415833D02*
X403317Y412500D01*
X404400Y415833D01*
X405483Y412500D01*
X406483Y415833D01*
G01X408750Y414750D02*
X411417D01*
X411167Y415333D01*
X410750Y415667D01*
X410167Y415833D01*
X409583Y415750D01*
X409083Y415500D01*
X408750Y414917D01*
X408583Y414417D01*
Y413917D01*
X408750Y413417D01*
X409167Y412917D01*
X409667Y412583D01*
X410250Y412500D01*
X410833Y412667D01*
X411417Y413167D01*
G01X417100Y417500D02*
Y412500D01*
G01Y413250D02*
X416767Y412833D01*
X416267Y412583D01*
X415683Y412500D01*
X415017Y412667D01*
X414517Y413083D01*
X414183Y413583D01*
X414100Y414167D01*
X414183Y414750D01*
X414517Y415250D01*
X415017Y415667D01*
X415683Y415833D01*
X416267Y415750D01*
X416683Y415583D01*
X417100Y415250D01*
G01X421033Y411583D02*
X421367Y412667D01*
G01X436500Y412500D02*
Y417500D01*
G01Y415000D02*
X436917Y415500D01*
X437417Y415750D01*
X437917Y415833D01*
X438667Y415667D01*
X439167Y415333D01*
X439500Y414750D01*
Y414083D01*
X439333Y413417D01*
X439000Y412917D01*
X438417Y412583D01*
X437917Y412500D01*
X437417Y412583D01*
X436917Y412833D01*
X436500Y413250D01*
G01X442183Y415833D02*
Y413500D01*
X442517Y412917D01*
X443017Y412583D01*
X443600Y412500D01*
X444183Y412583D01*
X444683Y412917D01*
X445017Y413500D01*
G01Y412500D02*
Y415833D01*
G01X449200Y417500D02*
Y412500D01*
G01X448033Y415833D02*
X450367D01*
G01X461900Y412500D02*
Y415833D01*
G01Y415250D02*
X461567Y415583D01*
X461067Y415750D01*
X460483Y415833D01*
X459900Y415667D01*
X459400Y415333D01*
X459067Y414833D01*
X458900Y414167D01*
X459067Y413500D01*
X459400Y413000D01*
X459900Y412667D01*
X460483Y412500D01*
X461067Y412583D01*
X461567Y412833D01*
X461900Y413167D01*
G01X464583Y412500D02*
Y415833D01*
G01Y415000D02*
X464917Y415417D01*
X465417Y415750D01*
X466083Y415833D01*
X466667Y415750D01*
X467167Y415417D01*
X467417Y414833D01*
Y412500D01*
G01X470183D02*
Y415833D01*
G01Y415000D02*
X470517Y415417D01*
X471017Y415750D01*
X471683Y415833D01*
X472267Y415750D01*
X472767Y415417D01*
X473017Y414833D01*
Y412500D01*
G01X475783Y415833D02*
Y413500D01*
X476117Y412917D01*
X476617Y412583D01*
X477200Y412500D01*
X477783Y412583D01*
X478283Y412917D01*
X478617Y413500D01*
G01Y412500D02*
Y415833D01*
G01X484300Y412500D02*
Y415833D01*
G01Y415250D02*
X483967Y415583D01*
X483467Y415750D01*
X482883Y415833D01*
X482300Y415667D01*
X481800Y415333D01*
X481467Y414833D01*
X481300Y414167D01*
X481467Y413500D01*
X481800Y413000D01*
X482300Y412667D01*
X482883Y412500D01*
X483467Y412583D01*
X483967Y412833D01*
X484300Y413167D01*
G01X488400Y412500D02*
Y417500D01*
G01X498433Y412500D02*
Y415833D01*
G01Y415167D02*
X498850Y415500D01*
X499267Y415750D01*
X499850Y415833D01*
X500267Y415750D01*
X500767Y415500D01*
G01X505200Y415833D02*
Y412500D01*
G01Y417167D02*
X505033Y417250D01*
Y417417D01*
X505200Y417500D01*
X505367Y417417D01*
Y417250D01*
X505200Y417167D01*
G01X509383Y412500D02*
Y415833D01*
G01Y415000D02*
X509717Y415417D01*
X510217Y415750D01*
X510883Y415833D01*
X511467Y415750D01*
X511967Y415417D01*
X512217Y414833D01*
Y412500D01*
G01X515233Y411250D02*
X515817Y410917D01*
X516483Y410833D01*
X517067Y410917D01*
X517567Y411333D01*
X517900Y411917D01*
Y415833D01*
G01Y415167D02*
X517567Y415500D01*
X517067Y415750D01*
X516483Y415833D01*
X515817Y415667D01*
X515400Y415333D01*
X515067Y414750D01*
X514900Y414167D01*
X514983Y413667D01*
X515317Y413083D01*
X515817Y412667D01*
X516483Y412500D01*
X516983Y412583D01*
X517567Y412917D01*
X517900Y413250D01*
G01X527600Y417500D02*
Y412500D01*
G01X526433Y415833D02*
X528767D01*
G01X534700Y412500D02*
Y415833D01*
G01Y415250D02*
X534367Y415583D01*
X533867Y415750D01*
X533283Y415833D01*
X532700Y415667D01*
X532200Y415333D01*
X531867Y414833D01*
X531700Y414167D01*
X531867Y413500D01*
X532200Y413000D01*
X532700Y412667D01*
X533283Y412500D01*
X533867Y412583D01*
X534367Y412833D01*
X534700Y413167D01*
G01X537383Y412500D02*
Y415833D01*
G01Y415000D02*
X537717Y415417D01*
X538217Y415750D01*
X538883Y415833D01*
X539467Y415750D01*
X539967Y415417D01*
X540217Y414833D01*
Y412500D01*
G01X543233Y411250D02*
X543817Y410917D01*
X544483Y410833D01*
X545067Y410917D01*
X545567Y411333D01*
X545900Y411917D01*
Y415833D01*
G01Y415167D02*
X545567Y415500D01*
X545067Y415750D01*
X544483Y415833D01*
X543817Y415667D01*
X543400Y415333D01*
X543067Y414750D01*
X542900Y414167D01*
X542983Y413667D01*
X543317Y413083D01*
X543817Y412667D01*
X544483Y412500D01*
X544983Y412583D01*
X545567Y412917D01*
X545900Y413250D01*
G01X548750Y414750D02*
X551417D01*
X551167Y415333D01*
X550750Y415667D01*
X550167Y415833D01*
X549583Y415750D01*
X549083Y415500D01*
X548750Y414917D01*
X548583Y414417D01*
Y413917D01*
X548750Y413417D01*
X549167Y412917D01*
X549667Y412583D01*
X550250Y412500D01*
X550833Y412667D01*
X551417Y413167D01*
G01X554183Y412500D02*
Y415833D01*
G01Y415000D02*
X554517Y415417D01*
X555017Y415750D01*
X555683Y415833D01*
X556267Y415750D01*
X556767Y415417D01*
X557017Y414833D01*
Y412500D01*
G01X562533Y415417D02*
X561950Y415750D01*
X561450Y415833D01*
X560783Y415667D01*
X560283Y415333D01*
X559950Y414750D01*
X559867Y414167D01*
X559950Y413583D01*
X560283Y413083D01*
X560783Y412667D01*
X561450Y412500D01*
X562033Y412667D01*
X562533Y413000D01*
G01X565050Y411000D02*
X565550Y410833D01*
X566217Y411000D01*
X566633Y411333D01*
X566967Y411750D01*
X567467Y413083D01*
X568550Y415833D01*
G01X565883D02*
X567467Y413083D01*
G01X578000Y415833D02*
Y412500D01*
G01Y417167D02*
X577833Y417250D01*
Y417417D01*
X578000Y417500D01*
X578167Y417417D01*
Y417250D01*
X578000Y417167D01*
G01X582350Y413083D02*
X582767Y412750D01*
X583350Y412500D01*
X583850D01*
X584350Y412667D01*
X584683Y412917D01*
X584850Y413250D01*
X584767Y413750D01*
X584433Y414000D01*
X582933Y414500D01*
X582600Y415083D01*
X582767Y415500D01*
X583100Y415750D01*
X583600Y415833D01*
X584100Y415750D01*
X584600Y415500D01*
G01X262500Y397000D02*
Y679000D01*
G01X273000Y437500D02*
Y432500D01*
G01Y433250D02*
X272667Y432833D01*
X272167Y432583D01*
X271583Y432500D01*
X270917Y432667D01*
X270417Y433083D01*
X270083Y433583D01*
X270000Y434167D01*
X270083Y434750D01*
X270417Y435250D01*
X270917Y435667D01*
X271583Y435833D01*
X272167Y435750D01*
X272583Y435583D01*
X273000Y435250D01*
G01X275850Y434750D02*
X278517D01*
X278267Y435333D01*
X277850Y435667D01*
X277267Y435833D01*
X276683Y435750D01*
X276183Y435500D01*
X275850Y434917D01*
X275683Y434417D01*
Y433917D01*
X275850Y433417D01*
X276267Y432917D01*
X276767Y432583D01*
X277350Y432500D01*
X277933Y432667D01*
X278517Y433167D01*
G01X281200Y430833D02*
Y435833D01*
G01Y435083D02*
X281617Y435500D01*
X282033Y435750D01*
X282700Y435833D01*
X283283Y435750D01*
X283867Y435333D01*
X284117Y434750D01*
X284200Y434167D01*
X284117Y433583D01*
X283867Y433000D01*
X283367Y432667D01*
X282700Y432500D01*
X282117Y432583D01*
X281533Y432833D01*
X281200Y433167D01*
G01X288300Y437500D02*
Y432500D01*
G01X287133Y435833D02*
X289467D01*
G01X292483Y432500D02*
Y437500D01*
G01Y435083D02*
X292900Y435500D01*
X293317Y435750D01*
X293983Y435833D01*
X294483Y435750D01*
X295067Y435417D01*
X295317Y434917D01*
Y432500D01*
G01X305100Y437500D02*
Y432500D01*
G01X303933Y435833D02*
X306267D01*
G01X310700Y432500D02*
X310200Y432583D01*
X309700Y432917D01*
X309367Y433500D01*
X309200Y434167D01*
X309367Y434833D01*
X309700Y435417D01*
X310200Y435750D01*
X310700Y435833D01*
X311200Y435750D01*
X311700Y435417D01*
X312033Y434833D01*
X312117Y434167D01*
X312033Y433500D01*
X311700Y432917D01*
X311200Y432583D01*
X310700Y432500D01*
G01X316300D02*
Y437500D01*
G01X320650Y434750D02*
X323317D01*
X323067Y435333D01*
X322650Y435667D01*
X322067Y435833D01*
X321483Y435750D01*
X320983Y435500D01*
X320650Y434917D01*
X320483Y434417D01*
Y433917D01*
X320650Y433417D01*
X321067Y432917D01*
X321567Y432583D01*
X322150Y432500D01*
X322733Y432667D01*
X323317Y433167D01*
G01X326333Y432500D02*
Y435833D01*
G01Y435167D02*
X326750Y435500D01*
X327167Y435750D01*
X327750Y435833D01*
X328167Y435750D01*
X328667Y435500D01*
G01X334600Y432500D02*
Y435833D01*
G01Y435250D02*
X334267Y435583D01*
X333767Y435750D01*
X333183Y435833D01*
X332600Y435667D01*
X332100Y435333D01*
X331767Y434833D01*
X331600Y434167D01*
X331767Y433500D01*
X332100Y433000D01*
X332600Y432667D01*
X333183Y432500D01*
X333767Y432583D01*
X334267Y432833D01*
X334600Y433167D01*
G01X337283Y432500D02*
Y435833D01*
G01Y435000D02*
X337617Y435417D01*
X338117Y435750D01*
X338783Y435833D01*
X339367Y435750D01*
X339867Y435417D01*
X340117Y434833D01*
Y432500D01*
G01X345633Y435417D02*
X345050Y435750D01*
X344550Y435833D01*
X343883Y435667D01*
X343383Y435333D01*
X343050Y434750D01*
X342967Y434167D01*
X343050Y433583D01*
X343383Y433083D01*
X343883Y432667D01*
X344550Y432500D01*
X345133Y432667D01*
X345633Y433000D01*
G01X348650Y434750D02*
X351317D01*
X351067Y435333D01*
X350650Y435667D01*
X350067Y435833D01*
X349483Y435750D01*
X348983Y435500D01*
X348650Y434917D01*
X348483Y434417D01*
Y433917D01*
X348650Y433417D01*
X349067Y432917D01*
X349567Y432583D01*
X350150Y432500D01*
X350733Y432667D01*
X351317Y433167D01*
G01X270750Y453500D02*
Y458500D01*
G01X274250D02*
Y453500D01*
G01Y456000D02*
X270750D01*
G01X278100Y453500D02*
X277600Y453583D01*
X277100Y453917D01*
X276767Y454500D01*
X276600Y455167D01*
X276767Y455833D01*
X277100Y456417D01*
X277600Y456750D01*
X278100Y456833D01*
X278600Y456750D01*
X279100Y456417D01*
X279433Y455833D01*
X279517Y455167D01*
X279433Y454500D01*
X279100Y453917D01*
X278600Y453583D01*
X278100Y453500D01*
G01X283700D02*
Y458500D01*
G01X288050Y455750D02*
X290717D01*
X290467Y456333D01*
X290050Y456667D01*
X289467Y456833D01*
X288883Y456750D01*
X288383Y456500D01*
X288050Y455917D01*
X287883Y455417D01*
Y454917D01*
X288050Y454417D01*
X288467Y453917D01*
X288967Y453583D01*
X289550Y453500D01*
X290133Y453667D01*
X290717Y454167D01*
G01X298000Y458500D02*
X299167Y453500D01*
X300500Y458500D01*
X301833Y453500D01*
X303000Y458500D01*
G01X307600Y453500D02*
Y456833D01*
G01Y456250D02*
X307267Y456583D01*
X306767Y456750D01*
X306183Y456833D01*
X305600Y456667D01*
X305100Y456333D01*
X304767Y455833D01*
X304600Y455167D01*
X304767Y454500D01*
X305100Y454000D01*
X305600Y453667D01*
X306183Y453500D01*
X306767Y453583D01*
X307267Y453833D01*
X307600Y454167D01*
G01X311700Y453500D02*
Y458500D01*
G01X317300Y453500D02*
Y458500D01*
G01X326833Y453500D02*
Y458500D01*
X328917D01*
X329583Y458250D01*
X330000Y457917D01*
X330167Y457250D01*
X330000Y456583D01*
X329500Y456167D01*
X328917Y455917D01*
X326833D01*
G01X328917D02*
X330167Y453500D01*
G01X334100D02*
X333600Y453583D01*
X333100Y453917D01*
X332767Y454500D01*
X332600Y455167D01*
X332767Y455833D01*
X333100Y456417D01*
X333600Y456750D01*
X334100Y456833D01*
X334600Y456750D01*
X335100Y456417D01*
X335433Y455833D01*
X335517Y455167D01*
X335433Y454500D01*
X335100Y453917D01*
X334600Y453583D01*
X334100Y453500D01*
G01X338283Y456833D02*
Y454500D01*
X338617Y453917D01*
X339117Y453583D01*
X339700Y453500D01*
X340283Y453583D01*
X340783Y453917D01*
X341117Y454500D01*
G01Y453500D02*
Y456833D01*
G01X344133Y452250D02*
X344717Y451917D01*
X345383Y451833D01*
X345967Y451917D01*
X346467Y452333D01*
X346800Y452917D01*
Y456833D01*
G01Y456167D02*
X346467Y456500D01*
X345967Y456750D01*
X345383Y456833D01*
X344717Y456667D01*
X344300Y456333D01*
X343967Y455750D01*
X343800Y455167D01*
X343883Y454667D01*
X344217Y454083D01*
X344717Y453667D01*
X345383Y453500D01*
X345883Y453583D01*
X346467Y453917D01*
X346800Y454250D01*
G01X349483Y453500D02*
Y458500D01*
G01Y456083D02*
X349900Y456500D01*
X350317Y456750D01*
X350983Y456833D01*
X351483Y456750D01*
X352067Y456417D01*
X352317Y455917D01*
Y453500D01*
G01X355083D02*
Y456833D01*
G01Y456000D02*
X355417Y456417D01*
X355917Y456750D01*
X356583Y456833D01*
X357167Y456750D01*
X357667Y456417D01*
X357917Y455833D01*
Y453500D01*
G01X360850Y455750D02*
X363517D01*
X363267Y456333D01*
X362850Y456667D01*
X362267Y456833D01*
X361683Y456750D01*
X361183Y456500D01*
X360850Y455917D01*
X360683Y455417D01*
Y454917D01*
X360850Y454417D01*
X361267Y453917D01*
X361767Y453583D01*
X362350Y453500D01*
X362933Y453667D01*
X363517Y454167D01*
G01X366450Y454083D02*
X366867Y453750D01*
X367450Y453500D01*
X367950D01*
X368450Y453667D01*
X368783Y453917D01*
X368950Y454250D01*
X368867Y454750D01*
X368533Y455000D01*
X367033Y455500D01*
X366700Y456083D01*
X366867Y456500D01*
X367200Y456750D01*
X367700Y456833D01*
X368200Y456750D01*
X368700Y456500D01*
G01X372050Y454083D02*
X372467Y453750D01*
X373050Y453500D01*
X373550D01*
X374050Y453667D01*
X374383Y453917D01*
X374550Y454250D01*
X374467Y454750D01*
X374133Y455000D01*
X372633Y455500D01*
X372300Y456083D01*
X372467Y456500D01*
X372800Y456750D01*
X373300Y456833D01*
X373800Y456750D01*
X374300Y456500D01*
G01X272500Y470000D02*
X271833Y470083D01*
X271250Y470417D01*
X270750Y470917D01*
X270417Y471500D01*
X270250Y472167D01*
Y472833D01*
X270417Y473500D01*
X270750Y474083D01*
X271250Y474583D01*
X271833Y474917D01*
X272500Y475000D01*
X273167Y474917D01*
X273750Y474583D01*
X274250Y474083D01*
X274583Y473500D01*
X274750Y472833D01*
Y472167D01*
X274583Y471500D01*
X274250Y470917D01*
X273750Y470417D01*
X273167Y470083D01*
X272500Y470000D01*
G01X278100Y475000D02*
Y470000D01*
G01X276933Y473333D02*
X279267D01*
G01X282283Y470000D02*
Y475000D01*
G01Y472583D02*
X282700Y473000D01*
X283117Y473250D01*
X283783Y473333D01*
X284283Y473250D01*
X284867Y472917D01*
X285117Y472417D01*
Y470000D01*
G01X288050Y472250D02*
X290717D01*
X290467Y472833D01*
X290050Y473167D01*
X289467Y473333D01*
X288883Y473250D01*
X288383Y473000D01*
X288050Y472417D01*
X287883Y471917D01*
Y471417D01*
X288050Y470917D01*
X288467Y470417D01*
X288967Y470083D01*
X289550Y470000D01*
X290133Y470167D01*
X290717Y470667D01*
G01X293733Y470000D02*
Y473333D01*
G01Y472667D02*
X294150Y473000D01*
X294567Y473250D01*
X295150Y473333D01*
X295567Y473250D01*
X296067Y473000D01*
G01X299250Y470583D02*
X299667Y470250D01*
X300250Y470000D01*
X300750D01*
X301250Y470167D01*
X301583Y470417D01*
X301750Y470750D01*
X301667Y471250D01*
X301333Y471500D01*
X299833Y472000D01*
X299500Y472583D01*
X299667Y473000D01*
X300000Y473250D01*
X300500Y473333D01*
X301000Y473250D01*
X301500Y473000D01*
G01X311283Y468333D02*
X310450Y469167D01*
X310033Y470000D01*
Y473333D01*
X310450Y474167D01*
X311283Y475000D01*
G01X317300Y470000D02*
Y475000D01*
G01X322900Y473333D02*
Y470000D01*
G01Y474667D02*
X322733Y474750D01*
Y474917D01*
X322900Y475000D01*
X323067Y474917D01*
Y474750D01*
X322900Y474667D01*
G01X327083Y470000D02*
Y475000D01*
G01X329750Y473333D02*
X327083Y471417D01*
G01X328167Y472167D02*
X329917Y470000D01*
G01X332850Y472250D02*
X335517D01*
X335267Y472833D01*
X334850Y473167D01*
X334267Y473333D01*
X333683Y473250D01*
X333183Y473000D01*
X332850Y472417D01*
X332683Y471917D01*
Y471417D01*
X332850Y470917D01*
X333267Y470417D01*
X333767Y470083D01*
X334350Y470000D01*
X334933Y470167D01*
X335517Y470667D01*
G01X344050Y472250D02*
X346717D01*
X346467Y472833D01*
X346050Y473167D01*
X345467Y473333D01*
X344883Y473250D01*
X344383Y473000D01*
X344050Y472417D01*
X343883Y471917D01*
Y471417D01*
X344050Y470917D01*
X344467Y470417D01*
X344967Y470083D01*
X345550Y470000D01*
X346133Y470167D01*
X346717Y470667D01*
G01X350900Y470000D02*
Y475000D01*
G01X356500Y470000D02*
Y475000D01*
G01X362100Y473333D02*
Y470000D01*
G01Y474667D02*
X361933Y474750D01*
Y474917D01*
X362100Y475000D01*
X362267Y474917D01*
Y474750D01*
X362100Y474667D01*
G01X366200Y468333D02*
Y473333D01*
G01Y472583D02*
X366617Y473000D01*
X367033Y473250D01*
X367700Y473333D01*
X368283Y473250D01*
X368867Y472833D01*
X369117Y472250D01*
X369200Y471667D01*
X369117Y471083D01*
X368867Y470500D01*
X368367Y470167D01*
X367700Y470000D01*
X367117Y470083D01*
X366533Y470333D01*
X366200Y470667D01*
G01X372050Y470583D02*
X372467Y470250D01*
X373050Y470000D01*
X373550D01*
X374050Y470167D01*
X374383Y470417D01*
X374550Y470750D01*
X374467Y471250D01*
X374133Y471500D01*
X372633Y472000D01*
X372300Y472583D01*
X372467Y473000D01*
X372800Y473250D01*
X373300Y473333D01*
X373800Y473250D01*
X374300Y473000D01*
G01X377650Y472250D02*
X380317D01*
X380067Y472833D01*
X379650Y473167D01*
X379067Y473333D01*
X378483Y473250D01*
X377983Y473000D01*
X377650Y472417D01*
X377483Y471917D01*
Y471417D01*
X377650Y470917D01*
X378067Y470417D01*
X378567Y470083D01*
X379150Y470000D01*
X379733Y470167D01*
X380317Y470667D01*
G01X391600Y470000D02*
Y473333D01*
G01Y472750D02*
X391267Y473083D01*
X390767Y473250D01*
X390183Y473333D01*
X389600Y473167D01*
X389100Y472833D01*
X388767Y472333D01*
X388600Y471667D01*
X388767Y471000D01*
X389100Y470500D01*
X389600Y470167D01*
X390183Y470000D01*
X390767Y470083D01*
X391267Y470333D01*
X391600Y470667D01*
G01X394283Y470000D02*
Y473333D01*
G01Y472500D02*
X394617Y472917D01*
X395117Y473250D01*
X395783Y473333D01*
X396367Y473250D01*
X396867Y472917D01*
X397117Y472333D01*
Y470000D01*
G01X402800Y475000D02*
Y470000D01*
G01Y470750D02*
X402467Y470333D01*
X401967Y470083D01*
X401383Y470000D01*
X400717Y470167D01*
X400217Y470583D01*
X399883Y471083D01*
X399800Y471667D01*
X399883Y472250D01*
X400217Y472750D01*
X400717Y473167D01*
X401383Y473333D01*
X401967Y473250D01*
X402383Y473083D01*
X402800Y472750D01*
G01X412500Y470000D02*
X412000Y470083D01*
X411500Y470417D01*
X411167Y471000D01*
X411000Y471667D01*
X411167Y472333D01*
X411500Y472917D01*
X412000Y473250D01*
X412500Y473333D01*
X413000Y473250D01*
X413500Y472917D01*
X413833Y472333D01*
X413917Y471667D01*
X413833Y471000D01*
X413500Y470417D01*
X413000Y470083D01*
X412500Y470000D01*
G01X418100Y475000D02*
Y470000D01*
G01X416933Y473333D02*
X419267D01*
G01X422283Y470000D02*
Y475000D01*
G01Y472583D02*
X422700Y473000D01*
X423117Y473250D01*
X423783Y473333D01*
X424283Y473250D01*
X424867Y472917D01*
X425117Y472417D01*
Y470000D01*
G01X428050Y472250D02*
X430717D01*
X430467Y472833D01*
X430050Y473167D01*
X429467Y473333D01*
X428883Y473250D01*
X428383Y473000D01*
X428050Y472417D01*
X427883Y471917D01*
Y471417D01*
X428050Y470917D01*
X428467Y470417D01*
X428967Y470083D01*
X429550Y470000D01*
X430133Y470167D01*
X430717Y470667D01*
G01X433733Y470000D02*
Y473333D01*
G01Y472667D02*
X434150Y473000D01*
X434567Y473250D01*
X435150Y473333D01*
X435567Y473250D01*
X436067Y473000D01*
G01X439250Y470583D02*
X439667Y470250D01*
X440250Y470000D01*
X440750D01*
X441250Y470167D01*
X441583Y470417D01*
X441750Y470750D01*
X441667Y471250D01*
X441333Y471500D01*
X439833Y472000D01*
X439500Y472583D01*
X439667Y473000D01*
X440000Y473250D01*
X440500Y473333D01*
X441000Y473250D01*
X441500Y473000D01*
G01X446517Y468333D02*
X447350Y469167D01*
X447767Y470000D01*
Y473333D01*
X447350Y474167D01*
X446517Y475000D01*
G01X270833Y485000D02*
Y490000D01*
X272833D01*
X273500Y489750D01*
X274000Y489167D01*
X274167Y488500D01*
X274000Y487833D01*
X273583Y487333D01*
X272833Y487083D01*
X270833D01*
G01X278100Y490000D02*
Y485000D01*
G01X276183Y490000D02*
X280017D01*
G01X281950Y485000D02*
Y490000D01*
G01X285450D02*
Y485000D01*
G01Y487500D02*
X281950D01*
G01X287800Y484833D02*
X290800Y490000D01*
G01X292983Y485000D02*
Y490000D01*
X296817Y485000D01*
Y490000D01*
G01X298833Y485000D02*
Y490000D01*
X300833D01*
X301500Y489750D01*
X302000Y489167D01*
X302167Y488500D01*
X302000Y487833D01*
X301583Y487333D01*
X300833Y487083D01*
X298833D01*
G01X306100Y490000D02*
Y485000D01*
G01X304183Y490000D02*
X308017D01*
G01X309950Y485000D02*
Y490000D01*
G01X313450D02*
Y485000D01*
G01Y487500D02*
X309950D01*
G01X321233Y485000D02*
X324567Y486667D01*
X321233Y488333D01*
G01X327417Y485917D02*
X329583D01*
G01Y487417D02*
X327417D01*
G01X332267Y485750D02*
X332767Y485333D01*
X333350Y485083D01*
X334100Y485000D01*
X334850Y485167D01*
X335433Y485500D01*
X335850Y486083D01*
X335933Y486750D01*
X335767Y487417D01*
X335350Y487833D01*
X334767Y488167D01*
X334183Y488250D01*
X333600Y488167D01*
X332850Y487833D01*
X333100Y490000D01*
X335350D01*
G01X342800Y485000D02*
Y488333D01*
G01Y487417D02*
X343050Y487833D01*
X343467Y488167D01*
X344050Y488333D01*
X344633Y488167D01*
X345050Y487833D01*
X345300Y487417D01*
Y485000D01*
G01Y487417D02*
X345550Y487833D01*
X345967Y488167D01*
X346550Y488333D01*
X347133Y488167D01*
X347550Y487833D01*
X347800Y487333D01*
Y485000D01*
G01X348400D02*
Y488333D01*
G01Y487417D02*
X348650Y487833D01*
X349067Y488167D01*
X349650Y488333D01*
X350233Y488167D01*
X350650Y487833D01*
X350900Y487417D01*
Y485000D01*
G01Y487417D02*
X351150Y487833D01*
X351567Y488167D01*
X352150Y488333D01*
X352733Y488167D01*
X353150Y487833D01*
X353400Y487333D01*
Y485000D01*
G01X262500Y479000D02*
X694500D01*
G01X270583Y498500D02*
Y503500D01*
X274417Y498500D01*
Y503500D01*
G01X276433Y498500D02*
Y503500D01*
X278433D01*
X279100Y503250D01*
X279600Y502667D01*
X279767Y502000D01*
X279600Y501333D01*
X279183Y500833D01*
X278433Y500583D01*
X276433D01*
G01X283700Y503500D02*
Y498500D01*
G01X281783Y503500D02*
X285617D01*
G01X287550Y498500D02*
Y503500D01*
G01X291050D02*
Y498500D01*
G01Y501000D02*
X287550D01*
G01X298750Y499167D02*
X299417Y498750D01*
X300167Y498500D01*
X300833D01*
X301500Y498750D01*
X302000Y499167D01*
X302250Y499750D01*
X302083Y500333D01*
X301667Y500833D01*
X300917Y501167D01*
X299917Y501333D01*
X299333Y501667D01*
X299083Y502250D01*
X299250Y502833D01*
X299667Y503250D01*
X300250Y503500D01*
X300833D01*
X301417Y503333D01*
X301917Y502917D01*
G01X306100Y501833D02*
Y498500D01*
G01Y503167D02*
X305933Y503250D01*
Y503417D01*
X306100Y503500D01*
X306267Y503417D01*
Y503250D01*
X306100Y503167D01*
G01X310450Y501833D02*
X312950D01*
X310450Y498500D01*
X312950D01*
G01X316050Y500750D02*
X318717D01*
X318467Y501333D01*
X318050Y501667D01*
X317467Y501833D01*
X316883Y501750D01*
X316383Y501500D01*
X316050Y500917D01*
X315883Y500417D01*
Y499917D01*
X316050Y499417D01*
X316467Y498917D01*
X316967Y498583D01*
X317550Y498500D01*
X318133Y498667D01*
X318717Y499167D01*
G01X326667Y499500D02*
X327167Y498917D01*
X327833Y498583D01*
X328583Y498500D01*
X329250Y498583D01*
X329917Y499000D01*
X330333Y499500D01*
X330417Y500000D01*
X330250Y500583D01*
X329667Y501000D01*
X329083Y501167D01*
X328333D01*
G01X329083D02*
X329583Y501417D01*
X330000Y501833D01*
X330167Y502333D01*
X330000Y502833D01*
X329583Y503250D01*
X328833Y503500D01*
X328083Y503417D01*
X327333Y503083D01*
G01X334100Y498333D02*
X333933Y498417D01*
Y498583D01*
X334100Y498667D01*
X334267Y498583D01*
Y498417D01*
X334100Y498333D01*
G01X337867Y499250D02*
X338367Y498833D01*
X338950Y498583D01*
X339700Y498500D01*
X340450Y498667D01*
X341033Y499000D01*
X341450Y499583D01*
X341533Y500250D01*
X341367Y500917D01*
X340950Y501333D01*
X340367Y501667D01*
X339783Y501750D01*
X339200Y501667D01*
X338450Y501333D01*
X338700Y503500D01*
X340950D01*
G01X343467Y499250D02*
X343967Y498833D01*
X344550Y498583D01*
X345300Y498500D01*
X346050Y498667D01*
X346633Y499000D01*
X347050Y499583D01*
X347133Y500250D01*
X346967Y500917D01*
X346550Y501333D01*
X345967Y501667D01*
X345383Y501750D01*
X344800Y501667D01*
X344050Y501333D01*
X344300Y503500D01*
X346550D01*
G01X348400Y498500D02*
Y501833D01*
G01Y500917D02*
X348650Y501333D01*
X349067Y501667D01*
X349650Y501833D01*
X350233Y501667D01*
X350650Y501333D01*
X350900Y500917D01*
Y498500D01*
G01Y500917D02*
X351150Y501333D01*
X351567Y501667D01*
X352150Y501833D01*
X352733Y501667D01*
X353150Y501333D01*
X353400Y500833D01*
Y498500D01*
G01X354000D02*
Y501833D01*
G01Y500917D02*
X354250Y501333D01*
X354667Y501667D01*
X355250Y501833D01*
X355833Y501667D01*
X356250Y501333D01*
X356500Y500917D01*
Y498500D01*
G01Y500917D02*
X356750Y501333D01*
X357167Y501667D01*
X357750Y501833D01*
X358333Y501667D01*
X358750Y501333D01*
X359000Y500833D01*
Y498500D01*
G01X270583Y513500D02*
Y518500D01*
X274417Y513500D01*
Y518500D01*
G01X276433Y513500D02*
Y518500D01*
X278433D01*
X279100Y518250D01*
X279600Y517667D01*
X279767Y517000D01*
X279600Y516333D01*
X279183Y515833D01*
X278433Y515583D01*
X276433D01*
G01X283700Y518500D02*
Y513500D01*
G01X281783Y518500D02*
X285617D01*
G01X287550Y513500D02*
Y518500D01*
G01X291050D02*
Y513500D01*
G01Y516000D02*
X287550D01*
G01X298750Y514167D02*
X299417Y513750D01*
X300167Y513500D01*
X300833D01*
X301500Y513750D01*
X302000Y514167D01*
X302250Y514750D01*
X302083Y515333D01*
X301667Y515833D01*
X300917Y516167D01*
X299917Y516333D01*
X299333Y516667D01*
X299083Y517250D01*
X299250Y517833D01*
X299667Y518250D01*
X300250Y518500D01*
X300833D01*
X301417Y518333D01*
X301917Y517917D01*
G01X306100Y516833D02*
Y513500D01*
G01Y518167D02*
X305933Y518250D01*
Y518417D01*
X306100Y518500D01*
X306267Y518417D01*
Y518250D01*
X306100Y518167D01*
G01X310450Y516833D02*
X312950D01*
X310450Y513500D01*
X312950D01*
G01X316050Y515750D02*
X318717D01*
X318467Y516333D01*
X318050Y516667D01*
X317467Y516833D01*
X316883Y516750D01*
X316383Y516500D01*
X316050Y515917D01*
X315883Y515417D01*
Y514917D01*
X316050Y514417D01*
X316467Y513917D01*
X316967Y513583D01*
X317550Y513500D01*
X318133Y513667D01*
X318717Y514167D01*
G01X324567Y513500D02*
X321233Y515167D01*
X324567Y516833D01*
G01X332267Y514250D02*
X332767Y513833D01*
X333350Y513583D01*
X334100Y513500D01*
X334850Y513667D01*
X335433Y514000D01*
X335850Y514583D01*
X335933Y515250D01*
X335767Y515917D01*
X335350Y516333D01*
X334767Y516667D01*
X334183Y516750D01*
X333600Y516667D01*
X332850Y516333D01*
X333100Y518500D01*
X335350D01*
G01X337200Y513500D02*
Y516833D01*
G01Y515917D02*
X337450Y516333D01*
X337867Y516667D01*
X338450Y516833D01*
X339033Y516667D01*
X339450Y516333D01*
X339700Y515917D01*
Y513500D01*
G01Y515917D02*
X339950Y516333D01*
X340367Y516667D01*
X340950Y516833D01*
X341533Y516667D01*
X341950Y516333D01*
X342200Y515833D01*
Y513500D01*
G01X342800D02*
Y516833D01*
G01Y515917D02*
X343050Y516333D01*
X343467Y516667D01*
X344050Y516833D01*
X344633Y516667D01*
X345050Y516333D01*
X345300Y515917D01*
Y513500D01*
G01Y515917D02*
X345550Y516333D01*
X345967Y516667D01*
X346550Y516833D01*
X347133Y516667D01*
X347550Y516333D01*
X347800Y515833D01*
Y513500D01*
G01X270667Y535000D02*
Y531417D01*
X271000Y530667D01*
X271667Y530167D01*
X272500Y530000D01*
X273333Y530167D01*
X274000Y530667D01*
X274333Y531417D01*
Y535000D01*
G01X276683Y530000D02*
Y533333D01*
G01Y532500D02*
X277017Y532917D01*
X277517Y533250D01*
X278183Y533333D01*
X278767Y533250D01*
X279267Y532917D01*
X279517Y532333D01*
Y530000D01*
G01X282617Y531667D02*
X284783D01*
G01X287800Y528333D02*
Y533333D01*
G01Y532583D02*
X288217Y533000D01*
X288633Y533250D01*
X289300Y533333D01*
X289883Y533250D01*
X290467Y532833D01*
X290717Y532250D01*
X290800Y531667D01*
X290717Y531083D01*
X290467Y530500D01*
X289967Y530167D01*
X289300Y530000D01*
X288717Y530083D01*
X288133Y530333D01*
X287800Y530667D01*
G01X294900Y530000D02*
Y535000D01*
G01X299083Y533333D02*
Y531000D01*
X299417Y530417D01*
X299917Y530083D01*
X300500Y530000D01*
X301083Y530083D01*
X301583Y530417D01*
X301917Y531000D01*
G01Y530000D02*
Y533333D01*
G01X304933Y528750D02*
X305517Y528417D01*
X306183Y528333D01*
X306767Y528417D01*
X307267Y528833D01*
X307600Y529417D01*
Y533333D01*
G01Y532667D02*
X307267Y533000D01*
X306767Y533250D01*
X306183Y533333D01*
X305517Y533167D01*
X305100Y532833D01*
X304767Y532250D01*
X304600Y531667D01*
X304683Y531167D01*
X305017Y530583D01*
X305517Y530167D01*
X306183Y530000D01*
X306683Y530083D01*
X307267Y530417D01*
X307600Y530750D01*
G01X310533Y528750D02*
X311117Y528417D01*
X311783Y528333D01*
X312367Y528417D01*
X312867Y528833D01*
X313200Y529417D01*
Y533333D01*
G01Y532667D02*
X312867Y533000D01*
X312367Y533250D01*
X311783Y533333D01*
X311117Y533167D01*
X310700Y532833D01*
X310367Y532250D01*
X310200Y531667D01*
X310283Y531167D01*
X310617Y530583D01*
X311117Y530167D01*
X311783Y530000D01*
X312283Y530083D01*
X312867Y530417D01*
X313200Y530750D01*
G01X316050Y532250D02*
X318717D01*
X318467Y532833D01*
X318050Y533167D01*
X317467Y533333D01*
X316883Y533250D01*
X316383Y533000D01*
X316050Y532417D01*
X315883Y531917D01*
Y531417D01*
X316050Y530917D01*
X316467Y530417D01*
X316967Y530083D01*
X317550Y530000D01*
X318133Y530167D01*
X318717Y530667D01*
G01X324400Y535000D02*
Y530000D01*
G01Y530750D02*
X324067Y530333D01*
X323567Y530083D01*
X322983Y530000D01*
X322317Y530167D01*
X321817Y530583D01*
X321483Y531083D01*
X321400Y531667D01*
X321483Y532250D01*
X321817Y532750D01*
X322317Y533167D01*
X322983Y533333D01*
X323567Y533250D01*
X323983Y533083D01*
X324400Y532750D01*
G01X332433Y530000D02*
Y535000D01*
X334433D01*
X335100Y534750D01*
X335600Y534167D01*
X335767Y533500D01*
X335600Y532833D01*
X335183Y532333D01*
X334433Y532083D01*
X332433D01*
G01X339700Y535000D02*
Y530000D01*
G01X337783Y535000D02*
X341617D01*
G01X343550Y530000D02*
Y535000D01*
G01X347050D02*
Y530000D01*
G01Y532500D02*
X343550D01*
G01X356083Y528333D02*
X355250Y529167D01*
X354833Y530000D01*
Y533333D01*
X355250Y534167D01*
X356083Y535000D01*
G01X360350Y530000D02*
Y535000D01*
G01X363850D02*
Y530000D01*
G01Y532500D02*
X360350D01*
G01X367700Y530000D02*
X367200Y530083D01*
X366700Y530417D01*
X366367Y531000D01*
X366200Y531667D01*
X366367Y532333D01*
X366700Y532917D01*
X367200Y533250D01*
X367700Y533333D01*
X368200Y533250D01*
X368700Y532917D01*
X369033Y532333D01*
X369117Y531667D01*
X369033Y531000D01*
X368700Y530417D01*
X368200Y530083D01*
X367700Y530000D01*
G01X373300D02*
Y535000D01*
G01X377650Y532250D02*
X380317D01*
X380067Y532833D01*
X379650Y533167D01*
X379067Y533333D01*
X378483Y533250D01*
X377983Y533000D01*
X377650Y532417D01*
X377483Y531917D01*
Y531417D01*
X377650Y530917D01*
X378067Y530417D01*
X378567Y530083D01*
X379150Y530000D01*
X379733Y530167D01*
X380317Y530667D01*
G01X388350D02*
X389017Y530250D01*
X389767Y530000D01*
X390433D01*
X391100Y530250D01*
X391600Y530667D01*
X391850Y531250D01*
X391683Y531833D01*
X391267Y532333D01*
X390517Y532667D01*
X389517Y532833D01*
X388933Y533167D01*
X388683Y533750D01*
X388850Y534333D01*
X389267Y534750D01*
X389850Y535000D01*
X390433D01*
X391017Y534833D01*
X391517Y534417D01*
G01X395700Y533333D02*
Y530000D01*
G01Y534667D02*
X395533Y534750D01*
Y534917D01*
X395700Y535000D01*
X395867Y534917D01*
Y534750D01*
X395700Y534667D01*
G01X400050Y533333D02*
X402550D01*
X400050Y530000D01*
X402550D01*
G01X405650Y532250D02*
X408317D01*
X408067Y532833D01*
X407650Y533167D01*
X407067Y533333D01*
X406483Y533250D01*
X405983Y533000D01*
X405650Y532417D01*
X405483Y531917D01*
Y531417D01*
X405650Y530917D01*
X406067Y530417D01*
X406567Y530083D01*
X407150Y530000D01*
X407733Y530167D01*
X408317Y530667D01*
G01X414167Y530000D02*
X410833Y531667D01*
X414167Y533333D01*
G01X418100Y530000D02*
Y535000D01*
X417100Y534000D01*
G01Y530000D02*
X419100D01*
G01X422283Y530583D02*
X422867Y530167D01*
X423533Y530000D01*
X424200Y530167D01*
X424783Y530667D01*
X425200Y531417D01*
X425367Y532167D01*
Y533083D01*
X425200Y533833D01*
X424783Y534500D01*
X424283Y534833D01*
X423700Y535000D01*
X423033Y534833D01*
X422533Y534500D01*
X422200Y534000D01*
X422033Y533333D01*
X422200Y532750D01*
X422617Y532167D01*
X423117Y531833D01*
X423700Y531750D01*
X424367Y531917D01*
X424867Y532333D01*
X425367Y533083D01*
G01X429133Y530000D02*
X429300Y531083D01*
X429550Y532000D01*
X429883Y532833D01*
X430300Y533750D01*
X430967Y535000D01*
X427633D01*
G01X432400Y530000D02*
Y533333D01*
G01Y532417D02*
X432650Y532833D01*
X433067Y533167D01*
X433650Y533333D01*
X434233Y533167D01*
X434650Y532833D01*
X434900Y532417D01*
Y530000D01*
G01Y532417D02*
X435150Y532833D01*
X435567Y533167D01*
X436150Y533333D01*
X436733Y533167D01*
X437150Y532833D01*
X437400Y532333D01*
Y530000D01*
G01X440500Y533333D02*
Y530000D01*
G01Y534667D02*
X440333Y534750D01*
Y534917D01*
X440500Y535000D01*
X440667Y534917D01*
Y534750D01*
X440500Y534667D01*
G01X446100Y530000D02*
Y535000D01*
G01X455217Y533333D02*
X456217Y530000D01*
X457300Y533333D01*
X458383Y530000D01*
X459383Y533333D01*
G01X462900D02*
Y530000D01*
G01Y534667D02*
X462733Y534750D01*
Y534917D01*
X462900Y535000D01*
X463067Y534917D01*
Y534750D01*
X462900Y534667D01*
G01X468500Y535000D02*
Y530000D01*
G01X467333Y533333D02*
X469667D01*
G01X472683Y530000D02*
Y535000D01*
G01Y532583D02*
X473100Y533000D01*
X473517Y533250D01*
X474183Y533333D01*
X474683Y533250D01*
X475267Y532917D01*
X475517Y532417D01*
Y530000D01*
G01X483550D02*
Y535000D01*
G01X487050D02*
Y530000D01*
G01Y532500D02*
X483550D01*
G01X488817Y530000D02*
X490900Y535000D01*
X492983Y530000D01*
G01X492233Y531750D02*
X489567D01*
G01X494750Y530667D02*
X495417Y530250D01*
X496167Y530000D01*
X496833D01*
X497500Y530250D01*
X498000Y530667D01*
X498250Y531250D01*
X498083Y531833D01*
X497667Y532333D01*
X496917Y532667D01*
X495917Y532833D01*
X495333Y533167D01*
X495083Y533750D01*
X495250Y534333D01*
X495667Y534750D01*
X496250Y535000D01*
X496833D01*
X497417Y534833D01*
X497917Y534417D01*
G01X500433Y535000D02*
Y530000D01*
X503767D01*
G01X511800Y528333D02*
Y533333D01*
G01Y532583D02*
X512217Y533000D01*
X512633Y533250D01*
X513300Y533333D01*
X513883Y533250D01*
X514467Y532833D01*
X514717Y532250D01*
X514800Y531667D01*
X514717Y531083D01*
X514467Y530500D01*
X513967Y530167D01*
X513300Y530000D01*
X512717Y530083D01*
X512133Y530333D01*
X511800Y530667D01*
G01X517733Y530000D02*
Y533333D01*
G01Y532667D02*
X518150Y533000D01*
X518567Y533250D01*
X519150Y533333D01*
X519567Y533250D01*
X520067Y533000D01*
G01X524500Y530000D02*
X524000Y530083D01*
X523500Y530417D01*
X523167Y531000D01*
X523000Y531667D01*
X523167Y532333D01*
X523500Y532917D01*
X524000Y533250D01*
X524500Y533333D01*
X525000Y533250D01*
X525500Y532917D01*
X525833Y532333D01*
X525917Y531667D01*
X525833Y531000D01*
X525500Y530417D01*
X525000Y530083D01*
X524500Y530000D01*
G01X531600Y535000D02*
Y530000D01*
G01Y530750D02*
X531267Y530333D01*
X530767Y530083D01*
X530183Y530000D01*
X529517Y530167D01*
X529017Y530583D01*
X528683Y531083D01*
X528600Y531667D01*
X528683Y532250D01*
X529017Y532750D01*
X529517Y533167D01*
X530183Y533333D01*
X530767Y533250D01*
X531183Y533083D01*
X531600Y532750D01*
G01X534283Y533333D02*
Y531000D01*
X534617Y530417D01*
X535117Y530083D01*
X535700Y530000D01*
X536283Y530083D01*
X536783Y530417D01*
X537117Y531000D01*
G01Y530000D02*
Y533333D01*
G01X542633Y532917D02*
X542050Y533250D01*
X541550Y533333D01*
X540883Y533167D01*
X540383Y532833D01*
X540050Y532250D01*
X539967Y531667D01*
X540050Y531083D01*
X540383Y530583D01*
X540883Y530167D01*
X541550Y530000D01*
X542133Y530167D01*
X542633Y530500D01*
G01X546900Y535000D02*
Y530000D01*
G01X545733Y533333D02*
X548067D01*
G01X551250Y530583D02*
X551667Y530250D01*
X552250Y530000D01*
X552750D01*
X553250Y530167D01*
X553583Y530417D01*
X553750Y530750D01*
X553667Y531250D01*
X553333Y531500D01*
X551833Y532000D01*
X551500Y532583D01*
X551667Y533000D01*
X552000Y533250D01*
X552500Y533333D01*
X553000Y533250D01*
X553500Y533000D01*
G01X558517Y528333D02*
X559350Y529167D01*
X559767Y530000D01*
Y533333D01*
X559350Y534167D01*
X558517Y535000D01*
G01X270667Y550000D02*
Y546417D01*
X271000Y545667D01*
X271667Y545167D01*
X272500Y545000D01*
X273333Y545167D01*
X274000Y545667D01*
X274333Y546417D01*
Y550000D01*
G01X276683Y545000D02*
Y548333D01*
G01Y547500D02*
X277017Y547917D01*
X277517Y548250D01*
X278183Y548333D01*
X278767Y548250D01*
X279267Y547917D01*
X279517Y547333D01*
Y545000D01*
G01X282617Y546667D02*
X284783D01*
G01X287800Y543333D02*
Y548333D01*
G01Y547583D02*
X288217Y548000D01*
X288633Y548250D01*
X289300Y548333D01*
X289883Y548250D01*
X290467Y547833D01*
X290717Y547250D01*
X290800Y546667D01*
X290717Y546083D01*
X290467Y545500D01*
X289967Y545167D01*
X289300Y545000D01*
X288717Y545083D01*
X288133Y545333D01*
X287800Y545667D01*
G01X294900Y545000D02*
Y550000D01*
G01X299083Y548333D02*
Y546000D01*
X299417Y545417D01*
X299917Y545083D01*
X300500Y545000D01*
X301083Y545083D01*
X301583Y545417D01*
X301917Y546000D01*
G01Y545000D02*
Y548333D01*
G01X304933Y543750D02*
X305517Y543417D01*
X306183Y543333D01*
X306767Y543417D01*
X307267Y543833D01*
X307600Y544417D01*
Y548333D01*
G01Y547667D02*
X307267Y548000D01*
X306767Y548250D01*
X306183Y548333D01*
X305517Y548167D01*
X305100Y547833D01*
X304767Y547250D01*
X304600Y546667D01*
X304683Y546167D01*
X305017Y545583D01*
X305517Y545167D01*
X306183Y545000D01*
X306683Y545083D01*
X307267Y545417D01*
X307600Y545750D01*
G01X310533Y543750D02*
X311117Y543417D01*
X311783Y543333D01*
X312367Y543417D01*
X312867Y543833D01*
X313200Y544417D01*
Y548333D01*
G01Y547667D02*
X312867Y548000D01*
X312367Y548250D01*
X311783Y548333D01*
X311117Y548167D01*
X310700Y547833D01*
X310367Y547250D01*
X310200Y546667D01*
X310283Y546167D01*
X310617Y545583D01*
X311117Y545167D01*
X311783Y545000D01*
X312283Y545083D01*
X312867Y545417D01*
X313200Y545750D01*
G01X316050Y547250D02*
X318717D01*
X318467Y547833D01*
X318050Y548167D01*
X317467Y548333D01*
X316883Y548250D01*
X316383Y548000D01*
X316050Y547417D01*
X315883Y546917D01*
Y546417D01*
X316050Y545917D01*
X316467Y545417D01*
X316967Y545083D01*
X317550Y545000D01*
X318133Y545167D01*
X318717Y545667D01*
G01X324400Y550000D02*
Y545000D01*
G01Y545750D02*
X324067Y545333D01*
X323567Y545083D01*
X322983Y545000D01*
X322317Y545167D01*
X321817Y545583D01*
X321483Y546083D01*
X321400Y546667D01*
X321483Y547250D01*
X321817Y547750D01*
X322317Y548167D01*
X322983Y548333D01*
X323567Y548250D01*
X323983Y548083D01*
X324400Y547750D01*
G01X332433Y545000D02*
Y550000D01*
X334433D01*
X335100Y549750D01*
X335600Y549167D01*
X335767Y548500D01*
X335600Y547833D01*
X335183Y547333D01*
X334433Y547083D01*
X332433D01*
G01X339700Y550000D02*
Y545000D01*
G01X337783Y550000D02*
X341617D01*
G01X343550Y545000D02*
Y550000D01*
G01X347050D02*
Y545000D01*
G01Y547500D02*
X343550D01*
G01X356083Y543333D02*
X355250Y544167D01*
X354833Y545000D01*
Y548333D01*
X355250Y549167D01*
X356083Y550000D01*
G01X360350Y545000D02*
Y550000D01*
G01X363850D02*
Y545000D01*
G01Y547500D02*
X360350D01*
G01X367700Y545000D02*
X367200Y545083D01*
X366700Y545417D01*
X366367Y546000D01*
X366200Y546667D01*
X366367Y547333D01*
X366700Y547917D01*
X367200Y548250D01*
X367700Y548333D01*
X368200Y548250D01*
X368700Y547917D01*
X369033Y547333D01*
X369117Y546667D01*
X369033Y546000D01*
X368700Y545417D01*
X368200Y545083D01*
X367700Y545000D01*
G01X373300D02*
Y550000D01*
G01X377650Y547250D02*
X380317D01*
X380067Y547833D01*
X379650Y548167D01*
X379067Y548333D01*
X378483Y548250D01*
X377983Y548000D01*
X377650Y547417D01*
X377483Y546917D01*
Y546417D01*
X377650Y545917D01*
X378067Y545417D01*
X378567Y545083D01*
X379150Y545000D01*
X379733Y545167D01*
X380317Y545667D01*
G01X388350D02*
X389017Y545250D01*
X389767Y545000D01*
X390433D01*
X391100Y545250D01*
X391600Y545667D01*
X391850Y546250D01*
X391683Y546833D01*
X391267Y547333D01*
X390517Y547667D01*
X389517Y547833D01*
X388933Y548167D01*
X388683Y548750D01*
X388850Y549333D01*
X389267Y549750D01*
X389850Y550000D01*
X390433D01*
X391017Y549833D01*
X391517Y549417D01*
G01X395700Y548333D02*
Y545000D01*
G01Y549667D02*
X395533Y549750D01*
Y549917D01*
X395700Y550000D01*
X395867Y549917D01*
Y549750D01*
X395700Y549667D01*
G01X400050Y548333D02*
X402550D01*
X400050Y545000D01*
X402550D01*
G01X405650Y547250D02*
X408317D01*
X408067Y547833D01*
X407650Y548167D01*
X407067Y548333D01*
X406483Y548250D01*
X405983Y548000D01*
X405650Y547417D01*
X405483Y546917D01*
Y546417D01*
X405650Y545917D01*
X406067Y545417D01*
X406567Y545083D01*
X407150Y545000D01*
X407733Y545167D01*
X408317Y545667D01*
G01X414167Y545000D02*
X410833Y546667D01*
X414167Y548333D01*
G01X418100Y545000D02*
Y550000D01*
X417100Y549000D01*
G01Y545000D02*
X419100D01*
G01X422283Y545583D02*
X422867Y545167D01*
X423533Y545000D01*
X424200Y545167D01*
X424783Y545667D01*
X425200Y546417D01*
X425367Y547167D01*
Y548083D01*
X425200Y548833D01*
X424783Y549500D01*
X424283Y549833D01*
X423700Y550000D01*
X423033Y549833D01*
X422533Y549500D01*
X422200Y549000D01*
X422033Y548333D01*
X422200Y547750D01*
X422617Y547167D01*
X423117Y546833D01*
X423700Y546750D01*
X424367Y546917D01*
X424867Y547333D01*
X425367Y548083D01*
G01X429133Y545000D02*
X429300Y546083D01*
X429550Y547000D01*
X429883Y547833D01*
X430300Y548750D01*
X430967Y550000D01*
X427633D01*
G01X432400Y545000D02*
Y548333D01*
G01Y547417D02*
X432650Y547833D01*
X433067Y548167D01*
X433650Y548333D01*
X434233Y548167D01*
X434650Y547833D01*
X434900Y547417D01*
Y545000D01*
G01Y547417D02*
X435150Y547833D01*
X435567Y548167D01*
X436150Y548333D01*
X436733Y548167D01*
X437150Y547833D01*
X437400Y547333D01*
Y545000D01*
G01X440500Y548333D02*
Y545000D01*
G01Y549667D02*
X440333Y549750D01*
Y549917D01*
X440500Y550000D01*
X440667Y549917D01*
Y549750D01*
X440500Y549667D01*
G01X446100Y545000D02*
Y550000D01*
G01X455217Y548333D02*
X456217Y545000D01*
X457300Y548333D01*
X458383Y545000D01*
X459383Y548333D01*
G01X462900D02*
Y545000D01*
G01Y549667D02*
X462733Y549750D01*
Y549917D01*
X462900Y550000D01*
X463067Y549917D01*
Y549750D01*
X462900Y549667D01*
G01X468500Y550000D02*
Y545000D01*
G01X467333Y548333D02*
X469667D01*
G01X472683Y545000D02*
Y550000D01*
G01Y547583D02*
X473100Y548000D01*
X473517Y548250D01*
X474183Y548333D01*
X474683Y548250D01*
X475267Y547917D01*
X475517Y547417D01*
Y545000D01*
G01X483883D02*
Y548333D01*
G01Y547500D02*
X484217Y547917D01*
X484717Y548250D01*
X485383Y548333D01*
X485967Y548250D01*
X486467Y547917D01*
X486717Y547333D01*
Y545000D01*
G01X490900D02*
X490400Y545083D01*
X489900Y545417D01*
X489567Y546000D01*
X489400Y546667D01*
X489567Y547333D01*
X489900Y547917D01*
X490400Y548250D01*
X490900Y548333D01*
X491400Y548250D01*
X491900Y547917D01*
X492233Y547333D01*
X492317Y546667D01*
X492233Y546000D01*
X491900Y545417D01*
X491400Y545083D01*
X490900Y545000D01*
G01X495083D02*
Y548333D01*
G01Y547500D02*
X495417Y547917D01*
X495917Y548250D01*
X496583Y548333D01*
X497167Y548250D01*
X497667Y547917D01*
X497917Y547333D01*
Y545000D01*
G01X501017Y546667D02*
X503183D01*
G01X505950Y545000D02*
Y550000D01*
G01X509450D02*
Y545000D01*
G01Y547500D02*
X505950D01*
G01X511217Y545000D02*
X513300Y550000D01*
X515383Y545000D01*
G01X514633Y546750D02*
X511967D01*
G01X517150Y545667D02*
X517817Y545250D01*
X518567Y545000D01*
X519233D01*
X519900Y545250D01*
X520400Y545667D01*
X520650Y546250D01*
X520483Y546833D01*
X520067Y547333D01*
X519317Y547667D01*
X518317Y547833D01*
X517733Y548167D01*
X517483Y548750D01*
X517650Y549333D01*
X518067Y549750D01*
X518650Y550000D01*
X519233D01*
X519817Y549833D01*
X520317Y549417D01*
G01X522833Y550000D02*
Y545000D01*
X526167D01*
G01X534200Y543333D02*
Y548333D01*
G01Y547583D02*
X534617Y548000D01*
X535033Y548250D01*
X535700Y548333D01*
X536283Y548250D01*
X536867Y547833D01*
X537117Y547250D01*
X537200Y546667D01*
X537117Y546083D01*
X536867Y545500D01*
X536367Y545167D01*
X535700Y545000D01*
X535117Y545083D01*
X534533Y545333D01*
X534200Y545667D01*
G01X540133Y545000D02*
Y548333D01*
G01Y547667D02*
X540550Y548000D01*
X540967Y548250D01*
X541550Y548333D01*
X541967Y548250D01*
X542467Y548000D01*
G01X546900Y545000D02*
X546400Y545083D01*
X545900Y545417D01*
X545567Y546000D01*
X545400Y546667D01*
X545567Y547333D01*
X545900Y547917D01*
X546400Y548250D01*
X546900Y548333D01*
X547400Y548250D01*
X547900Y547917D01*
X548233Y547333D01*
X548317Y546667D01*
X548233Y546000D01*
X547900Y545417D01*
X547400Y545083D01*
X546900Y545000D01*
G01X554000Y550000D02*
Y545000D01*
G01Y545750D02*
X553667Y545333D01*
X553167Y545083D01*
X552583Y545000D01*
X551917Y545167D01*
X551417Y545583D01*
X551083Y546083D01*
X551000Y546667D01*
X551083Y547250D01*
X551417Y547750D01*
X551917Y548167D01*
X552583Y548333D01*
X553167Y548250D01*
X553583Y548083D01*
X554000Y547750D01*
G01X556683Y548333D02*
Y546000D01*
X557017Y545417D01*
X557517Y545083D01*
X558100Y545000D01*
X558683Y545083D01*
X559183Y545417D01*
X559517Y546000D01*
G01Y545000D02*
Y548333D01*
G01X565033Y547917D02*
X564450Y548250D01*
X563950Y548333D01*
X563283Y548167D01*
X562783Y547833D01*
X562450Y547250D01*
X562367Y546667D01*
X562450Y546083D01*
X562783Y545583D01*
X563283Y545167D01*
X563950Y545000D01*
X564533Y545167D01*
X565033Y545500D01*
G01X569300Y550000D02*
Y545000D01*
G01X568133Y548333D02*
X570467D01*
G01X573650Y545583D02*
X574067Y545250D01*
X574650Y545000D01*
X575150D01*
X575650Y545167D01*
X575983Y545417D01*
X576150Y545750D01*
X576067Y546250D01*
X575733Y546500D01*
X574233Y547000D01*
X573900Y547583D01*
X574067Y548000D01*
X574400Y548250D01*
X574900Y548333D01*
X575400Y548250D01*
X575900Y548000D01*
G01X580917Y543333D02*
X581750Y544167D01*
X582167Y545000D01*
Y548333D01*
X581750Y549167D01*
X580917Y550000D01*
G01X270833Y560000D02*
Y565000D01*
X272833D01*
X273500Y564750D01*
X274000Y564167D01*
X274167Y563500D01*
X274000Y562833D01*
X273583Y562333D01*
X272833Y562083D01*
X270833D01*
G01X278100Y560000D02*
Y565000D01*
G01X282283Y563333D02*
Y561000D01*
X282617Y560417D01*
X283117Y560083D01*
X283700Y560000D01*
X284283Y560083D01*
X284783Y560417D01*
X285117Y561000D01*
G01Y560000D02*
Y563333D01*
G01X288133Y558750D02*
X288717Y558417D01*
X289383Y558333D01*
X289967Y558417D01*
X290467Y558833D01*
X290800Y559417D01*
Y563333D01*
G01Y562667D02*
X290467Y563000D01*
X289967Y563250D01*
X289383Y563333D01*
X288717Y563167D01*
X288300Y562833D01*
X287967Y562250D01*
X287800Y561667D01*
X287883Y561167D01*
X288217Y560583D01*
X288717Y560167D01*
X289383Y560000D01*
X289883Y560083D01*
X290467Y560417D01*
X290800Y560750D01*
G01X293733Y558750D02*
X294317Y558417D01*
X294983Y558333D01*
X295567Y558417D01*
X296067Y558833D01*
X296400Y559417D01*
Y563333D01*
G01Y562667D02*
X296067Y563000D01*
X295567Y563250D01*
X294983Y563333D01*
X294317Y563167D01*
X293900Y562833D01*
X293567Y562250D01*
X293400Y561667D01*
X293483Y561167D01*
X293817Y560583D01*
X294317Y560167D01*
X294983Y560000D01*
X295483Y560083D01*
X296067Y560417D01*
X296400Y560750D01*
G01X299250Y562250D02*
X301917D01*
X301667Y562833D01*
X301250Y563167D01*
X300667Y563333D01*
X300083Y563250D01*
X299583Y563000D01*
X299250Y562417D01*
X299083Y561917D01*
Y561417D01*
X299250Y560917D01*
X299667Y560417D01*
X300167Y560083D01*
X300750Y560000D01*
X301333Y560167D01*
X301917Y560667D01*
G01X307600Y565000D02*
Y560000D01*
G01Y560750D02*
X307267Y560333D01*
X306767Y560083D01*
X306183Y560000D01*
X305517Y560167D01*
X305017Y560583D01*
X304683Y561083D01*
X304600Y561667D01*
X304683Y562250D01*
X305017Y562750D01*
X305517Y563167D01*
X306183Y563333D01*
X306767Y563250D01*
X307183Y563083D01*
X307600Y562750D01*
G01X315633Y560000D02*
Y565000D01*
X317633D01*
X318300Y564750D01*
X318800Y564167D01*
X318967Y563500D01*
X318800Y562833D01*
X318383Y562333D01*
X317633Y562083D01*
X315633D01*
G01X322900Y565000D02*
Y560000D01*
G01X320983Y565000D02*
X324817D01*
G01X326750Y560000D02*
Y565000D01*
G01X330250D02*
Y560000D01*
G01Y562500D02*
X326750D01*
G01X333683Y558333D02*
X332850Y559167D01*
X332433Y560000D01*
Y563333D01*
X332850Y564167D01*
X333683Y565000D01*
G01X338283Y560000D02*
Y565000D01*
G01Y562583D02*
X338700Y563000D01*
X339117Y563250D01*
X339783Y563333D01*
X340283Y563250D01*
X340867Y562917D01*
X341117Y562417D01*
Y560000D01*
G01X345300D02*
X344800Y560083D01*
X344300Y560417D01*
X343967Y561000D01*
X343800Y561667D01*
X343967Y562333D01*
X344300Y562917D01*
X344800Y563250D01*
X345300Y563333D01*
X345800Y563250D01*
X346300Y562917D01*
X346633Y562333D01*
X346717Y561667D01*
X346633Y561000D01*
X346300Y560417D01*
X345800Y560083D01*
X345300Y560000D01*
G01X350900D02*
Y565000D01*
G01X355250Y562250D02*
X357917D01*
X357667Y562833D01*
X357250Y563167D01*
X356667Y563333D01*
X356083Y563250D01*
X355583Y563000D01*
X355250Y562417D01*
X355083Y561917D01*
Y561417D01*
X355250Y560917D01*
X355667Y560417D01*
X356167Y560083D01*
X356750Y560000D01*
X357333Y560167D01*
X357917Y560667D01*
G01X366450Y560583D02*
X366867Y560250D01*
X367450Y560000D01*
X367950D01*
X368450Y560167D01*
X368783Y560417D01*
X368950Y560750D01*
X368867Y561250D01*
X368533Y561500D01*
X367033Y562000D01*
X366700Y562583D01*
X366867Y563000D01*
X367200Y563250D01*
X367700Y563333D01*
X368200Y563250D01*
X368700Y563000D01*
G01X373300Y563333D02*
Y560000D01*
G01Y564667D02*
X373133Y564750D01*
Y564917D01*
X373300Y565000D01*
X373467Y564917D01*
Y564750D01*
X373300Y564667D01*
G01X377650Y563333D02*
X380150D01*
X377650Y560000D01*
X380150D01*
G01X383250Y562250D02*
X385917D01*
X385667Y562833D01*
X385250Y563167D01*
X384667Y563333D01*
X384083Y563250D01*
X383583Y563000D01*
X383250Y562417D01*
X383083Y561917D01*
Y561417D01*
X383250Y560917D01*
X383667Y560417D01*
X384167Y560083D01*
X384750Y560000D01*
X385333Y560167D01*
X385917Y560667D01*
G01X388433Y560000D02*
X391767Y561667D01*
X388433Y563333D01*
G01X394617Y560917D02*
X396783D01*
G01Y562417D02*
X394617D01*
G01X401300Y560000D02*
Y565000D01*
X400300Y564000D01*
G01Y560000D02*
X402300D01*
G01X405317Y562083D02*
X405900Y562667D01*
X406400Y563000D01*
X407067Y563167D01*
X407650Y563000D01*
X408067Y562667D01*
X408400Y562167D01*
X408483Y561583D01*
X408400Y561083D01*
X408067Y560583D01*
X407567Y560167D01*
X406983Y560000D01*
X406317Y560167D01*
X405733Y560667D01*
X405400Y561417D01*
X405317Y562250D01*
X405483Y563333D01*
X405733Y563917D01*
X406150Y564500D01*
X406733Y564917D01*
X407317Y565000D01*
X407900Y564833D01*
X408317Y564417D01*
G01X415600Y560000D02*
Y563333D01*
G01Y562417D02*
X415850Y562833D01*
X416267Y563167D01*
X416850Y563333D01*
X417433Y563167D01*
X417850Y562833D01*
X418100Y562417D01*
Y560000D01*
G01Y562417D02*
X418350Y562833D01*
X418767Y563167D01*
X419350Y563333D01*
X419933Y563167D01*
X420350Y562833D01*
X420600Y562333D01*
Y560000D01*
G01X423700Y563333D02*
Y560000D01*
G01Y564667D02*
X423533Y564750D01*
Y564917D01*
X423700Y565000D01*
X423867Y564917D01*
Y564750D01*
X423700Y564667D01*
G01X429300Y560000D02*
Y565000D01*
G01X435317Y558333D02*
X436150Y559167D01*
X436567Y560000D01*
Y563333D01*
X436150Y564167D01*
X435317Y565000D01*
G01X262500Y494000D02*
X694500D01*
G01X262500Y509000D02*
X694500D01*
G01X262500Y524000D02*
X694500D01*
G01X262500Y539000D02*
X694500D01*
G01X262500Y554000D02*
X694500D01*
G01X273000Y609000D02*
Y604000D01*
G01X271083Y609000D02*
X274917D01*
G01X277183Y604000D02*
Y609000D01*
G01Y606583D02*
X277600Y607000D01*
X278017Y607250D01*
X278683Y607333D01*
X279183Y607250D01*
X279767Y606917D01*
X280017Y606417D01*
Y604000D01*
G01X282950Y606250D02*
X285617D01*
X285367Y606833D01*
X284950Y607167D01*
X284367Y607333D01*
X283783Y607250D01*
X283283Y607000D01*
X282950Y606417D01*
X282783Y605917D01*
Y605417D01*
X282950Y604917D01*
X283367Y604417D01*
X283867Y604083D01*
X284450Y604000D01*
X285033Y604167D01*
X285617Y604667D01*
G01X288633Y604000D02*
Y607333D01*
G01Y606667D02*
X289050Y607000D01*
X289467Y607250D01*
X290050Y607333D01*
X290467Y607250D01*
X290967Y607000D01*
G01X292900Y604000D02*
Y607333D01*
G01Y606417D02*
X293150Y606833D01*
X293567Y607167D01*
X294150Y607333D01*
X294733Y607167D01*
X295150Y606833D01*
X295400Y606417D01*
Y604000D01*
G01Y606417D02*
X295650Y606833D01*
X296067Y607167D01*
X296650Y607333D01*
X297233Y607167D01*
X297650Y606833D01*
X297900Y606333D01*
Y604000D01*
G01X302500D02*
Y607333D01*
G01Y606750D02*
X302167Y607083D01*
X301667Y607250D01*
X301083Y607333D01*
X300500Y607167D01*
X300000Y606833D01*
X299667Y606333D01*
X299500Y605667D01*
X299667Y605000D01*
X300000Y604500D01*
X300500Y604167D01*
X301083Y604000D01*
X301667Y604083D01*
X302167Y604333D01*
X302500Y604667D01*
G01X306600Y604000D02*
Y609000D01*
G01X316300Y602333D02*
Y607333D01*
G01Y606583D02*
X316717Y607000D01*
X317133Y607250D01*
X317800Y607333D01*
X318383Y607250D01*
X318967Y606833D01*
X319217Y606250D01*
X319300Y605667D01*
X319217Y605083D01*
X318967Y604500D01*
X318467Y604167D01*
X317800Y604000D01*
X317217Y604083D01*
X316633Y604333D01*
X316300Y604667D01*
G01X324900Y604000D02*
Y607333D01*
G01Y606750D02*
X324567Y607083D01*
X324067Y607250D01*
X323483Y607333D01*
X322900Y607167D01*
X322400Y606833D01*
X322067Y606333D01*
X321900Y605667D01*
X322067Y605000D01*
X322400Y604500D01*
X322900Y604167D01*
X323483Y604000D01*
X324067Y604083D01*
X324567Y604333D01*
X324900Y604667D01*
G01X330500Y609000D02*
Y604000D01*
G01Y604750D02*
X330167Y604333D01*
X329667Y604083D01*
X329083Y604000D01*
X328417Y604167D01*
X327917Y604583D01*
X327583Y605083D01*
X327500Y605667D01*
X327583Y606250D01*
X327917Y606750D01*
X328417Y607167D01*
X329083Y607333D01*
X329667Y607250D01*
X330083Y607083D01*
X330500Y606750D01*
G01X341533Y606917D02*
X340950Y607250D01*
X340450Y607333D01*
X339783Y607167D01*
X339283Y606833D01*
X338950Y606250D01*
X338867Y605667D01*
X338950Y605083D01*
X339283Y604583D01*
X339783Y604167D01*
X340450Y604000D01*
X341033Y604167D01*
X341533Y604500D01*
G01X347300Y604000D02*
Y607333D01*
G01Y606750D02*
X346967Y607083D01*
X346467Y607250D01*
X345883Y607333D01*
X345300Y607167D01*
X344800Y606833D01*
X344467Y606333D01*
X344300Y605667D01*
X344467Y605000D01*
X344800Y604500D01*
X345300Y604167D01*
X345883Y604000D01*
X346467Y604083D01*
X346967Y604333D01*
X347300Y604667D01*
G01X349983Y604000D02*
Y607333D01*
G01Y606500D02*
X350317Y606917D01*
X350817Y607250D01*
X351483Y607333D01*
X352067Y607250D01*
X352567Y606917D01*
X352817Y606333D01*
Y604000D01*
G01X363933Y606917D02*
X363350Y607250D01*
X362850Y607333D01*
X362183Y607167D01*
X361683Y606833D01*
X361350Y606250D01*
X361267Y605667D01*
X361350Y605083D01*
X361683Y604583D01*
X362183Y604167D01*
X362850Y604000D01*
X363433Y604167D01*
X363933Y604500D01*
G01X366783Y604000D02*
Y609000D01*
G01Y606583D02*
X367200Y607000D01*
X367617Y607250D01*
X368283Y607333D01*
X368783Y607250D01*
X369367Y606917D01*
X369617Y606417D01*
Y604000D01*
G01X375300D02*
Y607333D01*
G01Y606750D02*
X374967Y607083D01*
X374467Y607250D01*
X373883Y607333D01*
X373300Y607167D01*
X372800Y606833D01*
X372467Y606333D01*
X372300Y605667D01*
X372467Y605000D01*
X372800Y604500D01*
X373300Y604167D01*
X373883Y604000D01*
X374467Y604083D01*
X374967Y604333D01*
X375300Y604667D01*
G01X377983Y604000D02*
Y607333D01*
G01Y606500D02*
X378317Y606917D01*
X378817Y607250D01*
X379483Y607333D01*
X380067Y607250D01*
X380567Y606917D01*
X380817Y606333D01*
Y604000D01*
G01X383833Y602750D02*
X384417Y602417D01*
X385083Y602333D01*
X385667Y602417D01*
X386167Y602833D01*
X386500Y603417D01*
Y607333D01*
G01Y606667D02*
X386167Y607000D01*
X385667Y607250D01*
X385083Y607333D01*
X384417Y607167D01*
X384000Y606833D01*
X383667Y606250D01*
X383500Y605667D01*
X383583Y605167D01*
X383917Y604583D01*
X384417Y604167D01*
X385083Y604000D01*
X385583Y604083D01*
X386167Y604417D01*
X386500Y604750D01*
G01X389350Y606250D02*
X392017D01*
X391767Y606833D01*
X391350Y607167D01*
X390767Y607333D01*
X390183Y607250D01*
X389683Y607000D01*
X389350Y606417D01*
X389183Y605917D01*
Y605417D01*
X389350Y604917D01*
X389767Y604417D01*
X390267Y604083D01*
X390850Y604000D01*
X391433Y604167D01*
X392017Y604667D01*
G01X401800Y607333D02*
Y604000D01*
G01Y608667D02*
X401633Y608750D01*
Y608917D01*
X401800Y609000D01*
X401967Y608917D01*
Y608750D01*
X401800Y608667D01*
G01X405983Y604000D02*
Y607333D01*
G01Y606500D02*
X406317Y606917D01*
X406817Y607250D01*
X407483Y607333D01*
X408067Y607250D01*
X408567Y606917D01*
X408817Y606333D01*
Y604000D01*
G01X413000Y609000D02*
Y604000D01*
G01X411833Y607333D02*
X414167D01*
G01X418600Y604000D02*
X418100Y604083D01*
X417600Y604417D01*
X417267Y605000D01*
X417100Y605667D01*
X417267Y606333D01*
X417600Y606917D01*
X418100Y607250D01*
X418600Y607333D01*
X419100Y607250D01*
X419600Y606917D01*
X419933Y606333D01*
X420017Y605667D01*
X419933Y605000D01*
X419600Y604417D01*
X419100Y604083D01*
X418600Y604000D01*
G01X429300D02*
Y608250D01*
X429467Y608667D01*
X429800Y608917D01*
X430300Y609000D01*
X430800Y608833D01*
X431050Y608417D01*
G01X430050Y607000D02*
X428383D01*
G01X433983Y607333D02*
Y605000D01*
X434317Y604417D01*
X434817Y604083D01*
X435400Y604000D01*
X435983Y604083D01*
X436483Y604417D01*
X436817Y605000D01*
G01Y604000D02*
Y607333D01*
G01X441000Y604000D02*
Y609000D01*
G01X446600Y604000D02*
Y609000D01*
G01X459133Y606917D02*
X458550Y607250D01*
X458050Y607333D01*
X457383Y607167D01*
X456883Y606833D01*
X456550Y606250D01*
X456467Y605667D01*
X456550Y605083D01*
X456883Y604583D01*
X457383Y604167D01*
X458050Y604000D01*
X458633Y604167D01*
X459133Y604500D01*
G01X463400Y604000D02*
X462900Y604083D01*
X462400Y604417D01*
X462067Y605000D01*
X461900Y605667D01*
X462067Y606333D01*
X462400Y606917D01*
X462900Y607250D01*
X463400Y607333D01*
X463900Y607250D01*
X464400Y606917D01*
X464733Y606333D01*
X464817Y605667D01*
X464733Y605000D01*
X464400Y604417D01*
X463900Y604083D01*
X463400Y604000D01*
G01X467583D02*
Y607333D01*
G01Y606500D02*
X467917Y606917D01*
X468417Y607250D01*
X469083Y607333D01*
X469667Y607250D01*
X470167Y606917D01*
X470417Y606333D01*
Y604000D01*
G01X474600Y609000D02*
Y604000D01*
G01X473433Y607333D02*
X475767D01*
G01X481700Y604000D02*
Y607333D01*
G01Y606750D02*
X481367Y607083D01*
X480867Y607250D01*
X480283Y607333D01*
X479700Y607167D01*
X479200Y606833D01*
X478867Y606333D01*
X478700Y605667D01*
X478867Y605000D01*
X479200Y604500D01*
X479700Y604167D01*
X480283Y604000D01*
X480867Y604083D01*
X481367Y604333D01*
X481700Y604667D01*
G01X487133Y606917D02*
X486550Y607250D01*
X486050Y607333D01*
X485383Y607167D01*
X484883Y606833D01*
X484550Y606250D01*
X484467Y605667D01*
X484550Y605083D01*
X484883Y604583D01*
X485383Y604167D01*
X486050Y604000D01*
X486633Y604167D01*
X487133Y604500D01*
G01X491400Y609000D02*
Y604000D01*
G01X490233Y607333D02*
X492567D01*
G01X270417Y588500D02*
X272500Y593500D01*
X274583Y588500D01*
G01X273833Y590250D02*
X271167D01*
G01X276683Y588500D02*
Y591833D01*
G01Y591000D02*
X277017Y591417D01*
X277517Y591750D01*
X278183Y591833D01*
X278767Y591750D01*
X279267Y591417D01*
X279517Y590833D01*
Y588500D01*
G01X281950Y587000D02*
X282450Y586833D01*
X283117Y587000D01*
X283533Y587333D01*
X283867Y587750D01*
X284367Y589083D01*
X285450Y591833D01*
G01X282783D02*
X284367Y589083D01*
G01X293483Y588500D02*
Y593500D01*
G01Y591083D02*
X293900Y591500D01*
X294317Y591750D01*
X294983Y591833D01*
X295483Y591750D01*
X296067Y591417D01*
X296317Y590917D01*
Y588500D01*
G01X300500D02*
X300000Y588583D01*
X299500Y588917D01*
X299167Y589500D01*
X299000Y590167D01*
X299167Y590833D01*
X299500Y591417D01*
X300000Y591750D01*
X300500Y591833D01*
X301000Y591750D01*
X301500Y591417D01*
X301833Y590833D01*
X301917Y590167D01*
X301833Y589500D01*
X301500Y588917D01*
X301000Y588583D01*
X300500Y588500D01*
G01X306100D02*
Y593500D01*
G01X310450Y590750D02*
X313117D01*
X312867Y591333D01*
X312450Y591667D01*
X311867Y591833D01*
X311283Y591750D01*
X310783Y591500D01*
X310450Y590917D01*
X310283Y590417D01*
Y589917D01*
X310450Y589417D01*
X310867Y588917D01*
X311367Y588583D01*
X311950Y588500D01*
X312533Y588667D01*
X313117Y589167D01*
G01X322900Y593500D02*
Y588500D01*
G01X321733Y591833D02*
X324067D01*
G01X328500Y588500D02*
X328000Y588583D01*
X327500Y588917D01*
X327167Y589500D01*
X327000Y590167D01*
X327167Y590833D01*
X327500Y591417D01*
X328000Y591750D01*
X328500Y591833D01*
X329000Y591750D01*
X329500Y591417D01*
X329833Y590833D01*
X329917Y590167D01*
X329833Y589500D01*
X329500Y588917D01*
X329000Y588583D01*
X328500Y588500D01*
G01X338283D02*
Y593500D01*
G01Y591083D02*
X338700Y591500D01*
X339117Y591750D01*
X339783Y591833D01*
X340283Y591750D01*
X340867Y591417D01*
X341117Y590917D01*
Y588500D01*
G01X345300D02*
X344800Y588583D01*
X344300Y588917D01*
X343967Y589500D01*
X343800Y590167D01*
X343967Y590833D01*
X344300Y591417D01*
X344800Y591750D01*
X345300Y591833D01*
X345800Y591750D01*
X346300Y591417D01*
X346633Y590833D01*
X346717Y590167D01*
X346633Y589500D01*
X346300Y588917D01*
X345800Y588583D01*
X345300Y588500D01*
G01X350900D02*
Y593500D01*
G01X355250Y590750D02*
X357917D01*
X357667Y591333D01*
X357250Y591667D01*
X356667Y591833D01*
X356083Y591750D01*
X355583Y591500D01*
X355250Y590917D01*
X355083Y590417D01*
Y589917D01*
X355250Y589417D01*
X355667Y588917D01*
X356167Y588583D01*
X356750Y588500D01*
X357333Y588667D01*
X357917Y589167D01*
G01X270917Y619000D02*
X273000Y624000D01*
X275083Y619000D01*
G01X274333Y620750D02*
X271667D01*
G01X277183Y619000D02*
Y622333D01*
G01Y621500D02*
X277517Y621917D01*
X278017Y622250D01*
X278683Y622333D01*
X279267Y622250D01*
X279767Y621917D01*
X280017Y621333D01*
Y619000D01*
G01X284200Y624000D02*
Y619000D01*
G01X283033Y622333D02*
X285367D01*
G01X289800D02*
Y619000D01*
G01Y623667D02*
X289633Y623750D01*
Y623917D01*
X289800Y624000D01*
X289967Y623917D01*
Y623750D01*
X289800Y623667D01*
G01X294317Y620667D02*
X296483D01*
G01X299500Y617333D02*
Y622333D01*
G01Y621583D02*
X299917Y622000D01*
X300333Y622250D01*
X301000Y622333D01*
X301583Y622250D01*
X302167Y621833D01*
X302417Y621250D01*
X302500Y620667D01*
X302417Y620083D01*
X302167Y619500D01*
X301667Y619167D01*
X301000Y619000D01*
X300417Y619083D01*
X299833Y619333D01*
X299500Y619667D01*
G01X308100Y619000D02*
Y622333D01*
G01Y621750D02*
X307767Y622083D01*
X307267Y622250D01*
X306683Y622333D01*
X306100Y622167D01*
X305600Y621833D01*
X305267Y621333D01*
X305100Y620667D01*
X305267Y620000D01*
X305600Y619500D01*
X306100Y619167D01*
X306683Y619000D01*
X307267Y619083D01*
X307767Y619333D01*
X308100Y619667D01*
G01X313700Y624000D02*
Y619000D01*
G01Y619750D02*
X313367Y619333D01*
X312867Y619083D01*
X312283Y619000D01*
X311617Y619167D01*
X311117Y619583D01*
X310783Y620083D01*
X310700Y620667D01*
X310783Y621250D01*
X311117Y621750D01*
X311617Y622167D01*
X312283Y622333D01*
X312867Y622250D01*
X313283Y622083D01*
X313700Y621750D01*
G01X322150Y619583D02*
X322567Y619250D01*
X323150Y619000D01*
X323650D01*
X324150Y619167D01*
X324483Y619417D01*
X324650Y619750D01*
X324567Y620250D01*
X324233Y620500D01*
X322733Y621000D01*
X322400Y621583D01*
X322567Y622000D01*
X322900Y622250D01*
X323400Y622333D01*
X323900Y622250D01*
X324400Y622000D01*
G01X329000Y622333D02*
Y619000D01*
G01Y623667D02*
X328833Y623750D01*
Y623917D01*
X329000Y624000D01*
X329167Y623917D01*
Y623750D01*
X329000Y623667D01*
G01X333350Y622333D02*
X335850D01*
X333350Y619000D01*
X335850D01*
G01X338950Y621250D02*
X341617D01*
X341367Y621833D01*
X340950Y622167D01*
X340367Y622333D01*
X339783Y622250D01*
X339283Y622000D01*
X338950Y621417D01*
X338783Y620917D01*
Y620417D01*
X338950Y619917D01*
X339367Y619417D01*
X339867Y619083D01*
X340450Y619000D01*
X341033Y619167D01*
X341617Y619667D01*
G01X269717Y637573D02*
X270717Y634240D01*
X271800Y637573D01*
X272883Y634240D01*
X273883Y637573D01*
G01X277400D02*
Y634240D01*
G01Y638907D02*
X277233Y638990D01*
Y639157D01*
X277400Y639240D01*
X277567Y639157D01*
Y638990D01*
X277400Y638907D01*
G01X283000Y639240D02*
Y634240D01*
G01X281833Y637573D02*
X284167D01*
G01X287183Y634240D02*
Y639240D01*
G01Y636823D02*
X287600Y637240D01*
X288017Y637490D01*
X288683Y637573D01*
X289183Y637490D01*
X289767Y637157D01*
X290017Y636657D01*
Y634240D01*
G01X294200D02*
X293700Y634323D01*
X293200Y634657D01*
X292867Y635240D01*
X292700Y635907D01*
X292867Y636573D01*
X293200Y637157D01*
X293700Y637490D01*
X294200Y637573D01*
X294700Y637490D01*
X295200Y637157D01*
X295533Y636573D01*
X295617Y635907D01*
X295533Y635240D01*
X295200Y634657D01*
X294700Y634323D01*
X294200Y634240D01*
G01X298383Y637573D02*
Y635240D01*
X298717Y634657D01*
X299217Y634323D01*
X299800Y634240D01*
X300383Y634323D01*
X300883Y634657D01*
X301217Y635240D01*
G01Y634240D02*
Y637573D01*
G01X305400Y639240D02*
Y634240D01*
G01X304233Y637573D02*
X306567D01*
G01X317933Y637157D02*
X317350Y637490D01*
X316850Y637573D01*
X316183Y637407D01*
X315683Y637073D01*
X315350Y636490D01*
X315267Y635907D01*
X315350Y635323D01*
X315683Y634823D01*
X316183Y634407D01*
X316850Y634240D01*
X317433Y634407D01*
X317933Y634740D01*
G01X322200Y634240D02*
X321700Y634323D01*
X321200Y634657D01*
X320867Y635240D01*
X320700Y635907D01*
X320867Y636573D01*
X321200Y637157D01*
X321700Y637490D01*
X322200Y637573D01*
X322700Y637490D01*
X323200Y637157D01*
X323533Y636573D01*
X323617Y635907D01*
X323533Y635240D01*
X323200Y634657D01*
X322700Y634323D01*
X322200Y634240D01*
G01X326383D02*
Y637573D01*
G01Y636740D02*
X326717Y637157D01*
X327217Y637490D01*
X327883Y637573D01*
X328467Y637490D01*
X328967Y637157D01*
X329217Y636573D01*
Y634240D01*
G01X331983D02*
Y637573D01*
G01Y636740D02*
X332317Y637157D01*
X332817Y637490D01*
X333483Y637573D01*
X334067Y637490D01*
X334567Y637157D01*
X334817Y636573D01*
Y634240D01*
G01X337750Y636490D02*
X340417D01*
X340167Y637073D01*
X339750Y637407D01*
X339167Y637573D01*
X338583Y637490D01*
X338083Y637240D01*
X337750Y636657D01*
X337583Y636157D01*
Y635657D01*
X337750Y635157D01*
X338167Y634657D01*
X338667Y634323D01*
X339250Y634240D01*
X339833Y634407D01*
X340417Y634907D01*
G01X345933Y637157D02*
X345350Y637490D01*
X344850Y637573D01*
X344183Y637407D01*
X343683Y637073D01*
X343350Y636490D01*
X343267Y635907D01*
X343350Y635323D01*
X343683Y634823D01*
X344183Y634407D01*
X344850Y634240D01*
X345433Y634407D01*
X345933Y634740D01*
G01X350200Y639240D02*
Y634240D01*
G01X349033Y637573D02*
X351367D01*
G01X355800D02*
Y634240D01*
G01Y638907D02*
X355633Y638990D01*
Y639157D01*
X355800Y639240D01*
X355967Y639157D01*
Y638990D01*
X355800Y638907D01*
G01X359983Y634240D02*
Y637573D01*
G01Y636740D02*
X360317Y637157D01*
X360817Y637490D01*
X361483Y637573D01*
X362067Y637490D01*
X362567Y637157D01*
X362817Y636573D01*
Y634240D01*
G01X365833Y632990D02*
X366417Y632657D01*
X367083Y632573D01*
X367667Y632657D01*
X368167Y633073D01*
X368500Y633657D01*
Y637573D01*
G01Y636907D02*
X368167Y637240D01*
X367667Y637490D01*
X367083Y637573D01*
X366417Y637407D01*
X366000Y637073D01*
X365667Y636490D01*
X365500Y635907D01*
X365583Y635407D01*
X365917Y634823D01*
X366417Y634407D01*
X367083Y634240D01*
X367583Y634323D01*
X368167Y634657D01*
X368500Y634990D01*
G01X378200Y639240D02*
Y634240D01*
G01X377033Y637573D02*
X379367D01*
G01X383800Y634240D02*
X383300Y634323D01*
X382800Y634657D01*
X382467Y635240D01*
X382300Y635907D01*
X382467Y636573D01*
X382800Y637157D01*
X383300Y637490D01*
X383800Y637573D01*
X384300Y637490D01*
X384800Y637157D01*
X385133Y636573D01*
X385217Y635907D01*
X385133Y635240D01*
X384800Y634657D01*
X384300Y634323D01*
X383800Y634240D01*
G01X395000D02*
X394500Y634323D01*
X394000Y634657D01*
X393667Y635240D01*
X393500Y635907D01*
X393667Y636573D01*
X394000Y637157D01*
X394500Y637490D01*
X395000Y637573D01*
X395500Y637490D01*
X396000Y637157D01*
X396333Y636573D01*
X396417Y635907D01*
X396333Y635240D01*
X396000Y634657D01*
X395500Y634323D01*
X395000Y634240D01*
G01X400600Y639240D02*
Y634240D01*
G01X399433Y637573D02*
X401767D01*
G01X404783Y634240D02*
Y639240D01*
G01Y636823D02*
X405200Y637240D01*
X405617Y637490D01*
X406283Y637573D01*
X406783Y637490D01*
X407367Y637157D01*
X407617Y636657D01*
Y634240D01*
G01X410550Y636490D02*
X413217D01*
X412967Y637073D01*
X412550Y637407D01*
X411967Y637573D01*
X411383Y637490D01*
X410883Y637240D01*
X410550Y636657D01*
X410383Y636157D01*
Y635657D01*
X410550Y635157D01*
X410967Y634657D01*
X411467Y634323D01*
X412050Y634240D01*
X412633Y634407D01*
X413217Y634907D01*
G01X416233Y634240D02*
Y637573D01*
G01Y636907D02*
X416650Y637240D01*
X417067Y637490D01*
X417650Y637573D01*
X418067Y637490D01*
X418567Y637240D01*
G01X428600Y634240D02*
Y639240D01*
G01X435700Y634240D02*
Y637573D01*
G01Y636990D02*
X435367Y637323D01*
X434867Y637490D01*
X434283Y637573D01*
X433700Y637407D01*
X433200Y637073D01*
X432867Y636573D01*
X432700Y635907D01*
X432867Y635240D01*
X433200Y634740D01*
X433700Y634407D01*
X434283Y634240D01*
X434867Y634323D01*
X435367Y634573D01*
X435700Y634907D01*
G01X438050Y632740D02*
X438550Y632573D01*
X439217Y632740D01*
X439633Y633073D01*
X439967Y633490D01*
X440467Y634823D01*
X441550Y637573D01*
G01X438883D02*
X440467Y634823D01*
G01X444150Y636490D02*
X446817D01*
X446567Y637073D01*
X446150Y637407D01*
X445567Y637573D01*
X444983Y637490D01*
X444483Y637240D01*
X444150Y636657D01*
X443983Y636157D01*
Y635657D01*
X444150Y635157D01*
X444567Y634657D01*
X445067Y634323D01*
X445650Y634240D01*
X446233Y634407D01*
X446817Y634907D01*
G01X449833Y634240D02*
Y637573D01*
G01Y636907D02*
X450250Y637240D01*
X450667Y637490D01*
X451250Y637573D01*
X451667Y637490D01*
X452167Y637240D01*
G01X455350Y634823D02*
X455767Y634490D01*
X456350Y634240D01*
X456850D01*
X457350Y634407D01*
X457683Y634657D01*
X457850Y634990D01*
X457767Y635490D01*
X457433Y635740D01*
X455933Y636240D01*
X455600Y636823D01*
X455767Y637240D01*
X456100Y637490D01*
X456600Y637573D01*
X457100Y637490D01*
X457600Y637240D01*
G01X462617Y632573D02*
X463450Y633407D01*
X463867Y634240D01*
Y637573D01*
X463450Y638407D01*
X462617Y639240D01*
G01X270833Y575000D02*
Y580000D01*
X272833D01*
X273500Y579750D01*
X274000Y579167D01*
X274167Y578500D01*
X274000Y577833D01*
X273583Y577333D01*
X272833Y577083D01*
X270833D01*
G01X278100Y575000D02*
Y580000D01*
G01X282283Y578333D02*
Y576000D01*
X282617Y575417D01*
X283117Y575083D01*
X283700Y575000D01*
X284283Y575083D01*
X284783Y575417D01*
X285117Y576000D01*
G01Y575000D02*
Y578333D01*
G01X288133Y573750D02*
X288717Y573417D01*
X289383Y573333D01*
X289967Y573417D01*
X290467Y573833D01*
X290800Y574417D01*
Y578333D01*
G01Y577667D02*
X290467Y578000D01*
X289967Y578250D01*
X289383Y578333D01*
X288717Y578167D01*
X288300Y577833D01*
X287967Y577250D01*
X287800Y576667D01*
X287883Y576167D01*
X288217Y575583D01*
X288717Y575167D01*
X289383Y575000D01*
X289883Y575083D01*
X290467Y575417D01*
X290800Y575750D01*
G01X293733Y573750D02*
X294317Y573417D01*
X294983Y573333D01*
X295567Y573417D01*
X296067Y573833D01*
X296400Y574417D01*
Y578333D01*
G01Y577667D02*
X296067Y578000D01*
X295567Y578250D01*
X294983Y578333D01*
X294317Y578167D01*
X293900Y577833D01*
X293567Y577250D01*
X293400Y576667D01*
X293483Y576167D01*
X293817Y575583D01*
X294317Y575167D01*
X294983Y575000D01*
X295483Y575083D01*
X296067Y575417D01*
X296400Y575750D01*
G01X299250Y577250D02*
X301917D01*
X301667Y577833D01*
X301250Y578167D01*
X300667Y578333D01*
X300083Y578250D01*
X299583Y578000D01*
X299250Y577417D01*
X299083Y576917D01*
Y576417D01*
X299250Y575917D01*
X299667Y575417D01*
X300167Y575083D01*
X300750Y575000D01*
X301333Y575167D01*
X301917Y575667D01*
G01X307600Y580000D02*
Y575000D01*
G01Y575750D02*
X307267Y575333D01*
X306767Y575083D01*
X306183Y575000D01*
X305517Y575167D01*
X305017Y575583D01*
X304683Y576083D01*
X304600Y576667D01*
X304683Y577250D01*
X305017Y577750D01*
X305517Y578167D01*
X306183Y578333D01*
X306767Y578250D01*
X307183Y578083D01*
X307600Y577750D01*
G01X315217Y580000D02*
X317300Y575000D01*
X319383Y580000D01*
G01X322900Y578333D02*
Y575000D01*
G01Y579667D02*
X322733Y579750D01*
Y579917D01*
X322900Y580000D01*
X323067Y579917D01*
Y579750D01*
X322900Y579667D01*
G01X330000Y575000D02*
Y578333D01*
G01Y577750D02*
X329667Y578083D01*
X329167Y578250D01*
X328583Y578333D01*
X328000Y578167D01*
X327500Y577833D01*
X327167Y577333D01*
X327000Y576667D01*
X327167Y576000D01*
X327500Y575500D01*
X328000Y575167D01*
X328583Y575000D01*
X329167Y575083D01*
X329667Y575333D01*
X330000Y575667D01*
G01X333683Y573333D02*
X332850Y574167D01*
X332433Y575000D01*
Y578333D01*
X332850Y579167D01*
X333683Y580000D01*
G01X338283Y575000D02*
Y580000D01*
G01Y577583D02*
X338700Y578000D01*
X339117Y578250D01*
X339783Y578333D01*
X340283Y578250D01*
X340867Y577917D01*
X341117Y577417D01*
Y575000D01*
G01X345300D02*
X344800Y575083D01*
X344300Y575417D01*
X343967Y576000D01*
X343800Y576667D01*
X343967Y577333D01*
X344300Y577917D01*
X344800Y578250D01*
X345300Y578333D01*
X345800Y578250D01*
X346300Y577917D01*
X346633Y577333D01*
X346717Y576667D01*
X346633Y576000D01*
X346300Y575417D01*
X345800Y575083D01*
X345300Y575000D01*
G01X350900D02*
Y580000D01*
G01X355250Y577250D02*
X357917D01*
X357667Y577833D01*
X357250Y578167D01*
X356667Y578333D01*
X356083Y578250D01*
X355583Y578000D01*
X355250Y577417D01*
X355083Y576917D01*
Y576417D01*
X355250Y575917D01*
X355667Y575417D01*
X356167Y575083D01*
X356750Y575000D01*
X357333Y575167D01*
X357917Y575667D01*
G01X366450Y575583D02*
X366867Y575250D01*
X367450Y575000D01*
X367950D01*
X368450Y575167D01*
X368783Y575417D01*
X368950Y575750D01*
X368867Y576250D01*
X368533Y576500D01*
X367033Y577000D01*
X366700Y577583D01*
X366867Y578000D01*
X367200Y578250D01*
X367700Y578333D01*
X368200Y578250D01*
X368700Y578000D01*
G01X373300Y578333D02*
Y575000D01*
G01Y579667D02*
X373133Y579750D01*
Y579917D01*
X373300Y580000D01*
X373467Y579917D01*
Y579750D01*
X373300Y579667D01*
G01X377650Y578333D02*
X380150D01*
X377650Y575000D01*
X380150D01*
G01X383250Y577250D02*
X385917D01*
X385667Y577833D01*
X385250Y578167D01*
X384667Y578333D01*
X384083Y578250D01*
X383583Y578000D01*
X383250Y577417D01*
X383083Y576917D01*
Y576417D01*
X383250Y575917D01*
X383667Y575417D01*
X384167Y575083D01*
X384750Y575000D01*
X385333Y575167D01*
X385917Y575667D01*
G01X391767Y575000D02*
X388433Y576667D01*
X391767Y578333D01*
G01X395700Y575000D02*
Y580000D01*
X394700Y579000D01*
G01Y575000D02*
X396700D01*
G01X399717Y577083D02*
X400300Y577667D01*
X400800Y578000D01*
X401467Y578167D01*
X402050Y578000D01*
X402467Y577667D01*
X402800Y577167D01*
X402883Y576583D01*
X402800Y576083D01*
X402467Y575583D01*
X401967Y575167D01*
X401383Y575000D01*
X400717Y575167D01*
X400133Y575667D01*
X399800Y576417D01*
X399717Y577250D01*
X399883Y578333D01*
X400133Y578917D01*
X400550Y579500D01*
X401133Y579917D01*
X401717Y580000D01*
X402300Y579833D01*
X402717Y579417D01*
G01X410000Y575000D02*
Y578333D01*
G01Y577417D02*
X410250Y577833D01*
X410667Y578167D01*
X411250Y578333D01*
X411833Y578167D01*
X412250Y577833D01*
X412500Y577417D01*
Y575000D01*
G01Y577417D02*
X412750Y577833D01*
X413167Y578167D01*
X413750Y578333D01*
X414333Y578167D01*
X414750Y577833D01*
X415000Y577333D01*
Y575000D01*
G01X418100Y578333D02*
Y575000D01*
G01Y579667D02*
X417933Y579750D01*
Y579917D01*
X418100Y580000D01*
X418267Y579917D01*
Y579750D01*
X418100Y579667D01*
G01X423700Y575000D02*
Y580000D01*
G01X429717Y573333D02*
X430550Y574167D01*
X430967Y575000D01*
Y578333D01*
X430550Y579167D01*
X429717Y580000D01*
G01X262500Y569000D02*
X694500D01*
G01X270257Y644950D02*
Y649950D01*
X271923D01*
X272590Y649700D01*
X273090Y649367D01*
X273507Y648867D01*
X273840Y648283D01*
X273923Y647450D01*
X273840Y646617D01*
X273507Y646033D01*
X273090Y645533D01*
X272590Y645200D01*
X271923Y644950D01*
X270257D01*
G01X276440Y647200D02*
X279107D01*
X278857Y647783D01*
X278440Y648117D01*
X277857Y648283D01*
X277273Y648200D01*
X276773Y647950D01*
X276440Y647367D01*
X276273Y646867D01*
Y646367D01*
X276440Y645867D01*
X276857Y645367D01*
X277357Y645033D01*
X277940Y644950D01*
X278523Y645117D01*
X279107Y645617D01*
G01X283290Y644950D02*
Y649950D01*
G01X287640Y647200D02*
X290307D01*
X290057Y647783D01*
X289640Y648117D01*
X289057Y648283D01*
X288473Y648200D01*
X287973Y647950D01*
X287640Y647367D01*
X287473Y646867D01*
Y646367D01*
X287640Y645867D01*
X288057Y645367D01*
X288557Y645033D01*
X289140Y644950D01*
X289723Y645117D01*
X290307Y645617D01*
G01X294490Y649950D02*
Y644950D01*
G01X293323Y648283D02*
X295657D01*
G01X298840Y647200D02*
X301507D01*
X301257Y647783D01*
X300840Y648117D01*
X300257Y648283D01*
X299673Y648200D01*
X299173Y647950D01*
X298840Y647367D01*
X298673Y646867D01*
Y646367D01*
X298840Y645867D01*
X299257Y645367D01*
X299757Y645033D01*
X300340Y644950D01*
X300923Y645117D01*
X301507Y645617D01*
G01X309873Y644950D02*
Y648283D01*
G01Y647450D02*
X310207Y647867D01*
X310707Y648200D01*
X311373Y648283D01*
X311957Y648200D01*
X312457Y647867D01*
X312707Y647283D01*
Y644950D01*
G01X316890D02*
X316390Y645033D01*
X315890Y645367D01*
X315557Y645950D01*
X315390Y646617D01*
X315557Y647283D01*
X315890Y647867D01*
X316390Y648200D01*
X316890Y648283D01*
X317390Y648200D01*
X317890Y647867D01*
X318223Y647283D01*
X318307Y646617D01*
X318223Y645950D01*
X317890Y645367D01*
X317390Y645033D01*
X316890Y644950D01*
G01X321073D02*
Y648283D01*
G01Y647450D02*
X321407Y647867D01*
X321907Y648200D01*
X322573Y648283D01*
X323157Y648200D01*
X323657Y647867D01*
X323907Y647283D01*
Y644950D01*
G01X327007Y646617D02*
X329173D01*
G01X333190Y644950D02*
Y649200D01*
X333357Y649617D01*
X333690Y649867D01*
X334190Y649950D01*
X334690Y649783D01*
X334940Y649367D01*
G01X333940Y647950D02*
X332273D01*
G01X337873Y648283D02*
Y645950D01*
X338207Y645367D01*
X338707Y645033D01*
X339290Y644950D01*
X339873Y645033D01*
X340373Y645367D01*
X340707Y645950D01*
G01Y644950D02*
Y648283D01*
G01X343473Y644950D02*
Y648283D01*
G01Y647450D02*
X343807Y647867D01*
X344307Y648200D01*
X344973Y648283D01*
X345557Y648200D01*
X346057Y647867D01*
X346307Y647283D01*
Y644950D01*
G01X351823Y647867D02*
X351240Y648200D01*
X350740Y648283D01*
X350073Y648117D01*
X349573Y647783D01*
X349240Y647200D01*
X349157Y646617D01*
X349240Y646033D01*
X349573Y645533D01*
X350073Y645117D01*
X350740Y644950D01*
X351323Y645117D01*
X351823Y645450D01*
G01X356090Y649950D02*
Y644950D01*
G01X354923Y648283D02*
X357257D01*
G01X361690D02*
Y644950D01*
G01Y649617D02*
X361523Y649700D01*
Y649867D01*
X361690Y649950D01*
X361857Y649867D01*
Y649700D01*
X361690Y649617D01*
G01X367290Y644950D02*
X366790Y645033D01*
X366290Y645367D01*
X365957Y645950D01*
X365790Y646617D01*
X365957Y647283D01*
X366290Y647867D01*
X366790Y648200D01*
X367290Y648283D01*
X367790Y648200D01*
X368290Y647867D01*
X368623Y647283D01*
X368707Y646617D01*
X368623Y645950D01*
X368290Y645367D01*
X367790Y645033D01*
X367290Y644950D01*
G01X371473D02*
Y648283D01*
G01Y647450D02*
X371807Y647867D01*
X372307Y648200D01*
X372973Y648283D01*
X373557Y648200D01*
X374057Y647867D01*
X374307Y647283D01*
Y644950D01*
G01X379990D02*
Y648283D01*
G01Y647700D02*
X379657Y648033D01*
X379157Y648200D01*
X378573Y648283D01*
X377990Y648117D01*
X377490Y647783D01*
X377157Y647283D01*
X376990Y646617D01*
X377157Y645950D01*
X377490Y645450D01*
X377990Y645117D01*
X378573Y644950D01*
X379157Y645033D01*
X379657Y645283D01*
X379990Y645617D01*
G01X384090Y644950D02*
Y649950D01*
G01X393790Y643283D02*
Y648283D01*
G01Y647533D02*
X394207Y647950D01*
X394623Y648200D01*
X395290Y648283D01*
X395873Y648200D01*
X396457Y647783D01*
X396707Y647200D01*
X396790Y646617D01*
X396707Y646033D01*
X396457Y645450D01*
X395957Y645117D01*
X395290Y644950D01*
X394707Y645033D01*
X394123Y645283D01*
X393790Y645617D01*
G01X402390Y644950D02*
Y648283D01*
G01Y647700D02*
X402057Y648033D01*
X401557Y648200D01*
X400973Y648283D01*
X400390Y648117D01*
X399890Y647783D01*
X399557Y647283D01*
X399390Y646617D01*
X399557Y645950D01*
X399890Y645450D01*
X400390Y645117D01*
X400973Y644950D01*
X401557Y645033D01*
X402057Y645283D01*
X402390Y645617D01*
G01X407990Y649950D02*
Y644950D01*
G01Y645700D02*
X407657Y645283D01*
X407157Y645033D01*
X406573Y644950D01*
X405907Y645117D01*
X405407Y645533D01*
X405073Y646033D01*
X404990Y646617D01*
X405073Y647200D01*
X405407Y647700D01*
X405907Y648117D01*
X406573Y648283D01*
X407157Y648200D01*
X407573Y648033D01*
X407990Y647700D01*
G01X417690Y648283D02*
Y644950D01*
G01Y649617D02*
X417523Y649700D01*
Y649867D01*
X417690Y649950D01*
X417857Y649867D01*
Y649700D01*
X417690Y649617D01*
G01X421873Y644950D02*
Y648283D01*
G01Y647450D02*
X422207Y647867D01*
X422707Y648200D01*
X423373Y648283D01*
X423957Y648200D01*
X424457Y647867D01*
X424707Y647283D01*
Y644950D01*
G01X435990D02*
Y648283D01*
G01Y647700D02*
X435657Y648033D01*
X435157Y648200D01*
X434573Y648283D01*
X433990Y648117D01*
X433490Y647783D01*
X433157Y647283D01*
X432990Y646617D01*
X433157Y645950D01*
X433490Y645450D01*
X433990Y645117D01*
X434573Y644950D01*
X435157Y645033D01*
X435657Y645283D01*
X435990Y645617D01*
G01X440090Y644950D02*
Y649950D01*
G01X445690Y644950D02*
Y649950D01*
G01X455390Y643283D02*
Y648283D01*
G01Y647533D02*
X455807Y647950D01*
X456223Y648200D01*
X456890Y648283D01*
X457473Y648200D01*
X458057Y647783D01*
X458307Y647200D01*
X458390Y646617D01*
X458307Y646033D01*
X458057Y645450D01*
X457557Y645117D01*
X456890Y644950D01*
X456307Y645033D01*
X455723Y645283D01*
X455390Y645617D01*
G01X461323Y644950D02*
Y648283D01*
G01Y647617D02*
X461740Y647950D01*
X462157Y648200D01*
X462740Y648283D01*
X463157Y648200D01*
X463657Y647950D01*
G01X468090Y644950D02*
X467590Y645033D01*
X467090Y645367D01*
X466757Y645950D01*
X466590Y646617D01*
X466757Y647283D01*
X467090Y647867D01*
X467590Y648200D01*
X468090Y648283D01*
X468590Y648200D01*
X469090Y647867D01*
X469423Y647283D01*
X469507Y646617D01*
X469423Y645950D01*
X469090Y645367D01*
X468590Y645033D01*
X468090Y644950D01*
G01X475190Y649950D02*
Y644950D01*
G01Y645700D02*
X474857Y645283D01*
X474357Y645033D01*
X473773Y644950D01*
X473107Y645117D01*
X472607Y645533D01*
X472273Y646033D01*
X472190Y646617D01*
X472273Y647200D01*
X472607Y647700D01*
X473107Y648117D01*
X473773Y648283D01*
X474357Y648200D01*
X474773Y648033D01*
X475190Y647700D01*
G01X477873Y648283D02*
Y645950D01*
X478207Y645367D01*
X478707Y645033D01*
X479290Y644950D01*
X479873Y645033D01*
X480373Y645367D01*
X480707Y645950D01*
G01Y644950D02*
Y648283D01*
G01X486223Y647867D02*
X485640Y648200D01*
X485140Y648283D01*
X484473Y648117D01*
X483973Y647783D01*
X483640Y647200D01*
X483557Y646617D01*
X483640Y646033D01*
X483973Y645533D01*
X484473Y645117D01*
X485140Y644950D01*
X485723Y645117D01*
X486223Y645450D01*
G01X490490Y649950D02*
Y644950D01*
G01X489323Y648283D02*
X491657D01*
G01X494840Y645533D02*
X495257Y645200D01*
X495840Y644950D01*
X496340D01*
X496840Y645117D01*
X497173Y645367D01*
X497340Y645700D01*
X497257Y646200D01*
X496923Y646450D01*
X495423Y646950D01*
X495090Y647533D01*
X495257Y647950D01*
X495590Y648200D01*
X496090Y648283D01*
X496590Y648200D01*
X497090Y647950D01*
G01X501690Y644783D02*
X501523Y644867D01*
Y645033D01*
X501690Y645117D01*
X501857Y645033D01*
Y644867D01*
X501690Y644783D01*
G01X506873Y643283D02*
X506040Y644117D01*
X505623Y644950D01*
Y648283D01*
X506040Y649117D01*
X506873Y649950D01*
G01X511890D02*
X513890D01*
G01X512890D02*
Y644950D01*
G01X511890D02*
X513890D01*
G01X517240Y645533D02*
X517657Y645200D01*
X518240Y644950D01*
X518740D01*
X519240Y645117D01*
X519573Y645367D01*
X519740Y645700D01*
X519657Y646200D01*
X519323Y646450D01*
X517823Y646950D01*
X517490Y647533D01*
X517657Y647950D01*
X517990Y648200D01*
X518490Y648283D01*
X518990Y648200D01*
X519490Y647950D01*
G01X524090Y644950D02*
X523590Y645033D01*
X523090Y645367D01*
X522757Y645950D01*
X522590Y646617D01*
X522757Y647283D01*
X523090Y647867D01*
X523590Y648200D01*
X524090Y648283D01*
X524590Y648200D01*
X525090Y647867D01*
X525423Y647283D01*
X525507Y646617D01*
X525423Y645950D01*
X525090Y645367D01*
X524590Y645033D01*
X524090Y644950D01*
G01X529690D02*
Y649950D01*
G01X536790Y644950D02*
Y648283D01*
G01Y647700D02*
X536457Y648033D01*
X535957Y648200D01*
X535373Y648283D01*
X534790Y648117D01*
X534290Y647783D01*
X533957Y647283D01*
X533790Y646617D01*
X533957Y645950D01*
X534290Y645450D01*
X534790Y645117D01*
X535373Y644950D01*
X535957Y645033D01*
X536457Y645283D01*
X536790Y645617D01*
G01X540890Y649950D02*
Y644950D01*
G01X539723Y648283D02*
X542057D01*
G01X545240Y647200D02*
X547907D01*
X547657Y647783D01*
X547240Y648117D01*
X546657Y648283D01*
X546073Y648200D01*
X545573Y647950D01*
X545240Y647367D01*
X545073Y646867D01*
Y646367D01*
X545240Y645867D01*
X545657Y645367D01*
X546157Y645033D01*
X546740Y644950D01*
X547323Y645117D01*
X547907Y645617D01*
G01X556190Y643283D02*
Y648283D01*
G01Y647533D02*
X556607Y647950D01*
X557023Y648200D01*
X557690Y648283D01*
X558273Y648200D01*
X558857Y647783D01*
X559107Y647200D01*
X559190Y646617D01*
X559107Y646033D01*
X558857Y645450D01*
X558357Y645117D01*
X557690Y644950D01*
X557107Y645033D01*
X556523Y645283D01*
X556190Y645617D01*
G01X564790Y644950D02*
Y648283D01*
G01Y647700D02*
X564457Y648033D01*
X563957Y648200D01*
X563373Y648283D01*
X562790Y648117D01*
X562290Y647783D01*
X561957Y647283D01*
X561790Y646617D01*
X561957Y645950D01*
X562290Y645450D01*
X562790Y645117D01*
X563373Y644950D01*
X563957Y645033D01*
X564457Y645283D01*
X564790Y645617D01*
G01X570390Y649950D02*
Y644950D01*
G01Y645700D02*
X570057Y645283D01*
X569557Y645033D01*
X568973Y644950D01*
X568307Y645117D01*
X567807Y645533D01*
X567473Y646033D01*
X567390Y646617D01*
X567473Y647200D01*
X567807Y647700D01*
X568307Y648117D01*
X568973Y648283D01*
X569557Y648200D01*
X569973Y648033D01*
X570390Y647700D01*
G01X322623Y303963D02*
X322890Y304163D01*
X323090Y304497D01*
X323223Y304963D01*
X323090Y305363D01*
X322823Y305630D01*
X322357Y305830D01*
X320557D01*
Y301830D01*
X322757D01*
X323223Y302097D01*
X323490Y302497D01*
X323623Y302963D01*
X323490Y303430D01*
X323090Y303830D01*
X322623Y303963D01*
X320557D01*
G01X320423Y351330D02*
X322090Y355330D01*
X323757Y351330D01*
G01X323157Y352730D02*
X321023D01*
G01X395000Y364500D02*
Y175500D01*
G01X402977Y229887D02*
X403310Y230137D01*
X403560Y230553D01*
X403727Y231137D01*
X403560Y231637D01*
X403227Y231970D01*
X402643Y232220D01*
X400393D01*
Y227220D01*
X403143D01*
X403727Y227553D01*
X404060Y228053D01*
X404227Y228637D01*
X404060Y229220D01*
X403560Y229720D01*
X402977Y229887D01*
X400393D01*
G01X406493Y230553D02*
Y228220D01*
X406827Y227637D01*
X407327Y227303D01*
X407910Y227220D01*
X408493Y227303D01*
X408993Y227637D01*
X409327Y228220D01*
G01Y227220D02*
Y230553D01*
G01X411010Y227220D02*
Y230553D01*
G01Y229637D02*
X411260Y230053D01*
X411677Y230387D01*
X412260Y230553D01*
X412843Y230387D01*
X413260Y230053D01*
X413510Y229637D01*
Y227220D01*
G01Y229637D02*
X413760Y230053D01*
X414177Y230387D01*
X414760Y230553D01*
X415343Y230387D01*
X415760Y230053D01*
X416010Y229553D01*
Y227220D01*
G01X417610Y225553D02*
Y230553D01*
G01Y229803D02*
X418027Y230220D01*
X418443Y230470D01*
X419110Y230553D01*
X419693Y230470D01*
X420277Y230053D01*
X420527Y229470D01*
X420610Y228887D01*
X420527Y228303D01*
X420277Y227720D01*
X419777Y227387D01*
X419110Y227220D01*
X418527Y227303D01*
X417943Y227553D01*
X417610Y227887D01*
G01X401520Y268213D02*
X403020Y264880D01*
X404520Y268213D01*
G01X408620D02*
Y264880D01*
G01Y269547D02*
X408453Y269630D01*
Y269797D01*
X408620Y269880D01*
X408787Y269797D01*
Y269630D01*
X408620Y269547D01*
G01X415720Y264880D02*
Y268213D01*
G01Y267630D02*
X415387Y267963D01*
X414887Y268130D01*
X414303Y268213D01*
X413720Y268047D01*
X413220Y267713D01*
X412887Y267213D01*
X412720Y266547D01*
X412887Y265880D01*
X413220Y265380D01*
X413720Y265047D01*
X414303Y264880D01*
X414887Y264963D01*
X415387Y265213D01*
X415720Y265547D01*
G01X401067Y277360D02*
Y282360D01*
X402733D01*
X403400Y282110D01*
X403900Y281777D01*
X404317Y281277D01*
X404650Y280693D01*
X404733Y279860D01*
X404650Y279027D01*
X404317Y278443D01*
X403900Y277943D01*
X403400Y277610D01*
X402733Y277360D01*
X401067D01*
G01X408500Y280693D02*
Y277360D01*
G01Y282027D02*
X408333Y282110D01*
Y282277D01*
X408500Y282360D01*
X408667Y282277D01*
Y282110D01*
X408500Y282027D01*
G01X411600Y277360D02*
Y280693D01*
G01Y279777D02*
X411850Y280193D01*
X412267Y280527D01*
X412850Y280693D01*
X413433Y280527D01*
X413850Y280193D01*
X414100Y279777D01*
Y277360D01*
G01Y279777D02*
X414350Y280193D01*
X414767Y280527D01*
X415350Y280693D01*
X415933Y280527D01*
X416350Y280193D01*
X416600Y279693D01*
Y277360D01*
G01X418200Y275693D02*
Y280693D01*
G01Y279943D02*
X418617Y280360D01*
X419033Y280610D01*
X419700Y280693D01*
X420283Y280610D01*
X420867Y280193D01*
X421117Y279610D01*
X421200Y279027D01*
X421117Y278443D01*
X420867Y277860D01*
X420367Y277527D01*
X419700Y277360D01*
X419117Y277443D01*
X418533Y277693D01*
X418200Y278027D01*
G01X425300Y277360D02*
Y282360D01*
G01X429650Y279610D02*
X432317D01*
X432067Y280193D01*
X431650Y280527D01*
X431067Y280693D01*
X430483Y280610D01*
X429983Y280360D01*
X429650Y279777D01*
X429483Y279277D01*
Y278777D01*
X429650Y278277D01*
X430067Y277777D01*
X430567Y277443D01*
X431150Y277360D01*
X431733Y277527D01*
X432317Y278027D01*
G01X441600Y277360D02*
Y281610D01*
X441767Y282027D01*
X442100Y282277D01*
X442600Y282360D01*
X443100Y282193D01*
X443350Y281777D01*
G01X442350Y280360D02*
X440683D01*
G01X447700Y277360D02*
X447200Y277443D01*
X446700Y277777D01*
X446367Y278360D01*
X446200Y279027D01*
X446367Y279693D01*
X446700Y280277D01*
X447200Y280610D01*
X447700Y280693D01*
X448200Y280610D01*
X448700Y280277D01*
X449033Y279693D01*
X449117Y279027D01*
X449033Y278360D01*
X448700Y277777D01*
X448200Y277443D01*
X447700Y277360D01*
G01X452133D02*
Y280693D01*
G01Y280027D02*
X452550Y280360D01*
X452967Y280610D01*
X453550Y280693D01*
X453967Y280610D01*
X454467Y280360D01*
G01X464500Y277360D02*
X464000Y277443D01*
X463500Y277777D01*
X463167Y278360D01*
X463000Y279027D01*
X463167Y279693D01*
X463500Y280277D01*
X464000Y280610D01*
X464500Y280693D01*
X465000Y280610D01*
X465500Y280277D01*
X465833Y279693D01*
X465917Y279027D01*
X465833Y278360D01*
X465500Y277777D01*
X465000Y277443D01*
X464500Y277360D01*
G01X468683Y280693D02*
Y278360D01*
X469017Y277777D01*
X469517Y277443D01*
X470100Y277360D01*
X470683Y277443D01*
X471183Y277777D01*
X471517Y278360D01*
G01Y277360D02*
Y280693D01*
G01X475700Y282360D02*
Y277360D01*
G01X474533Y280693D02*
X476867D01*
G01X480050Y279610D02*
X482717D01*
X482467Y280193D01*
X482050Y280527D01*
X481467Y280693D01*
X480883Y280610D01*
X480383Y280360D01*
X480050Y279777D01*
X479883Y279277D01*
Y278777D01*
X480050Y278277D01*
X480467Y277777D01*
X480967Y277443D01*
X481550Y277360D01*
X482133Y277527D01*
X482717Y278027D01*
G01X485733Y277360D02*
Y280693D01*
G01Y280027D02*
X486150Y280360D01*
X486567Y280610D01*
X487150Y280693D01*
X487567Y280610D01*
X488067Y280360D01*
G01X499600Y277360D02*
Y280693D01*
G01Y280110D02*
X499267Y280443D01*
X498767Y280610D01*
X498183Y280693D01*
X497600Y280527D01*
X497100Y280193D01*
X496767Y279693D01*
X496600Y279027D01*
X496767Y278360D01*
X497100Y277860D01*
X497600Y277527D01*
X498183Y277360D01*
X498767Y277443D01*
X499267Y277693D01*
X499600Y278027D01*
G01X502283Y277360D02*
Y280693D01*
G01Y279860D02*
X502617Y280277D01*
X503117Y280610D01*
X503783Y280693D01*
X504367Y280610D01*
X504867Y280277D01*
X505117Y279693D01*
Y277360D01*
G01X510800Y282360D02*
Y277360D01*
G01Y278110D02*
X510467Y277693D01*
X509967Y277443D01*
X509383Y277360D01*
X508717Y277527D01*
X508217Y277943D01*
X507883Y278443D01*
X507800Y279027D01*
X507883Y279610D01*
X508217Y280110D01*
X508717Y280527D01*
X509383Y280693D01*
X509967Y280610D01*
X510383Y280443D01*
X510800Y280110D01*
G01X520500Y280693D02*
Y277360D01*
G01Y282027D02*
X520333Y282110D01*
Y282277D01*
X520500Y282360D01*
X520667Y282277D01*
Y282110D01*
X520500Y282027D01*
G01X524683Y277360D02*
Y280693D01*
G01Y279860D02*
X525017Y280277D01*
X525517Y280610D01*
X526183Y280693D01*
X526767Y280610D01*
X527267Y280277D01*
X527517Y279693D01*
Y277360D01*
G01X530283D02*
Y280693D01*
G01Y279860D02*
X530617Y280277D01*
X531117Y280610D01*
X531783Y280693D01*
X532367Y280610D01*
X532867Y280277D01*
X533117Y279693D01*
Y277360D01*
G01X536050Y279610D02*
X538717D01*
X538467Y280193D01*
X538050Y280527D01*
X537467Y280693D01*
X536883Y280610D01*
X536383Y280360D01*
X536050Y279777D01*
X535883Y279277D01*
Y278777D01*
X536050Y278277D01*
X536467Y277777D01*
X536967Y277443D01*
X537550Y277360D01*
X538133Y277527D01*
X538717Y278027D01*
G01X541733Y277360D02*
Y280693D01*
G01Y280027D02*
X542150Y280360D01*
X542567Y280610D01*
X543150Y280693D01*
X543567Y280610D01*
X544067Y280360D01*
G01X554100Y277360D02*
Y282360D01*
G01X561200Y277360D02*
Y280693D01*
G01Y280110D02*
X560867Y280443D01*
X560367Y280610D01*
X559783Y280693D01*
X559200Y280527D01*
X558700Y280193D01*
X558367Y279693D01*
X558200Y279027D01*
X558367Y278360D01*
X558700Y277860D01*
X559200Y277527D01*
X559783Y277360D01*
X560367Y277443D01*
X560867Y277693D01*
X561200Y278027D01*
G01X564050Y277943D02*
X564467Y277610D01*
X565050Y277360D01*
X565550D01*
X566050Y277527D01*
X566383Y277777D01*
X566550Y278110D01*
X566467Y278610D01*
X566133Y278860D01*
X564633Y279360D01*
X564300Y279943D01*
X564467Y280360D01*
X564800Y280610D01*
X565300Y280693D01*
X565800Y280610D01*
X566300Y280360D01*
G01X569650Y279610D02*
X572317D01*
X572067Y280193D01*
X571650Y280527D01*
X571067Y280693D01*
X570483Y280610D01*
X569983Y280360D01*
X569650Y279777D01*
X569483Y279277D01*
Y278777D01*
X569650Y278277D01*
X570067Y277777D01*
X570567Y277443D01*
X571150Y277360D01*
X571733Y277527D01*
X572317Y278027D01*
G01X575333Y277360D02*
Y280693D01*
G01Y280027D02*
X575750Y280360D01*
X576167Y280610D01*
X576750Y280693D01*
X577167Y280610D01*
X577667Y280360D01*
G01X361117Y328537D02*
X360717Y328737D01*
X360250Y328870D01*
X359717D01*
X359117Y328670D01*
X358650Y328337D01*
X358317Y327937D01*
X358050Y327270D01*
X357983Y326670D01*
X358117Y326070D01*
X358317Y325670D01*
X358717Y325270D01*
X359183Y325003D01*
X359650Y324870D01*
X360117D01*
X360583Y325003D01*
X360983Y325203D01*
X361317Y325470D01*
G01X401827Y295540D02*
X403910Y300540D01*
X405993Y295540D01*
G01X405243Y297290D02*
X402577D01*
G01X408093Y295540D02*
Y298873D01*
G01Y298040D02*
X408427Y298457D01*
X408927Y298790D01*
X409593Y298873D01*
X410177Y298790D01*
X410677Y298457D01*
X410927Y297873D01*
Y295540D01*
G01X413943Y294290D02*
X414527Y293957D01*
X415193Y293873D01*
X415777Y293957D01*
X416277Y294373D01*
X416610Y294957D01*
Y298873D01*
G01Y298207D02*
X416277Y298540D01*
X415777Y298790D01*
X415193Y298873D01*
X414527Y298707D01*
X414110Y298373D01*
X413777Y297790D01*
X413610Y297207D01*
X413693Y296707D01*
X414027Y296123D01*
X414527Y295707D01*
X415193Y295540D01*
X415693Y295623D01*
X416277Y295957D01*
X416610Y296290D01*
G01X420710Y295540D02*
Y300540D01*
G01X425060Y297790D02*
X427727D01*
X427477Y298373D01*
X427060Y298707D01*
X426477Y298873D01*
X425893Y298790D01*
X425393Y298540D01*
X425060Y297957D01*
X424893Y297457D01*
Y296957D01*
X425060Y296457D01*
X425477Y295957D01*
X425977Y295623D01*
X426560Y295540D01*
X427143Y295707D01*
X427727Y296207D01*
G01X431493Y293873D02*
X430660Y294707D01*
X430243Y295540D01*
Y298873D01*
X430660Y299707D01*
X431493Y300540D01*
G01X449127Y293873D02*
X449960Y294707D01*
X450377Y295540D01*
Y298873D01*
X449960Y299707D01*
X449127Y300540D01*
G01X401777Y331927D02*
X402110Y332177D01*
X402360Y332593D01*
X402527Y333177D01*
X402360Y333677D01*
X402027Y334010D01*
X401443Y334260D01*
X399193D01*
Y329260D01*
X401943D01*
X402527Y329593D01*
X402860Y330093D01*
X403027Y330677D01*
X402860Y331260D01*
X402360Y331760D01*
X401777Y331927D01*
X399193D01*
G01X405210Y329093D02*
X408210Y334260D01*
G01X410227Y329260D02*
X412310Y334260D01*
X414393Y329260D01*
G01X413643Y331010D02*
X410977D01*
G01X395000Y305500D02*
X694500D01*
G01X395000Y337500D02*
X694500D01*
G01X400633Y358960D02*
Y353960D01*
X403967D01*
G01X409400D02*
Y357293D01*
G01Y356710D02*
X409067Y357043D01*
X408567Y357210D01*
X407983Y357293D01*
X407400Y357127D01*
X406900Y356793D01*
X406567Y356293D01*
X406400Y355627D01*
X406567Y354960D01*
X406900Y354460D01*
X407400Y354127D01*
X407983Y353960D01*
X408567Y354043D01*
X409067Y354293D01*
X409400Y354627D01*
G01X412250Y354543D02*
X412667Y354210D01*
X413250Y353960D01*
X413750D01*
X414250Y354127D01*
X414583Y354377D01*
X414750Y354710D01*
X414667Y355210D01*
X414333Y355460D01*
X412833Y355960D01*
X412500Y356543D01*
X412667Y356960D01*
X413000Y357210D01*
X413500Y357293D01*
X414000Y357210D01*
X414500Y356960D01*
G01X417850Y356210D02*
X420517D01*
X420267Y356793D01*
X419850Y357127D01*
X419267Y357293D01*
X418683Y357210D01*
X418183Y356960D01*
X417850Y356377D01*
X417683Y355877D01*
Y355377D01*
X417850Y354877D01*
X418267Y354377D01*
X418767Y354043D01*
X419350Y353960D01*
X419933Y354127D01*
X420517Y354627D01*
G01X423533Y353960D02*
Y357293D01*
G01Y356627D02*
X423950Y356960D01*
X424367Y357210D01*
X424950Y357293D01*
X425367Y357210D01*
X425867Y356960D01*
G01X434400Y357293D02*
X435900Y353960D01*
X437400Y357293D01*
G01X441500D02*
Y353960D01*
G01Y358627D02*
X441333Y358710D01*
Y358877D01*
X441500Y358960D01*
X441667Y358877D01*
Y358710D01*
X441500Y358627D01*
G01X448600Y353960D02*
Y357293D01*
G01Y356710D02*
X448267Y357043D01*
X447767Y357210D01*
X447183Y357293D01*
X446600Y357127D01*
X446100Y356793D01*
X445767Y356293D01*
X445600Y355627D01*
X445767Y354960D01*
X446100Y354460D01*
X446600Y354127D01*
X447183Y353960D01*
X447767Y354043D01*
X448267Y354293D01*
X448600Y354627D01*
G01X457050Y354543D02*
X457467Y354210D01*
X458050Y353960D01*
X458550D01*
X459050Y354127D01*
X459383Y354377D01*
X459550Y354710D01*
X459467Y355210D01*
X459133Y355460D01*
X457633Y355960D01*
X457300Y356543D01*
X457467Y356960D01*
X457800Y357210D01*
X458300Y357293D01*
X458800Y357210D01*
X459300Y356960D01*
G01X463900Y357293D02*
Y353960D01*
G01Y358627D02*
X463733Y358710D01*
Y358877D01*
X463900Y358960D01*
X464067Y358877D01*
Y358710D01*
X463900Y358627D01*
G01X468250Y357293D02*
X470750D01*
X468250Y353960D01*
X470750D01*
G01X473850Y356210D02*
X476517D01*
X476267Y356793D01*
X475850Y357127D01*
X475267Y357293D01*
X474683Y357210D01*
X474183Y356960D01*
X473850Y356377D01*
X473683Y355877D01*
Y355377D01*
X473850Y354877D01*
X474267Y354377D01*
X474767Y354043D01*
X475350Y353960D01*
X475933Y354127D01*
X476517Y354627D01*
G01X484217Y357293D02*
X485217Y353960D01*
X486300Y357293D01*
X487383Y353960D01*
X488383Y357293D01*
G01X491900D02*
Y353960D01*
G01Y358627D02*
X491733Y358710D01*
Y358877D01*
X491900Y358960D01*
X492067Y358877D01*
Y358710D01*
X491900Y358627D01*
G01X497500Y358960D02*
Y353960D01*
G01X496333Y357293D02*
X498667D01*
G01X501683Y353960D02*
Y358960D01*
G01Y356543D02*
X502100Y356960D01*
X502517Y357210D01*
X503183Y357293D01*
X503683Y357210D01*
X504267Y356877D01*
X504517Y356377D01*
Y353960D01*
G01X508700D02*
X508200Y354043D01*
X507700Y354377D01*
X507367Y354960D01*
X507200Y355627D01*
X507367Y356293D01*
X507700Y356877D01*
X508200Y357210D01*
X508700Y357293D01*
X509200Y357210D01*
X509700Y356877D01*
X510033Y356293D01*
X510117Y355627D01*
X510033Y354960D01*
X509700Y354377D01*
X509200Y354043D01*
X508700Y353960D01*
G01X512883Y357293D02*
Y354960D01*
X513217Y354377D01*
X513717Y354043D01*
X514300Y353960D01*
X514883Y354043D01*
X515383Y354377D01*
X515717Y354960D01*
G01Y353960D02*
Y357293D01*
G01X519900Y358960D02*
Y353960D01*
G01X518733Y357293D02*
X521067D01*
G01X529600Y352293D02*
Y357293D01*
G01Y356543D02*
X530017Y356960D01*
X530433Y357210D01*
X531100Y357293D01*
X531683Y357210D01*
X532267Y356793D01*
X532517Y356210D01*
X532600Y355627D01*
X532517Y355043D01*
X532267Y354460D01*
X531767Y354127D01*
X531100Y353960D01*
X530517Y354043D01*
X529933Y354293D01*
X529600Y354627D01*
G01X536700Y353960D02*
Y358960D01*
G01X543800Y353960D02*
Y357293D01*
G01Y356710D02*
X543467Y357043D01*
X542967Y357210D01*
X542383Y357293D01*
X541800Y357127D01*
X541300Y356793D01*
X540967Y356293D01*
X540800Y355627D01*
X540967Y354960D01*
X541300Y354460D01*
X541800Y354127D01*
X542383Y353960D01*
X542967Y354043D01*
X543467Y354293D01*
X543800Y354627D01*
G01X547900Y358960D02*
Y353960D01*
G01X546733Y357293D02*
X549067D01*
G01X553500D02*
Y353960D01*
G01Y358627D02*
X553333Y358710D01*
Y358877D01*
X553500Y358960D01*
X553667Y358877D01*
Y358710D01*
X553500Y358627D01*
G01X557683Y353960D02*
Y357293D01*
G01Y356460D02*
X558017Y356877D01*
X558517Y357210D01*
X559183Y357293D01*
X559767Y357210D01*
X560267Y356877D01*
X560517Y356293D01*
Y353960D01*
G01X563533Y352710D02*
X564117Y352377D01*
X564783Y352293D01*
X565367Y352377D01*
X565867Y352793D01*
X566200Y353377D01*
Y357293D01*
G01Y356627D02*
X565867Y356960D01*
X565367Y357210D01*
X564783Y357293D01*
X564117Y357127D01*
X563700Y356793D01*
X563367Y356210D01*
X563200Y355627D01*
X563283Y355127D01*
X563617Y354543D01*
X564117Y354127D01*
X564783Y353960D01*
X565283Y354043D01*
X565867Y354377D01*
X566200Y354710D01*
G01X575483Y352293D02*
X574650Y353127D01*
X574233Y353960D01*
Y357293D01*
X574650Y358127D01*
X575483Y358960D01*
G01X582167Y356627D02*
X582500Y356877D01*
X582750Y357293D01*
X582917Y357877D01*
X582750Y358377D01*
X582417Y358710D01*
X581833Y358960D01*
X579583D01*
Y353960D01*
X582333D01*
X582917Y354293D01*
X583250Y354793D01*
X583417Y355377D01*
X583250Y355960D01*
X582750Y356460D01*
X582167Y356627D01*
X579583D01*
G01X587517Y352293D02*
X588350Y353127D01*
X588767Y353960D01*
Y357293D01*
X588350Y358127D01*
X587517Y358960D01*
G01X404500Y666833D02*
Y663500D01*
G01Y668167D02*
X404333Y668250D01*
Y668417D01*
X404500Y668500D01*
X404667Y668417D01*
Y668250D01*
X404500Y668167D01*
G01X410100Y668500D02*
Y663500D01*
G01X408933Y666833D02*
X411267D01*
G01X414450Y665750D02*
X417117D01*
X416867Y666333D01*
X416450Y666667D01*
X415867Y666833D01*
X415283Y666750D01*
X414783Y666500D01*
X414450Y665917D01*
X414283Y665417D01*
Y664917D01*
X414450Y664417D01*
X414867Y663917D01*
X415367Y663583D01*
X415950Y663500D01*
X416533Y663667D01*
X417117Y664167D01*
G01X418800Y663500D02*
Y666833D01*
G01Y665917D02*
X419050Y666333D01*
X419467Y666667D01*
X420050Y666833D01*
X420633Y666667D01*
X421050Y666333D01*
X421300Y665917D01*
Y663500D01*
G01Y665917D02*
X421550Y666333D01*
X421967Y666667D01*
X422550Y666833D01*
X423133Y666667D01*
X423550Y666333D01*
X423800Y665833D01*
Y663500D01*
G01X444197Y299927D02*
X443797Y300127D01*
X443330Y300260D01*
X442797D01*
X442197Y300060D01*
X441730Y299727D01*
X441397Y299327D01*
X441130Y298660D01*
X441063Y298060D01*
X441197Y297460D01*
X441397Y297060D01*
X441797Y296660D01*
X442263Y296393D01*
X442730Y296260D01*
X443197D01*
X443663Y296393D01*
X444063Y296593D01*
X444397Y296860D01*
G01X607500Y-15000D02*
X606833Y-15167D01*
X606333Y-15583D01*
X606000Y-16083D01*
X605750Y-16750D01*
X605667Y-17500D01*
X605750Y-18250D01*
X606000Y-18917D01*
X606333Y-19417D01*
X606833Y-19833D01*
X607500Y-20000D01*
X608167Y-19833D01*
X608667Y-19417D01*
X609000Y-18917D01*
X609250Y-18250D01*
X609333Y-17500D01*
X609250Y-16750D01*
X609000Y-16083D01*
X608667Y-15583D01*
X608167Y-15167D01*
X607500Y-15000D01*
G01X613100Y-20167D02*
X612933Y-20083D01*
Y-19917D01*
X613100Y-19833D01*
X613267Y-19917D01*
Y-20083D01*
X613100Y-20167D01*
G01X616867Y-19000D02*
X617367Y-19583D01*
X618033Y-19917D01*
X618783Y-20000D01*
X619450Y-19917D01*
X620117Y-19500D01*
X620533Y-19000D01*
X620617Y-18500D01*
X620450Y-17917D01*
X619867Y-17500D01*
X619283Y-17333D01*
X618533D01*
G01X619283D02*
X619783Y-17083D01*
X620200Y-16667D01*
X620367Y-16167D01*
X620200Y-15667D01*
X619783Y-15250D01*
X619033Y-15000D01*
X618283Y-15083D01*
X617533Y-15417D01*
G01X621800Y-18333D02*
X622633Y-16667D01*
X623467D01*
X625133Y-20000D01*
X625967D01*
X626800Y-18333D01*
G01X629900Y-15000D02*
X629233Y-15167D01*
X628733Y-15583D01*
X628400Y-16083D01*
X628150Y-16750D01*
X628067Y-17500D01*
X628150Y-18250D01*
X628400Y-18917D01*
X628733Y-19417D01*
X629233Y-19833D01*
X629900Y-20000D01*
X630567Y-19833D01*
X631067Y-19417D01*
X631400Y-18917D01*
X631650Y-18250D01*
X631733Y-17500D01*
X631650Y-16750D01*
X631400Y-16083D01*
X631067Y-15583D01*
X630567Y-15167D01*
X629900Y-15000D01*
G01X635500Y-20167D02*
X635333Y-20083D01*
Y-19917D01*
X635500Y-19833D01*
X635667Y-19917D01*
Y-20083D01*
X635500Y-20167D01*
G01X640933Y-20000D02*
X641100Y-18917D01*
X641350Y-18000D01*
X641683Y-17167D01*
X642100Y-16250D01*
X642767Y-15000D01*
X639433D01*
G01X644200Y-20000D02*
Y-16667D01*
G01Y-17583D02*
X644450Y-17167D01*
X644867Y-16833D01*
X645450Y-16667D01*
X646033Y-16833D01*
X646450Y-17167D01*
X646700Y-17583D01*
Y-20000D01*
G01Y-17583D02*
X646950Y-17167D01*
X647367Y-16833D01*
X647950Y-16667D01*
X648533Y-16833D01*
X648950Y-17167D01*
X649200Y-17667D01*
Y-20000D01*
G01X652300Y-16667D02*
Y-20000D01*
G01Y-15333D02*
X652133Y-15250D01*
Y-15083D01*
X652300Y-15000D01*
X652467Y-15083D01*
Y-15250D01*
X652300Y-15333D01*
G01X657900Y-20000D02*
Y-15000D01*
G01X607500Y-28500D02*
X606833Y-28667D01*
X606333Y-29083D01*
X606000Y-29583D01*
X605750Y-30250D01*
X605667Y-31000D01*
X605750Y-31750D01*
X606000Y-32417D01*
X606333Y-32917D01*
X606833Y-33333D01*
X607500Y-33500D01*
X608167Y-33333D01*
X608667Y-32917D01*
X609000Y-32417D01*
X609250Y-31750D01*
X609333Y-31000D01*
X609250Y-30250D01*
X609000Y-29583D01*
X608667Y-29083D01*
X608167Y-28667D01*
X607500Y-28500D01*
G01X613100Y-33667D02*
X612933Y-33583D01*
Y-33417D01*
X613100Y-33333D01*
X613267Y-33417D01*
Y-33583D01*
X613100Y-33667D01*
G01X616867Y-32500D02*
X617367Y-33083D01*
X618033Y-33417D01*
X618783Y-33500D01*
X619450Y-33417D01*
X620117Y-33000D01*
X620533Y-32500D01*
X620617Y-32000D01*
X620450Y-31417D01*
X619867Y-31000D01*
X619283Y-30833D01*
X618533D01*
G01X619283D02*
X619783Y-30583D01*
X620200Y-30167D01*
X620367Y-29667D01*
X620200Y-29167D01*
X619783Y-28750D01*
X619033Y-28500D01*
X618283Y-28583D01*
X617533Y-28917D01*
G01X621800Y-31833D02*
X622633Y-30167D01*
X623467D01*
X625133Y-33500D01*
X625967D01*
X626800Y-31833D01*
G01X629900Y-28500D02*
X629233Y-28667D01*
X628733Y-29083D01*
X628400Y-29583D01*
X628150Y-30250D01*
X628067Y-31000D01*
X628150Y-31750D01*
X628400Y-32417D01*
X628733Y-32917D01*
X629233Y-33333D01*
X629900Y-33500D01*
X630567Y-33333D01*
X631067Y-32917D01*
X631400Y-32417D01*
X631650Y-31750D01*
X631733Y-31000D01*
X631650Y-30250D01*
X631400Y-29583D01*
X631067Y-29083D01*
X630567Y-28667D01*
X629900Y-28500D01*
G01X635500Y-33667D02*
X635333Y-33583D01*
Y-33417D01*
X635500Y-33333D01*
X635667Y-33417D01*
Y-33583D01*
X635500Y-33667D01*
G01X640933Y-33500D02*
X641100Y-32417D01*
X641350Y-31500D01*
X641683Y-30667D01*
X642100Y-29750D01*
X642767Y-28500D01*
X639433D01*
G01X644200Y-33500D02*
Y-30167D01*
G01Y-31083D02*
X644450Y-30667D01*
X644867Y-30333D01*
X645450Y-30167D01*
X646033Y-30333D01*
X646450Y-30667D01*
X646700Y-31083D01*
Y-33500D01*
G01Y-31083D02*
X646950Y-30667D01*
X647367Y-30333D01*
X647950Y-30167D01*
X648533Y-30333D01*
X648950Y-30667D01*
X649200Y-31167D01*
Y-33500D01*
G01X652300Y-30167D02*
Y-33500D01*
G01Y-28833D02*
X652133Y-28750D01*
Y-28583D01*
X652300Y-28500D01*
X652467Y-28583D01*
Y-28750D01*
X652300Y-28833D01*
G01X657900Y-33500D02*
Y-28500D01*
G01X609167Y-48500D02*
X605833Y-46833D01*
X609167Y-45167D01*
G01X612017Y-47583D02*
X614183D01*
G01Y-46083D02*
X612017D01*
G01X618700Y-48500D02*
Y-43500D01*
X617700Y-44500D01*
G01Y-48500D02*
X619700D01*
G01X624300Y-48667D02*
X624133Y-48583D01*
Y-48417D01*
X624300Y-48333D01*
X624467Y-48417D01*
Y-48583D01*
X624300Y-48667D01*
G01X630900Y-48500D02*
Y-43500D01*
X627817Y-47083D01*
X631983D01*
G01X633000Y-48500D02*
Y-45167D01*
G01Y-46083D02*
X633250Y-45667D01*
X633667Y-45333D01*
X634250Y-45167D01*
X634833Y-45333D01*
X635250Y-45667D01*
X635500Y-46083D01*
Y-48500D01*
G01Y-46083D02*
X635750Y-45667D01*
X636167Y-45333D01*
X636750Y-45167D01*
X637333Y-45333D01*
X637750Y-45667D01*
X638000Y-46167D01*
Y-48500D01*
G01X641100Y-45167D02*
Y-48500D01*
G01Y-43833D02*
X640933Y-43750D01*
Y-43583D01*
X641100Y-43500D01*
X641267Y-43583D01*
Y-43750D01*
X641100Y-43833D01*
G01X646700Y-48500D02*
Y-43500D01*
G01X605333Y-65000D02*
Y-60000D01*
X607500Y-64167D01*
X609667Y-60000D01*
Y-65000D01*
G01X611683Y-61667D02*
Y-64000D01*
X612017Y-64583D01*
X612517Y-64917D01*
X613100Y-65000D01*
X613683Y-64917D01*
X614183Y-64583D01*
X614517Y-64000D01*
G01Y-65000D02*
Y-61667D01*
G01X617450Y-64417D02*
X617867Y-64750D01*
X618450Y-65000D01*
X618950D01*
X619450Y-64833D01*
X619783Y-64583D01*
X619950Y-64250D01*
X619867Y-63750D01*
X619533Y-63500D01*
X618033Y-63000D01*
X617700Y-62417D01*
X617867Y-62000D01*
X618200Y-61750D01*
X618700Y-61667D01*
X619200Y-61750D01*
X619700Y-62000D01*
G01X624300Y-60000D02*
Y-65000D01*
G01X623133Y-61667D02*
X625467D01*
G01X635000Y-65000D02*
Y-60750D01*
X635167Y-60333D01*
X635500Y-60083D01*
X636000Y-60000D01*
X636500Y-60167D01*
X636750Y-60583D01*
G01X635750Y-62000D02*
X634083D01*
G01X641100Y-65000D02*
X640600Y-64917D01*
X640100Y-64583D01*
X639767Y-64000D01*
X639600Y-63333D01*
X639767Y-62667D01*
X640100Y-62083D01*
X640600Y-61750D01*
X641100Y-61667D01*
X641600Y-61750D01*
X642100Y-62083D01*
X642433Y-62667D01*
X642517Y-63333D01*
X642433Y-64000D01*
X642100Y-64583D01*
X641600Y-64917D01*
X641100Y-65000D01*
G01X646700D02*
Y-60000D01*
G01X652300Y-65000D02*
Y-60000D01*
G01X657900Y-65000D02*
X657400Y-64917D01*
X656900Y-64583D01*
X656567Y-64000D01*
X656400Y-63333D01*
X656567Y-62667D01*
X656900Y-62083D01*
X657400Y-61750D01*
X657900Y-61667D01*
X658400Y-61750D01*
X658900Y-62083D01*
X659233Y-62667D01*
X659317Y-63333D01*
X659233Y-64000D01*
X658900Y-64583D01*
X658400Y-64917D01*
X657900Y-65000D01*
G01X661417Y-61667D02*
X662417Y-65000D01*
X663500Y-61667D01*
X664583Y-65000D01*
X665583Y-61667D01*
G01X595500Y-69500D02*
Y438000D01*
G01X606583Y-1833D02*
X608583D01*
G01X607500Y-750D02*
Y-2917D01*
G01X611600Y-3667D02*
X614600Y1500D01*
G01X617617Y-1833D02*
X619783D01*
G01X624300Y-3500D02*
Y1500D01*
X623300Y500D01*
G01Y-3500D02*
X625300D01*
G01X627400D02*
Y-167D01*
G01Y-1083D02*
X627650Y-667D01*
X628067Y-333D01*
X628650Y-167D01*
X629233Y-333D01*
X629650Y-667D01*
X629900Y-1083D01*
Y-3500D01*
G01Y-1083D02*
X630150Y-667D01*
X630567Y-333D01*
X631150Y-167D01*
X631733Y-333D01*
X632150Y-667D01*
X632400Y-1167D01*
Y-3500D01*
G01X635500Y-167D02*
Y-3500D01*
G01Y1167D02*
X635333Y1250D01*
Y1417D01*
X635500Y1500D01*
X635667Y1417D01*
Y1250D01*
X635500Y1167D01*
G01X641100Y-3500D02*
Y1500D01*
G01X606583Y48667D02*
X608583D01*
G01X607500Y49750D02*
Y47583D01*
G01X611600Y46833D02*
X614600Y52000D01*
G01X617617Y48667D02*
X619783D01*
G01X622717Y51167D02*
X623217Y51667D01*
X623800Y51917D01*
X624467Y52000D01*
X625300Y51833D01*
X625883Y51417D01*
X626050Y50917D01*
X625967Y50417D01*
X625633Y50000D01*
X623967Y49167D01*
X623217Y48583D01*
X622717Y47750D01*
X622550Y47000D01*
X626050D01*
G01X627400D02*
Y50333D01*
G01Y49417D02*
X627650Y49833D01*
X628067Y50167D01*
X628650Y50333D01*
X629233Y50167D01*
X629650Y49833D01*
X629900Y49417D01*
Y47000D01*
G01Y49417D02*
X630150Y49833D01*
X630567Y50167D01*
X631150Y50333D01*
X631733Y50167D01*
X632150Y49833D01*
X632400Y49333D01*
Y47000D01*
G01X635500Y50333D02*
Y47000D01*
G01Y51667D02*
X635333Y51750D01*
Y51917D01*
X635500Y52000D01*
X635667Y51917D01*
Y51750D01*
X635500Y51667D01*
G01X641100Y47000D02*
Y52000D01*
G01X606583Y24667D02*
X608583D01*
G01X607500Y25750D02*
Y23583D01*
G01X611600Y22833D02*
X614600Y28000D01*
G01X617617Y24667D02*
X619783D01*
G01X624300Y23000D02*
Y28000D01*
X623300Y27000D01*
G01Y23000D02*
X625300D01*
G01X627400D02*
Y26333D01*
G01Y25417D02*
X627650Y25833D01*
X628067Y26167D01*
X628650Y26333D01*
X629233Y26167D01*
X629650Y25833D01*
X629900Y25417D01*
Y23000D01*
G01Y25417D02*
X630150Y25833D01*
X630567Y26167D01*
X631150Y26333D01*
X631733Y26167D01*
X632150Y25833D01*
X632400Y25333D01*
Y23000D01*
G01X635500Y26333D02*
Y23000D01*
G01Y27667D02*
X635333Y27750D01*
Y27917D01*
X635500Y28000D01*
X635667Y27917D01*
Y27750D01*
X635500Y27667D01*
G01X641100Y23000D02*
Y28000D01*
G01X606583Y13167D02*
X608583D01*
G01X607500Y14250D02*
Y12083D01*
G01X611600Y11333D02*
X614600Y16500D01*
G01X617617Y13167D02*
X619783D01*
G01X622717Y15667D02*
X623217Y16167D01*
X623800Y16417D01*
X624467Y16500D01*
X625300Y16333D01*
X625883Y15917D01*
X626050Y15417D01*
X625967Y14917D01*
X625633Y14500D01*
X623967Y13667D01*
X623217Y13083D01*
X622717Y12250D01*
X622550Y11500D01*
X626050D01*
G01X627400D02*
Y14833D01*
G01Y13917D02*
X627650Y14333D01*
X628067Y14667D01*
X628650Y14833D01*
X629233Y14667D01*
X629650Y14333D01*
X629900Y13917D01*
Y11500D01*
G01Y13917D02*
X630150Y14333D01*
X630567Y14667D01*
X631150Y14833D01*
X631733Y14667D01*
X632150Y14333D01*
X632400Y13833D01*
Y11500D01*
G01X635500Y14833D02*
Y11500D01*
G01Y16167D02*
X635333Y16250D01*
Y16417D01*
X635500Y16500D01*
X635667Y16417D01*
Y16250D01*
X635500Y16167D01*
G01X641100Y11500D02*
Y16500D01*
G01X605833Y126500D02*
X609167Y128167D01*
X605833Y129833D01*
G01X612017Y127417D02*
X614183D01*
G01Y128917D02*
X612017D01*
G01X618700Y126500D02*
Y131500D01*
X617700Y130500D01*
G01Y126500D02*
X619700D01*
G01X624300Y126333D02*
X624133Y126417D01*
Y126583D01*
X624300Y126667D01*
X624467Y126583D01*
Y126417D01*
X624300Y126333D01*
G01X629900Y131500D02*
X629233Y131333D01*
X628733Y130917D01*
X628400Y130417D01*
X628150Y129750D01*
X628067Y129000D01*
X628150Y128250D01*
X628400Y127583D01*
X628733Y127083D01*
X629233Y126667D01*
X629900Y126500D01*
X630567Y126667D01*
X631067Y127083D01*
X631400Y127583D01*
X631650Y128250D01*
X631733Y129000D01*
X631650Y129750D01*
X631400Y130417D01*
X631067Y130917D01*
X630567Y131333D01*
X629900Y131500D01*
G01X633000Y126500D02*
Y129833D01*
G01Y128917D02*
X633250Y129333D01*
X633667Y129667D01*
X634250Y129833D01*
X634833Y129667D01*
X635250Y129333D01*
X635500Y128917D01*
Y126500D01*
G01Y128917D02*
X635750Y129333D01*
X636167Y129667D01*
X636750Y129833D01*
X637333Y129667D01*
X637750Y129333D01*
X638000Y128833D01*
Y126500D01*
G01X641100Y129833D02*
Y126500D01*
G01Y131167D02*
X640933Y131250D01*
Y131417D01*
X641100Y131500D01*
X641267Y131417D01*
Y131250D01*
X641100Y131167D01*
G01X646700Y126500D02*
Y131500D01*
G01X606583Y98167D02*
X608583D01*
G01X607500Y99250D02*
Y97083D01*
G01X611600Y96333D02*
X614600Y101500D01*
G01X617617Y98167D02*
X619783D01*
G01X622717Y100667D02*
X623217Y101167D01*
X623800Y101417D01*
X624467Y101500D01*
X625300Y101333D01*
X625883Y100917D01*
X626050Y100417D01*
X625967Y99917D01*
X625633Y99500D01*
X623967Y98667D01*
X623217Y98083D01*
X622717Y97250D01*
X622550Y96500D01*
X626050D01*
G01X629900Y101500D02*
X629233Y101333D01*
X628733Y100917D01*
X628400Y100417D01*
X628150Y99750D01*
X628067Y99000D01*
X628150Y98250D01*
X628400Y97583D01*
X628733Y97083D01*
X629233Y96667D01*
X629900Y96500D01*
X630567Y96667D01*
X631067Y97083D01*
X631400Y97583D01*
X631650Y98250D01*
X631733Y99000D01*
X631650Y99750D01*
X631400Y100417D01*
X631067Y100917D01*
X630567Y101333D01*
X629900Y101500D01*
G01X634000Y96333D02*
X637000Y101500D01*
G01X634000D02*
X633500Y101333D01*
X633250Y101083D01*
X633083Y100583D01*
X633250Y100083D01*
X633500Y99833D01*
X634000Y99667D01*
X634500Y99833D01*
X634750Y100083D01*
X634917Y100583D01*
X634750Y101083D01*
X634500Y101333D01*
X634000Y101500D01*
G01X637000Y98167D02*
X636500Y98000D01*
X636250Y97750D01*
X636083Y97250D01*
X636250Y96750D01*
X636500Y96500D01*
X637000Y96333D01*
X637500Y96500D01*
X637750Y96750D01*
X637917Y97250D01*
X637750Y97750D01*
X637500Y98000D01*
X637000Y98167D01*
G01X606583Y68167D02*
X608583D01*
G01X607500Y69250D02*
Y67083D01*
G01X611600Y66333D02*
X614600Y71500D01*
G01X617617Y68167D02*
X619783D01*
G01X624300Y66500D02*
Y71500D01*
X623300Y70500D01*
G01Y66500D02*
X625300D01*
G01X628067Y67250D02*
X628567Y66833D01*
X629150Y66583D01*
X629900Y66500D01*
X630650Y66667D01*
X631233Y67000D01*
X631650Y67583D01*
X631733Y68250D01*
X631567Y68917D01*
X631150Y69333D01*
X630567Y69667D01*
X629983Y69750D01*
X629400Y69667D01*
X628650Y69333D01*
X628900Y71500D01*
X631150D01*
G01X634000Y66333D02*
X637000Y71500D01*
G01X634000D02*
X633500Y71333D01*
X633250Y71083D01*
X633083Y70583D01*
X633250Y70083D01*
X633500Y69833D01*
X634000Y69667D01*
X634500Y69833D01*
X634750Y70083D01*
X634917Y70583D01*
X634750Y71083D01*
X634500Y71333D01*
X634000Y71500D01*
G01X637000Y68167D02*
X636500Y68000D01*
X636250Y67750D01*
X636083Y67250D01*
X636250Y66750D01*
X636500Y66500D01*
X637000Y66333D01*
X637500Y66500D01*
X637750Y66750D01*
X637917Y67250D01*
X637750Y67750D01*
X637500Y68000D01*
X637000Y68167D01*
G01X606583Y113167D02*
X608583D01*
G01X607500Y114250D02*
Y112083D01*
G01X611600Y111333D02*
X614600Y116500D01*
G01X617617Y113167D02*
X619783D01*
G01X622467Y112500D02*
X622967Y111917D01*
X623633Y111583D01*
X624383Y111500D01*
X625050Y111583D01*
X625717Y112000D01*
X626133Y112500D01*
X626217Y113000D01*
X626050Y113583D01*
X625467Y114000D01*
X624883Y114167D01*
X624133D01*
G01X624883D02*
X625383Y114417D01*
X625800Y114833D01*
X625967Y115333D01*
X625800Y115833D01*
X625383Y116250D01*
X624633Y116500D01*
X623883Y116417D01*
X623133Y116083D01*
G01X627400Y111500D02*
Y114833D01*
G01Y113917D02*
X627650Y114333D01*
X628067Y114667D01*
X628650Y114833D01*
X629233Y114667D01*
X629650Y114333D01*
X629900Y113917D01*
Y111500D01*
G01Y113917D02*
X630150Y114333D01*
X630567Y114667D01*
X631150Y114833D01*
X631733Y114667D01*
X632150Y114333D01*
X632400Y113833D01*
Y111500D01*
G01X635500Y114833D02*
Y111500D01*
G01Y116167D02*
X635333Y116250D01*
Y116417D01*
X635500Y116500D01*
X635667Y116417D01*
Y116250D01*
X635500Y116167D01*
G01X641100Y111500D02*
Y116500D01*
G01X606583Y83167D02*
X608583D01*
G01X607500Y84250D02*
Y82083D01*
G01X611600Y81333D02*
X614600Y86500D01*
G01X617617Y83167D02*
X619783D01*
G01X624300Y81500D02*
Y86500D01*
X623300Y85500D01*
G01Y81500D02*
X625300D01*
G01X627400D02*
Y84833D01*
G01Y83917D02*
X627650Y84333D01*
X628067Y84667D01*
X628650Y84833D01*
X629233Y84667D01*
X629650Y84333D01*
X629900Y83917D01*
Y81500D01*
G01Y83917D02*
X630150Y84333D01*
X630567Y84667D01*
X631150Y84833D01*
X631733Y84667D01*
X632150Y84333D01*
X632400Y83833D01*
Y81500D01*
G01X635500Y84833D02*
Y81500D01*
G01Y86167D02*
X635333Y86250D01*
Y86417D01*
X635500Y86500D01*
X635667Y86417D01*
Y86250D01*
X635500Y86167D01*
G01X641100Y81500D02*
Y86500D01*
G01X612977Y200490D02*
X609643Y202157D01*
X612977Y203823D01*
G01X616910Y205490D02*
X616243Y205323D01*
X615743Y204907D01*
X615410Y204407D01*
X615160Y203740D01*
X615077Y202990D01*
X615160Y202240D01*
X615410Y201573D01*
X615743Y201073D01*
X616243Y200657D01*
X616910Y200490D01*
X617577Y200657D01*
X618077Y201073D01*
X618410Y201573D01*
X618660Y202240D01*
X618743Y202990D01*
X618660Y203740D01*
X618410Y204407D01*
X618077Y204907D01*
X617577Y205323D01*
X616910Y205490D01*
G01X622510Y200323D02*
X622343Y200407D01*
Y200573D01*
X622510Y200657D01*
X622677Y200573D01*
Y200407D01*
X622510Y200323D01*
G01X626277Y201490D02*
X626777Y200907D01*
X627443Y200573D01*
X628193Y200490D01*
X628860Y200573D01*
X629527Y200990D01*
X629943Y201490D01*
X630027Y201990D01*
X629860Y202573D01*
X629277Y202990D01*
X628693Y203157D01*
X627943D01*
G01X628693D02*
X629193Y203407D01*
X629610Y203823D01*
X629777Y204323D01*
X629610Y204823D01*
X629193Y205240D01*
X628443Y205490D01*
X627693Y205407D01*
X626943Y205073D01*
G01X631210Y200490D02*
Y203823D01*
G01Y202907D02*
X631460Y203323D01*
X631877Y203657D01*
X632460Y203823D01*
X633043Y203657D01*
X633460Y203323D01*
X633710Y202907D01*
Y200490D01*
G01Y202907D02*
X633960Y203323D01*
X634377Y203657D01*
X634960Y203823D01*
X635543Y203657D01*
X635960Y203323D01*
X636210Y202823D01*
Y200490D01*
G01X639310Y203823D02*
Y200490D01*
G01Y205157D02*
X639143Y205240D01*
Y205407D01*
X639310Y205490D01*
X639477Y205407D01*
Y205240D01*
X639310Y205157D01*
G01X644910Y200490D02*
Y205490D01*
G01X605833Y166500D02*
X609167Y168167D01*
X605833Y169833D01*
G01X612017Y167417D02*
X614183D01*
G01Y168917D02*
X612017D01*
G01X618700Y166500D02*
Y171500D01*
X617700Y170500D01*
G01Y166500D02*
X619700D01*
G01X624300Y166333D02*
X624133Y166417D01*
Y166583D01*
X624300Y166667D01*
X624467Y166583D01*
Y166417D01*
X624300Y166333D01*
G01X628067Y167500D02*
X628567Y166917D01*
X629233Y166583D01*
X629983Y166500D01*
X630650Y166583D01*
X631317Y167000D01*
X631733Y167500D01*
X631817Y168000D01*
X631650Y168583D01*
X631067Y169000D01*
X630483Y169167D01*
X629733D01*
G01X630483D02*
X630983Y169417D01*
X631400Y169833D01*
X631567Y170333D01*
X631400Y170833D01*
X630983Y171250D01*
X630233Y171500D01*
X629483Y171417D01*
X628733Y171083D01*
G01X633000Y166500D02*
Y169833D01*
G01Y168917D02*
X633250Y169333D01*
X633667Y169667D01*
X634250Y169833D01*
X634833Y169667D01*
X635250Y169333D01*
X635500Y168917D01*
Y166500D01*
G01Y168917D02*
X635750Y169333D01*
X636167Y169667D01*
X636750Y169833D01*
X637333Y169667D01*
X637750Y169333D01*
X638000Y168833D01*
Y166500D01*
G01X641100Y169833D02*
Y166500D01*
G01Y171167D02*
X640933Y171250D01*
Y171417D01*
X641100Y171500D01*
X641267Y171417D01*
Y171250D01*
X641100Y171167D01*
G01X646700Y166500D02*
Y171500D01*
G01X605833Y144000D02*
X609167Y145667D01*
X605833Y147333D01*
G01X612017Y144917D02*
X614183D01*
G01Y146417D02*
X612017D01*
G01X618700Y144000D02*
Y149000D01*
X617700Y148000D01*
G01Y144000D02*
X619700D01*
G01X624300Y143833D02*
X624133Y143917D01*
Y144083D01*
X624300Y144167D01*
X624467Y144083D01*
Y143917D01*
X624300Y143833D01*
G01X628067Y144750D02*
X628567Y144333D01*
X629150Y144083D01*
X629900Y144000D01*
X630650Y144167D01*
X631233Y144500D01*
X631650Y145083D01*
X631733Y145750D01*
X631567Y146417D01*
X631150Y146833D01*
X630567Y147167D01*
X629983Y147250D01*
X629400Y147167D01*
X628650Y146833D01*
X628900Y149000D01*
X631150D01*
G01X633000Y144000D02*
Y147333D01*
G01Y146417D02*
X633250Y146833D01*
X633667Y147167D01*
X634250Y147333D01*
X634833Y147167D01*
X635250Y146833D01*
X635500Y146417D01*
Y144000D01*
G01Y146417D02*
X635750Y146833D01*
X636167Y147167D01*
X636750Y147333D01*
X637333Y147167D01*
X637750Y146833D01*
X638000Y146333D01*
Y144000D01*
G01X641100Y147333D02*
Y144000D01*
G01Y148667D02*
X640933Y148750D01*
Y148917D01*
X641100Y149000D01*
X641267Y148917D01*
Y148750D01*
X641100Y148667D01*
G01X646700Y144000D02*
Y149000D01*
G01X612377Y255680D02*
X609043Y257347D01*
X612377Y259013D01*
G01X616310Y255680D02*
Y260680D01*
X615310Y259680D01*
G01Y255680D02*
X617310D01*
G01X619410D02*
Y259013D01*
G01Y258097D02*
X619660Y258513D01*
X620077Y258847D01*
X620660Y259013D01*
X621243Y258847D01*
X621660Y258513D01*
X621910Y258097D01*
Y255680D01*
G01Y258097D02*
X622160Y258513D01*
X622577Y258847D01*
X623160Y259013D01*
X623743Y258847D01*
X624160Y258513D01*
X624410Y258013D01*
Y255680D01*
G01X627510Y259013D02*
Y255680D01*
G01Y260347D02*
X627343Y260430D01*
Y260597D01*
X627510Y260680D01*
X627677Y260597D01*
Y260430D01*
X627510Y260347D01*
G01X633110Y255680D02*
Y260680D01*
G01X602120Y310470D02*
Y313803D01*
G01Y312887D02*
X602370Y313303D01*
X602787Y313637D01*
X603370Y313803D01*
X603953Y313637D01*
X604370Y313303D01*
X604620Y312887D01*
Y310470D01*
G01Y312887D02*
X604870Y313303D01*
X605287Y313637D01*
X605870Y313803D01*
X606453Y313637D01*
X606870Y313303D01*
X607120Y312803D01*
Y310470D01*
G01X608803Y313803D02*
Y311470D01*
X609137Y310887D01*
X609637Y310553D01*
X610220Y310470D01*
X610803Y310553D01*
X611303Y310887D01*
X611637Y311470D01*
G01Y310470D02*
Y313803D01*
G01X614570Y311053D02*
X614987Y310720D01*
X615570Y310470D01*
X616070D01*
X616570Y310637D01*
X616903Y310887D01*
X617070Y311220D01*
X616987Y311720D01*
X616653Y311970D01*
X615153Y312470D01*
X614820Y313053D01*
X614987Y313470D01*
X615320Y313720D01*
X615820Y313803D01*
X616320Y313720D01*
X616820Y313470D01*
G01X621420Y315470D02*
Y310470D01*
G01X620253Y313803D02*
X622587D01*
G01X628687Y310470D02*
X625353Y312137D01*
X628687Y313803D01*
G01X630537Y310470D02*
X632620Y315470D01*
X634703Y310470D01*
G01X633953Y312220D02*
X631287D01*
G01X645320Y315470D02*
Y310470D01*
G01Y311220D02*
X644987Y310803D01*
X644487Y310553D01*
X643903Y310470D01*
X643237Y310637D01*
X642737Y311053D01*
X642403Y311553D01*
X642320Y312137D01*
X642403Y312720D01*
X642737Y313220D01*
X643237Y313637D01*
X643903Y313803D01*
X644487Y313720D01*
X644903Y313553D01*
X645320Y313220D01*
G01X649420Y313803D02*
Y310470D01*
G01Y315137D02*
X649253Y315220D01*
Y315387D01*
X649420Y315470D01*
X649587Y315387D01*
Y315220D01*
X649420Y315137D01*
G01X656520Y310470D02*
Y313803D01*
G01Y313220D02*
X656187Y313553D01*
X655687Y313720D01*
X655103Y313803D01*
X654520Y313637D01*
X654020Y313303D01*
X653687Y312803D01*
X653520Y312137D01*
X653687Y311470D01*
X654020Y310970D01*
X654520Y310637D01*
X655103Y310470D01*
X655687Y310553D01*
X656187Y310803D01*
X656520Y311137D01*
G01X658120Y310470D02*
Y313803D01*
G01Y312887D02*
X658370Y313303D01*
X658787Y313637D01*
X659370Y313803D01*
X659953Y313637D01*
X660370Y313303D01*
X660620Y312887D01*
Y310470D01*
G01Y312887D02*
X660870Y313303D01*
X661287Y313637D01*
X661870Y313803D01*
X662453Y313637D01*
X662870Y313303D01*
X663120Y312803D01*
Y310470D01*
G01X664970Y312720D02*
X667637D01*
X667387Y313303D01*
X666970Y313637D01*
X666387Y313803D01*
X665803Y313720D01*
X665303Y313470D01*
X664970Y312887D01*
X664803Y312387D01*
Y311887D01*
X664970Y311387D01*
X665387Y310887D01*
X665887Y310553D01*
X666470Y310470D01*
X667053Y310637D01*
X667637Y311137D01*
G01X671820Y315470D02*
Y310470D01*
G01X670653Y313803D02*
X672987D01*
G01X676170Y312720D02*
X678837D01*
X678587Y313303D01*
X678170Y313637D01*
X677587Y313803D01*
X677003Y313720D01*
X676503Y313470D01*
X676170Y312887D01*
X676003Y312387D01*
Y311887D01*
X676170Y311387D01*
X676587Y310887D01*
X677087Y310553D01*
X677670Y310470D01*
X678253Y310637D01*
X678837Y311137D01*
G01X681853Y310470D02*
Y313803D01*
G01Y313137D02*
X682270Y313470D01*
X682687Y313720D01*
X683270Y313803D01*
X683687Y313720D01*
X684187Y313470D01*
G01X602700Y319240D02*
Y324240D01*
G01Y321740D02*
X603117Y322240D01*
X603617Y322490D01*
X604117Y322573D01*
X604867Y322407D01*
X605367Y322073D01*
X605700Y321490D01*
Y320823D01*
X605533Y320157D01*
X605200Y319657D01*
X604617Y319323D01*
X604117Y319240D01*
X603617Y319323D01*
X603117Y319573D01*
X602700Y319990D01*
G01X608383Y322573D02*
Y320240D01*
X608717Y319657D01*
X609217Y319323D01*
X609800Y319240D01*
X610383Y319323D01*
X610883Y319657D01*
X611217Y320240D01*
G01Y319240D02*
Y322573D01*
G01X615400Y324240D02*
Y319240D01*
G01X614233Y322573D02*
X616567D01*
G01X627267Y321907D02*
X627600Y322157D01*
X627850Y322573D01*
X628017Y323157D01*
X627850Y323657D01*
X627517Y323990D01*
X626933Y324240D01*
X624683D01*
Y319240D01*
X627433D01*
X628017Y319573D01*
X628350Y320073D01*
X628517Y320657D01*
X628350Y321240D01*
X627850Y321740D01*
X627267Y321907D01*
X624683D01*
G01X639300Y324240D02*
Y319240D01*
G01Y319990D02*
X638967Y319573D01*
X638467Y319323D01*
X637883Y319240D01*
X637217Y319407D01*
X636717Y319823D01*
X636383Y320323D01*
X636300Y320907D01*
X636383Y321490D01*
X636717Y321990D01*
X637217Y322407D01*
X637883Y322573D01*
X638467Y322490D01*
X638883Y322323D01*
X639300Y321990D01*
G01X643400Y322573D02*
Y319240D01*
G01Y323907D02*
X643233Y323990D01*
Y324157D01*
X643400Y324240D01*
X643567Y324157D01*
Y323990D01*
X643400Y323907D01*
G01X650500Y319240D02*
Y322573D01*
G01Y321990D02*
X650167Y322323D01*
X649667Y322490D01*
X649083Y322573D01*
X648500Y322407D01*
X648000Y322073D01*
X647667Y321573D01*
X647500Y320907D01*
X647667Y320240D01*
X648000Y319740D01*
X648500Y319407D01*
X649083Y319240D01*
X649667Y319323D01*
X650167Y319573D01*
X650500Y319907D01*
G01X652100Y319240D02*
Y322573D01*
G01Y321657D02*
X652350Y322073D01*
X652767Y322407D01*
X653350Y322573D01*
X653933Y322407D01*
X654350Y322073D01*
X654600Y321657D01*
Y319240D01*
G01Y321657D02*
X654850Y322073D01*
X655267Y322407D01*
X655850Y322573D01*
X656433Y322407D01*
X656850Y322073D01*
X657100Y321573D01*
Y319240D01*
G01X658950Y321490D02*
X661617D01*
X661367Y322073D01*
X660950Y322407D01*
X660367Y322573D01*
X659783Y322490D01*
X659283Y322240D01*
X658950Y321657D01*
X658783Y321157D01*
Y320657D01*
X658950Y320157D01*
X659367Y319657D01*
X659867Y319323D01*
X660450Y319240D01*
X661033Y319407D01*
X661617Y319907D01*
G01X665800Y324240D02*
Y319240D01*
G01X664633Y322573D02*
X666967D01*
G01X670150Y321490D02*
X672817D01*
X672567Y322073D01*
X672150Y322407D01*
X671567Y322573D01*
X670983Y322490D01*
X670483Y322240D01*
X670150Y321657D01*
X669983Y321157D01*
Y320657D01*
X670150Y320157D01*
X670567Y319657D01*
X671067Y319323D01*
X671650Y319240D01*
X672233Y319407D01*
X672817Y319907D01*
G01X675833Y319240D02*
Y322573D01*
G01Y321907D02*
X676250Y322240D01*
X676667Y322490D01*
X677250Y322573D01*
X677667Y322490D01*
X678167Y322240D01*
G01X608397Y295230D02*
X605063Y296897D01*
X608397Y298563D01*
G01X610913Y295813D02*
X611497Y295397D01*
X612163Y295230D01*
X612830Y295397D01*
X613413Y295897D01*
X613830Y296647D01*
X613997Y297397D01*
Y298313D01*
X613830Y299063D01*
X613413Y299730D01*
X612913Y300063D01*
X612330Y300230D01*
X611663Y300063D01*
X611163Y299730D01*
X610830Y299230D01*
X610663Y298563D01*
X610830Y297980D01*
X611247Y297397D01*
X611747Y297063D01*
X612330Y296980D01*
X612997Y297147D01*
X613497Y297563D01*
X613997Y298313D01*
G01X617930Y300230D02*
X617263Y300063D01*
X616763Y299647D01*
X616430Y299147D01*
X616180Y298480D01*
X616097Y297730D01*
X616180Y296980D01*
X616430Y296313D01*
X616763Y295813D01*
X617263Y295397D01*
X617930Y295230D01*
X618597Y295397D01*
X619097Y295813D01*
X619430Y296313D01*
X619680Y296980D01*
X619763Y297730D01*
X619680Y298480D01*
X619430Y299147D01*
X619097Y299647D01*
X618597Y300063D01*
X617930Y300230D01*
G01X630630D02*
Y295230D01*
G01Y295980D02*
X630297Y295563D01*
X629797Y295313D01*
X629213Y295230D01*
X628547Y295397D01*
X628047Y295813D01*
X627713Y296313D01*
X627630Y296897D01*
X627713Y297480D01*
X628047Y297980D01*
X628547Y298397D01*
X629213Y298563D01*
X629797Y298480D01*
X630213Y298313D01*
X630630Y297980D01*
G01X633480Y297480D02*
X636147D01*
X635897Y298063D01*
X635480Y298397D01*
X634897Y298563D01*
X634313Y298480D01*
X633813Y298230D01*
X633480Y297647D01*
X633313Y297147D01*
Y296647D01*
X633480Y296147D01*
X633897Y295647D01*
X634397Y295313D01*
X634980Y295230D01*
X635563Y295397D01*
X636147Y295897D01*
G01X639163Y293980D02*
X639747Y293647D01*
X640413Y293563D01*
X640997Y293647D01*
X641497Y294063D01*
X641830Y294647D01*
Y298563D01*
G01Y297897D02*
X641497Y298230D01*
X640997Y298480D01*
X640413Y298563D01*
X639747Y298397D01*
X639330Y298063D01*
X638997Y297480D01*
X638830Y296897D01*
X638913Y296397D01*
X639247Y295813D01*
X639747Y295397D01*
X640413Y295230D01*
X640913Y295313D01*
X641497Y295647D01*
X641830Y295980D01*
G01X644763Y295230D02*
Y298563D01*
G01Y297897D02*
X645180Y298230D01*
X645597Y298480D01*
X646180Y298563D01*
X646597Y298480D01*
X647097Y298230D01*
G01X650280Y297480D02*
X652947D01*
X652697Y298063D01*
X652280Y298397D01*
X651697Y298563D01*
X651113Y298480D01*
X650613Y298230D01*
X650280Y297647D01*
X650113Y297147D01*
Y296647D01*
X650280Y296147D01*
X650697Y295647D01*
X651197Y295313D01*
X651780Y295230D01*
X652363Y295397D01*
X652947Y295897D01*
G01X655880Y297480D02*
X658547D01*
X658297Y298063D01*
X657880Y298397D01*
X657297Y298563D01*
X656713Y298480D01*
X656213Y298230D01*
X655880Y297647D01*
X655713Y297147D01*
Y296647D01*
X655880Y296147D01*
X656297Y295647D01*
X656797Y295313D01*
X657380Y295230D01*
X657963Y295397D01*
X658547Y295897D01*
G01X603783Y329260D02*
X607117Y330927D01*
X603783Y332593D01*
G01X609967Y330177D02*
X612133D01*
G01Y331677D02*
X609967D01*
G01X616483Y329260D02*
X616650Y330343D01*
X616900Y331260D01*
X617233Y332093D01*
X617650Y333010D01*
X618317Y334260D01*
X614983D01*
G01X622250D02*
X621583Y334093D01*
X621083Y333677D01*
X620750Y333177D01*
X620500Y332510D01*
X620417Y331760D01*
X620500Y331010D01*
X620750Y330343D01*
X621083Y329843D01*
X621583Y329427D01*
X622250Y329260D01*
X622917Y329427D01*
X623417Y329843D01*
X623750Y330343D01*
X624000Y331010D01*
X624083Y331760D01*
X624000Y332510D01*
X623750Y333177D01*
X623417Y333677D01*
X622917Y334093D01*
X622250Y334260D01*
G01X626350Y329093D02*
X629350Y334260D01*
G01X626350D02*
X625850Y334093D01*
X625600Y333843D01*
X625433Y333343D01*
X625600Y332843D01*
X625850Y332593D01*
X626350Y332427D01*
X626850Y332593D01*
X627100Y332843D01*
X627267Y333343D01*
X627100Y333843D01*
X626850Y334093D01*
X626350Y334260D01*
G01X629350Y330927D02*
X628850Y330760D01*
X628600Y330510D01*
X628433Y330010D01*
X628600Y329510D01*
X628850Y329260D01*
X629350Y329093D01*
X629850Y329260D01*
X630100Y329510D01*
X630267Y330010D01*
X630100Y330510D01*
X629850Y330760D01*
X629350Y330927D01*
G01X633283Y328343D02*
X633617Y329427D01*
G01X605763Y349687D02*
X607763D01*
G01X606680Y350770D02*
Y348603D01*
G01X610780Y347853D02*
X613780Y353020D01*
G01X616797Y349687D02*
X618963D01*
G01X623480Y348020D02*
Y353020D01*
X622480Y352020D01*
G01Y348020D02*
X624480D01*
G01X626580D02*
Y351353D01*
G01Y350437D02*
X626830Y350853D01*
X627247Y351187D01*
X627830Y351353D01*
X628413Y351187D01*
X628830Y350853D01*
X629080Y350437D01*
Y348020D01*
G01Y350437D02*
X629330Y350853D01*
X629747Y351187D01*
X630330Y351353D01*
X630913Y351187D01*
X631330Y350853D01*
X631580Y350353D01*
Y348020D01*
G01X634680Y351353D02*
Y348020D01*
G01Y352687D02*
X634513Y352770D01*
Y352937D01*
X634680Y353020D01*
X634847Y352937D01*
Y352770D01*
X634680Y352687D01*
G01X640280Y348020D02*
Y353020D01*
G01X608333Y393000D02*
Y398000D01*
X610500Y393833D01*
X612667Y398000D01*
Y393000D01*
G01X614683Y396333D02*
Y394000D01*
X615017Y393417D01*
X615517Y393083D01*
X616100Y393000D01*
X616683Y393083D01*
X617183Y393417D01*
X617517Y394000D01*
G01Y393000D02*
Y396333D01*
G01X620450Y393583D02*
X620867Y393250D01*
X621450Y393000D01*
X621950D01*
X622450Y393167D01*
X622783Y393417D01*
X622950Y393750D01*
X622867Y394250D01*
X622533Y394500D01*
X621033Y395000D01*
X620700Y395583D01*
X620867Y396000D01*
X621200Y396250D01*
X621700Y396333D01*
X622200Y396250D01*
X622700Y396000D01*
G01X627300Y398000D02*
Y393000D01*
G01X626133Y396333D02*
X628467D01*
G01X638000Y393000D02*
Y397250D01*
X638167Y397667D01*
X638500Y397917D01*
X639000Y398000D01*
X639500Y397833D01*
X639750Y397417D01*
G01X638750Y396000D02*
X637083D01*
G01X644100Y393000D02*
X643600Y393083D01*
X643100Y393417D01*
X642767Y394000D01*
X642600Y394667D01*
X642767Y395333D01*
X643100Y395917D01*
X643600Y396250D01*
X644100Y396333D01*
X644600Y396250D01*
X645100Y395917D01*
X645433Y395333D01*
X645517Y394667D01*
X645433Y394000D01*
X645100Y393417D01*
X644600Y393083D01*
X644100Y393000D01*
G01X649700D02*
Y398000D01*
G01X655300Y393000D02*
Y398000D01*
G01X660900Y393000D02*
X660400Y393083D01*
X659900Y393417D01*
X659567Y394000D01*
X659400Y394667D01*
X659567Y395333D01*
X659900Y395917D01*
X660400Y396250D01*
X660900Y396333D01*
X661400Y396250D01*
X661900Y395917D01*
X662233Y395333D01*
X662317Y394667D01*
X662233Y394000D01*
X661900Y393417D01*
X661400Y393083D01*
X660900Y393000D01*
G01X664417Y396333D02*
X665417Y393000D01*
X666500Y396333D01*
X667583Y393000D01*
X668583Y396333D01*
G01X595500Y679000D02*
Y396000D01*
G01X605810Y429990D02*
Y434240D01*
X605977Y434657D01*
X606310Y434907D01*
X606810Y434990D01*
X607310Y434823D01*
X607560Y434407D01*
G01X606560Y432990D02*
X604893D01*
G01X611910Y429990D02*
X611410Y430073D01*
X610910Y430407D01*
X610577Y430990D01*
X610410Y431657D01*
X610577Y432323D01*
X610910Y432907D01*
X611410Y433240D01*
X611910Y433323D01*
X612410Y433240D01*
X612910Y432907D01*
X613243Y432323D01*
X613327Y431657D01*
X613243Y430990D01*
X612910Y430407D01*
X612410Y430073D01*
X611910Y429990D01*
G01X617510D02*
Y434990D01*
G01X623110Y429990D02*
Y434990D01*
G01X628710Y429990D02*
X628210Y430073D01*
X627710Y430407D01*
X627377Y430990D01*
X627210Y431657D01*
X627377Y432323D01*
X627710Y432907D01*
X628210Y433240D01*
X628710Y433323D01*
X629210Y433240D01*
X629710Y432907D01*
X630043Y432323D01*
X630127Y431657D01*
X630043Y430990D01*
X629710Y430407D01*
X629210Y430073D01*
X628710Y429990D01*
G01X632227Y433323D02*
X633227Y429990D01*
X634310Y433323D01*
X635393Y429990D01*
X636393Y433323D01*
G01X647010Y434990D02*
Y429990D01*
G01Y430740D02*
X646677Y430323D01*
X646177Y430073D01*
X645593Y429990D01*
X644927Y430157D01*
X644427Y430573D01*
X644093Y431073D01*
X644010Y431657D01*
X644093Y432240D01*
X644427Y432740D01*
X644927Y433157D01*
X645593Y433323D01*
X646177Y433240D01*
X646593Y433073D01*
X647010Y432740D01*
G01X649943Y429990D02*
Y433323D01*
G01Y432657D02*
X650360Y432990D01*
X650777Y433240D01*
X651360Y433323D01*
X651777Y433240D01*
X652277Y432990D01*
G01X658210Y429990D02*
Y433323D01*
G01Y432740D02*
X657877Y433073D01*
X657377Y433240D01*
X656793Y433323D01*
X656210Y433157D01*
X655710Y432823D01*
X655377Y432323D01*
X655210Y431657D01*
X655377Y430990D01*
X655710Y430490D01*
X656210Y430157D01*
X656793Y429990D01*
X657377Y430073D01*
X657877Y430323D01*
X658210Y430657D01*
G01X660227Y433323D02*
X661227Y429990D01*
X662310Y433323D01*
X663393Y429990D01*
X664393Y433323D01*
G01X667910D02*
Y429990D01*
G01Y434657D02*
X667743Y434740D01*
Y434907D01*
X667910Y434990D01*
X668077Y434907D01*
Y434740D01*
X667910Y434657D01*
G01X672093Y429990D02*
Y433323D01*
G01Y432490D02*
X672427Y432907D01*
X672927Y433240D01*
X673593Y433323D01*
X674177Y433240D01*
X674677Y432907D01*
X674927Y432323D01*
Y429990D01*
G01X677943Y428740D02*
X678527Y428407D01*
X679193Y428323D01*
X679777Y428407D01*
X680277Y428823D01*
X680610Y429407D01*
Y433323D01*
G01Y432657D02*
X680277Y432990D01*
X679777Y433240D01*
X679193Y433323D01*
X678527Y433157D01*
X678110Y432823D01*
X677777Y432240D01*
X677610Y431657D01*
X677693Y431157D01*
X678027Y430573D01*
X678527Y430157D01*
X679193Y429990D01*
X679693Y430073D01*
X680277Y430407D01*
X680610Y430740D01*
G01X685127Y428323D02*
X685960Y429157D01*
X686377Y429990D01*
Y433323D01*
X685960Y434157D01*
X685127Y434990D01*
G01X606903Y440587D02*
X608903D01*
G01X607820Y441670D02*
Y439503D01*
G01X611920Y438753D02*
X614920Y443920D01*
G01X617937Y440587D02*
X620103D01*
G01X622787Y439670D02*
X623287Y439253D01*
X623870Y439003D01*
X624620Y438920D01*
X625370Y439087D01*
X625953Y439420D01*
X626370Y440003D01*
X626453Y440670D01*
X626287Y441337D01*
X625870Y441753D01*
X625287Y442087D01*
X624703Y442170D01*
X624120Y442087D01*
X623370Y441753D01*
X623620Y443920D01*
X625870D01*
G01X627720Y438920D02*
Y442253D01*
G01Y441337D02*
X627970Y441753D01*
X628387Y442087D01*
X628970Y442253D01*
X629553Y442087D01*
X629970Y441753D01*
X630220Y441337D01*
Y438920D01*
G01Y441337D02*
X630470Y441753D01*
X630887Y442087D01*
X631470Y442253D01*
X632053Y442087D01*
X632470Y441753D01*
X632720Y441253D01*
Y438920D01*
G01X635820Y442253D02*
Y438920D01*
G01Y443587D02*
X635653Y443670D01*
Y443837D01*
X635820Y443920D01*
X635987Y443837D01*
Y443670D01*
X635820Y443587D01*
G01X641420Y438920D02*
Y443920D01*
G01X607500Y452000D02*
Y457000D01*
X606500Y456000D01*
G01Y452000D02*
X608500D01*
G01X613100Y451833D02*
X612933Y451917D01*
Y452083D01*
X613100Y452167D01*
X613267Y452083D01*
Y451917D01*
X613100Y451833D01*
G01X618700Y457000D02*
X618033Y456833D01*
X617533Y456417D01*
X617200Y455917D01*
X616950Y455250D01*
X616867Y454500D01*
X616950Y453750D01*
X617200Y453083D01*
X617533Y452583D01*
X618033Y452167D01*
X618700Y452000D01*
X619367Y452167D01*
X619867Y452583D01*
X620200Y453083D01*
X620450Y453750D01*
X620533Y454500D01*
X620450Y455250D01*
X620200Y455917D01*
X619867Y456417D01*
X619367Y456833D01*
X618700Y457000D01*
G01X621800Y452000D02*
Y455333D01*
G01Y454417D02*
X622050Y454833D01*
X622467Y455167D01*
X623050Y455333D01*
X623633Y455167D01*
X624050Y454833D01*
X624300Y454417D01*
Y452000D01*
G01Y454417D02*
X624550Y454833D01*
X624967Y455167D01*
X625550Y455333D01*
X626133Y455167D01*
X626550Y454833D01*
X626800Y454333D01*
Y452000D01*
G01X629900Y455333D02*
Y452000D01*
G01Y456667D02*
X629733Y456750D01*
Y456917D01*
X629900Y457000D01*
X630067Y456917D01*
Y456750D01*
X629900Y456667D01*
G01X635500Y452000D02*
Y457000D01*
G01X644200Y452000D02*
Y455333D01*
G01Y454417D02*
X644450Y454833D01*
X644867Y455167D01*
X645450Y455333D01*
X646033Y455167D01*
X646450Y454833D01*
X646700Y454417D01*
Y452000D01*
G01Y454417D02*
X646950Y454833D01*
X647367Y455167D01*
X647950Y455333D01*
X648533Y455167D01*
X648950Y454833D01*
X649200Y454333D01*
Y452000D01*
G01X653800D02*
Y455333D01*
G01Y454750D02*
X653467Y455083D01*
X652967Y455250D01*
X652383Y455333D01*
X651800Y455167D01*
X651300Y454833D01*
X650967Y454333D01*
X650800Y453667D01*
X650967Y453000D01*
X651300Y452500D01*
X651800Y452167D01*
X652383Y452000D01*
X652967Y452083D01*
X653467Y452333D01*
X653800Y452667D01*
G01X656650Y455333D02*
X659150Y452000D01*
G01Y455333D02*
X656650Y452000D01*
G01X606583Y471667D02*
X608583D01*
G01X607500Y472750D02*
Y470583D01*
G01X611600Y469833D02*
X614600Y475000D01*
G01X617617Y471667D02*
X619783D01*
G01X622467Y470750D02*
X622967Y470333D01*
X623550Y470083D01*
X624300Y470000D01*
X625050Y470167D01*
X625633Y470500D01*
X626050Y471083D01*
X626133Y471750D01*
X625967Y472417D01*
X625550Y472833D01*
X624967Y473167D01*
X624383Y473250D01*
X623800Y473167D01*
X623050Y472833D01*
X623300Y475000D01*
X625550D01*
G01X627400Y470000D02*
Y473333D01*
G01Y472417D02*
X627650Y472833D01*
X628067Y473167D01*
X628650Y473333D01*
X629233Y473167D01*
X629650Y472833D01*
X629900Y472417D01*
Y470000D01*
G01Y472417D02*
X630150Y472833D01*
X630567Y473167D01*
X631150Y473333D01*
X631733Y473167D01*
X632150Y472833D01*
X632400Y472333D01*
Y470000D01*
G01X635500Y473333D02*
Y470000D01*
G01Y474667D02*
X635333Y474750D01*
Y474917D01*
X635500Y475000D01*
X635667Y474917D01*
Y474750D01*
X635500Y474667D01*
G01X641100Y470000D02*
Y475000D01*
G01X606583Y486667D02*
X608583D01*
G01X607500Y487750D02*
Y485583D01*
G01X611600Y484833D02*
X614600Y490000D01*
G01X617617Y486667D02*
X619783D01*
G01X622467Y485750D02*
X622967Y485333D01*
X623550Y485083D01*
X624300Y485000D01*
X625050Y485167D01*
X625633Y485500D01*
X626050Y486083D01*
X626133Y486750D01*
X625967Y487417D01*
X625550Y487833D01*
X624967Y488167D01*
X624383Y488250D01*
X623800Y488167D01*
X623050Y487833D01*
X623300Y490000D01*
X625550D01*
G01X627400Y485000D02*
Y488333D01*
G01Y487417D02*
X627650Y487833D01*
X628067Y488167D01*
X628650Y488333D01*
X629233Y488167D01*
X629650Y487833D01*
X629900Y487417D01*
Y485000D01*
G01Y487417D02*
X630150Y487833D01*
X630567Y488167D01*
X631150Y488333D01*
X631733Y488167D01*
X632150Y487833D01*
X632400Y487333D01*
Y485000D01*
G01X635500Y488333D02*
Y485000D01*
G01Y489667D02*
X635333Y489750D01*
Y489917D01*
X635500Y490000D01*
X635667Y489917D01*
Y489750D01*
X635500Y489667D01*
G01X641100Y485000D02*
Y490000D01*
G01X606583Y546667D02*
X608583D01*
G01X607500Y547750D02*
Y545583D01*
G01X611600Y544833D02*
X614600Y550000D01*
G01X617617Y546667D02*
X619783D01*
G01X622717Y549167D02*
X623217Y549667D01*
X623800Y549917D01*
X624467Y550000D01*
X625300Y549833D01*
X625883Y549417D01*
X626050Y548917D01*
X625967Y548417D01*
X625633Y548000D01*
X623967Y547167D01*
X623217Y546583D01*
X622717Y545750D01*
X622550Y545000D01*
X626050D01*
G01X627400D02*
Y548333D01*
G01Y547417D02*
X627650Y547833D01*
X628067Y548167D01*
X628650Y548333D01*
X629233Y548167D01*
X629650Y547833D01*
X629900Y547417D01*
Y545000D01*
G01Y547417D02*
X630150Y547833D01*
X630567Y548167D01*
X631150Y548333D01*
X631733Y548167D01*
X632150Y547833D01*
X632400Y547333D01*
Y545000D01*
G01X635500Y548333D02*
Y545000D01*
G01Y549667D02*
X635333Y549750D01*
Y549917D01*
X635500Y550000D01*
X635667Y549917D01*
Y549750D01*
X635500Y549667D01*
G01X641100Y545000D02*
Y550000D01*
G01X606583Y501667D02*
X608583D01*
G01X607500Y502750D02*
Y500583D01*
G01X611267Y501000D02*
X611767Y500417D01*
X612433Y500083D01*
X613183Y500000D01*
X613850Y500083D01*
X614517Y500500D01*
X614933Y501000D01*
X615017Y501500D01*
X614850Y502083D01*
X614267Y502500D01*
X613683Y502667D01*
X612933D01*
G01X613683D02*
X614183Y502917D01*
X614600Y503333D01*
X614767Y503833D01*
X614600Y504333D01*
X614183Y504750D01*
X613433Y505000D01*
X612683Y504917D01*
X611933Y504583D01*
G01X617200Y499833D02*
X620200Y505000D01*
G01X623217Y501667D02*
X625383D01*
G01X629900Y505000D02*
X629233Y504833D01*
X628733Y504417D01*
X628400Y503917D01*
X628150Y503250D01*
X628067Y502500D01*
X628150Y501750D01*
X628400Y501083D01*
X628733Y500583D01*
X629233Y500167D01*
X629900Y500000D01*
X630567Y500167D01*
X631067Y500583D01*
X631400Y501083D01*
X631650Y501750D01*
X631733Y502500D01*
X631650Y503250D01*
X631400Y503917D01*
X631067Y504417D01*
X630567Y504833D01*
X629900Y505000D01*
G01X633000Y500000D02*
Y503333D01*
G01Y502417D02*
X633250Y502833D01*
X633667Y503167D01*
X634250Y503333D01*
X634833Y503167D01*
X635250Y502833D01*
X635500Y502417D01*
Y500000D01*
G01Y502417D02*
X635750Y502833D01*
X636167Y503167D01*
X636750Y503333D01*
X637333Y503167D01*
X637750Y502833D01*
X638000Y502333D01*
Y500000D01*
G01X641100Y503333D02*
Y500000D01*
G01Y504667D02*
X640933Y504750D01*
Y504917D01*
X641100Y505000D01*
X641267Y504917D01*
Y504750D01*
X641100Y504667D01*
G01X646700Y500000D02*
Y505000D01*
G01X606583Y516667D02*
X608583D01*
G01X607500Y517750D02*
Y515583D01*
G01X611600Y514833D02*
X614600Y520000D01*
G01X617617Y516667D02*
X619783D01*
G01X622717Y519167D02*
X623217Y519667D01*
X623800Y519917D01*
X624467Y520000D01*
X625300Y519833D01*
X625883Y519417D01*
X626050Y518917D01*
X625967Y518417D01*
X625633Y518000D01*
X623967Y517167D01*
X623217Y516583D01*
X622717Y515750D01*
X622550Y515000D01*
X626050D01*
G01X627400D02*
Y518333D01*
G01Y517417D02*
X627650Y517833D01*
X628067Y518167D01*
X628650Y518333D01*
X629233Y518167D01*
X629650Y517833D01*
X629900Y517417D01*
Y515000D01*
G01Y517417D02*
X630150Y517833D01*
X630567Y518167D01*
X631150Y518333D01*
X631733Y518167D01*
X632150Y517833D01*
X632400Y517333D01*
Y515000D01*
G01X635500Y518333D02*
Y515000D01*
G01Y519667D02*
X635333Y519750D01*
Y519917D01*
X635500Y520000D01*
X635667Y519917D01*
Y519750D01*
X635500Y519667D01*
G01X641100Y515000D02*
Y520000D01*
G01X606583Y530167D02*
X608583D01*
G01X607500Y531250D02*
Y529083D01*
G01X611600Y528333D02*
X614600Y533500D01*
G01X617617Y530167D02*
X619783D01*
G01X622467Y529500D02*
X622967Y528917D01*
X623633Y528583D01*
X624383Y528500D01*
X625050Y528583D01*
X625717Y529000D01*
X626133Y529500D01*
X626217Y530000D01*
X626050Y530583D01*
X625467Y531000D01*
X624883Y531167D01*
X624133D01*
G01X624883D02*
X625383Y531417D01*
X625800Y531833D01*
X625967Y532333D01*
X625800Y532833D01*
X625383Y533250D01*
X624633Y533500D01*
X623883Y533417D01*
X623133Y533083D01*
G01X627400Y528500D02*
Y531833D01*
G01Y530917D02*
X627650Y531333D01*
X628067Y531667D01*
X628650Y531833D01*
X629233Y531667D01*
X629650Y531333D01*
X629900Y530917D01*
Y528500D01*
G01Y530917D02*
X630150Y531333D01*
X630567Y531667D01*
X631150Y531833D01*
X631733Y531667D01*
X632150Y531333D01*
X632400Y530833D01*
Y528500D01*
G01X635500Y531833D02*
Y528500D01*
G01Y533167D02*
X635333Y533250D01*
Y533417D01*
X635500Y533500D01*
X635667Y533417D01*
Y533250D01*
X635500Y533167D01*
G01X641100Y528500D02*
Y533500D01*
G01X606583Y561667D02*
X608583D01*
G01X607500Y562750D02*
Y560583D01*
G01X611600Y559833D02*
X614600Y565000D01*
G01X617617Y561667D02*
X619783D01*
G01X622717Y564167D02*
X623217Y564667D01*
X623800Y564917D01*
X624467Y565000D01*
X625300Y564833D01*
X625883Y564417D01*
X626050Y563917D01*
X625967Y563417D01*
X625633Y563000D01*
X623967Y562167D01*
X623217Y561583D01*
X622717Y560750D01*
X622550Y560000D01*
X626050D01*
G01X627400D02*
Y563333D01*
G01Y562417D02*
X627650Y562833D01*
X628067Y563167D01*
X628650Y563333D01*
X629233Y563167D01*
X629650Y562833D01*
X629900Y562417D01*
Y560000D01*
G01Y562417D02*
X630150Y562833D01*
X630567Y563167D01*
X631150Y563333D01*
X631733Y563167D01*
X632150Y562833D01*
X632400Y562333D01*
Y560000D01*
G01X635500Y563333D02*
Y560000D01*
G01Y564667D02*
X635333Y564750D01*
Y564917D01*
X635500Y565000D01*
X635667Y564917D01*
Y564750D01*
X635500Y564667D01*
G01X641100Y560000D02*
Y565000D01*
G01X606583Y620167D02*
X608583D01*
G01X607500Y621250D02*
Y619083D01*
G01X611600Y618333D02*
X614600Y623500D01*
G01X617617Y620167D02*
X619783D01*
G01X622717Y622667D02*
X623217Y623167D01*
X623800Y623417D01*
X624467Y623500D01*
X625300Y623333D01*
X625883Y622917D01*
X626050Y622417D01*
X625967Y621917D01*
X625633Y621500D01*
X623967Y620667D01*
X623217Y620083D01*
X622717Y619250D01*
X622550Y618500D01*
X626050D01*
G01X627400D02*
Y621833D01*
G01Y620917D02*
X627650Y621333D01*
X628067Y621667D01*
X628650Y621833D01*
X629233Y621667D01*
X629650Y621333D01*
X629900Y620917D01*
Y618500D01*
G01Y620917D02*
X630150Y621333D01*
X630567Y621667D01*
X631150Y621833D01*
X631733Y621667D01*
X632150Y621333D01*
X632400Y620833D01*
Y618500D01*
G01X635500Y621833D02*
Y618500D01*
G01Y623167D02*
X635333Y623250D01*
Y623417D01*
X635500Y623500D01*
X635667Y623417D01*
Y623250D01*
X635500Y623167D01*
G01X641100Y618500D02*
Y623500D01*
G01X606583Y591667D02*
X608583D01*
G01X607500Y592750D02*
Y590583D01*
G01X611600Y589833D02*
X614600Y595000D01*
G01X617617Y591667D02*
X619783D01*
G01X622467Y591000D02*
X622967Y590417D01*
X623633Y590083D01*
X624383Y590000D01*
X625050Y590083D01*
X625717Y590500D01*
X626133Y591000D01*
X626217Y591500D01*
X626050Y592083D01*
X625467Y592500D01*
X624883Y592667D01*
X624133D01*
G01X624883D02*
X625383Y592917D01*
X625800Y593333D01*
X625967Y593833D01*
X625800Y594333D01*
X625383Y594750D01*
X624633Y595000D01*
X623883Y594917D01*
X623133Y594583D01*
G01X627400Y590000D02*
Y593333D01*
G01Y592417D02*
X627650Y592833D01*
X628067Y593167D01*
X628650Y593333D01*
X629233Y593167D01*
X629650Y592833D01*
X629900Y592417D01*
Y590000D01*
G01Y592417D02*
X630150Y592833D01*
X630567Y593167D01*
X631150Y593333D01*
X631733Y593167D01*
X632150Y592833D01*
X632400Y592333D01*
Y590000D01*
G01X635500Y593333D02*
Y590000D01*
G01Y594667D02*
X635333Y594750D01*
Y594917D01*
X635500Y595000D01*
X635667Y594917D01*
Y594750D01*
X635500Y594667D01*
G01X641100Y590000D02*
Y595000D01*
G01X605417Y603500D02*
X607500Y608500D01*
X609583Y603500D01*
G01X608833Y605250D02*
X606167D01*
G01X613100Y603500D02*
Y608500D01*
G01X618700Y603500D02*
Y608500D01*
G01X624300Y603500D02*
X623800Y603583D01*
X623300Y603917D01*
X622967Y604500D01*
X622800Y605167D01*
X622967Y605833D01*
X623300Y606417D01*
X623800Y606750D01*
X624300Y606833D01*
X624800Y606750D01*
X625300Y606417D01*
X625633Y605833D01*
X625717Y605167D01*
X625633Y604500D01*
X625300Y603917D01*
X624800Y603583D01*
X624300Y603500D01*
G01X627817Y606833D02*
X628817Y603500D01*
X629900Y606833D01*
X630983Y603500D01*
X631983Y606833D01*
G01X605353Y638700D02*
Y643700D01*
X607520Y639533D01*
X609687Y643700D01*
Y638700D01*
G01X611703Y642033D02*
Y639700D01*
X612037Y639117D01*
X612537Y638783D01*
X613120Y638700D01*
X613703Y638783D01*
X614203Y639117D01*
X614537Y639700D01*
G01Y638700D02*
Y642033D01*
G01X617470Y639283D02*
X617887Y638950D01*
X618470Y638700D01*
X618970D01*
X619470Y638867D01*
X619803Y639117D01*
X619970Y639450D01*
X619887Y639950D01*
X619553Y640200D01*
X618053Y640700D01*
X617720Y641283D01*
X617887Y641700D01*
X618220Y641950D01*
X618720Y642033D01*
X619220Y641950D01*
X619720Y641700D01*
G01X624320Y643700D02*
Y638700D01*
G01X623153Y642033D02*
X625487D01*
G01X635020Y638700D02*
Y642950D01*
X635187Y643367D01*
X635520Y643617D01*
X636020Y643700D01*
X636520Y643533D01*
X636770Y643117D01*
G01X635770Y641700D02*
X634103D01*
G01X641120Y638700D02*
X640620Y638783D01*
X640120Y639117D01*
X639787Y639700D01*
X639620Y640367D01*
X639787Y641033D01*
X640120Y641617D01*
X640620Y641950D01*
X641120Y642033D01*
X641620Y641950D01*
X642120Y641617D01*
X642453Y641033D01*
X642537Y640367D01*
X642453Y639700D01*
X642120Y639117D01*
X641620Y638783D01*
X641120Y638700D01*
G01X646720D02*
Y643700D01*
G01X652320Y638700D02*
Y643700D01*
G01X657920Y638700D02*
X657420Y638783D01*
X656920Y639117D01*
X656587Y639700D01*
X656420Y640367D01*
X656587Y641033D01*
X656920Y641617D01*
X657420Y641950D01*
X657920Y642033D01*
X658420Y641950D01*
X658920Y641617D01*
X659253Y641033D01*
X659337Y640367D01*
X659253Y639700D01*
X658920Y639117D01*
X658420Y638783D01*
X657920Y638700D01*
G01X661437Y642033D02*
X662437Y638700D01*
X663520Y642033D01*
X664603Y638700D01*
X665603Y642033D01*
G01X606583Y575167D02*
X608583D01*
G01X607500Y576250D02*
Y574083D01*
G01X611517Y577667D02*
X612017Y578167D01*
X612600Y578417D01*
X613267Y578500D01*
X614100Y578333D01*
X614683Y577917D01*
X614850Y577417D01*
X614767Y576917D01*
X614433Y576500D01*
X612767Y575667D01*
X612017Y575083D01*
X611517Y574250D01*
X611350Y573500D01*
X614850D01*
G01X617200Y573333D02*
X620200Y578500D01*
G01X623217Y575167D02*
X625383D01*
G01X630900Y573500D02*
Y578500D01*
X627817Y574917D01*
X631983D01*
G01X633000Y573500D02*
Y576833D01*
G01Y575917D02*
X633250Y576333D01*
X633667Y576667D01*
X634250Y576833D01*
X634833Y576667D01*
X635250Y576333D01*
X635500Y575917D01*
Y573500D01*
G01Y575917D02*
X635750Y576333D01*
X636167Y576667D01*
X636750Y576833D01*
X637333Y576667D01*
X637750Y576333D01*
X638000Y575833D01*
Y573500D01*
G01X641100Y576833D02*
Y573500D01*
G01Y578167D02*
X640933Y578250D01*
Y578417D01*
X641100Y578500D01*
X641267Y578417D01*
Y578250D01*
X641100Y578167D01*
G01X646700Y573500D02*
Y578500D01*
G01X617500Y668500D02*
Y663500D01*
G01X615583Y668500D02*
X619417D01*
G01X623100Y663500D02*
X622600Y663583D01*
X622100Y663917D01*
X621767Y664500D01*
X621600Y665167D01*
X621767Y665833D01*
X622100Y666417D01*
X622600Y666750D01*
X623100Y666833D01*
X623600Y666750D01*
X624100Y666417D01*
X624433Y665833D01*
X624517Y665167D01*
X624433Y664500D01*
X624100Y663917D01*
X623600Y663583D01*
X623100Y663500D01*
G01X628700D02*
Y668500D01*
G01X633050Y665750D02*
X635717D01*
X635467Y666333D01*
X635050Y666667D01*
X634467Y666833D01*
X633883Y666750D01*
X633383Y666500D01*
X633050Y665917D01*
X632883Y665417D01*
Y664917D01*
X633050Y664417D01*
X633467Y663917D01*
X633967Y663583D01*
X634550Y663500D01*
X635133Y663667D01*
X635717Y664167D01*
G01X638733Y663500D02*
Y666833D01*
G01Y666167D02*
X639150Y666500D01*
X639567Y666750D01*
X640150Y666833D01*
X640567Y666750D01*
X641067Y666500D01*
G01X647000Y663500D02*
Y666833D01*
G01Y666250D02*
X646667Y666583D01*
X646167Y666750D01*
X645583Y666833D01*
X645000Y666667D01*
X644500Y666333D01*
X644167Y665833D01*
X644000Y665167D01*
X644167Y664500D01*
X644500Y664000D01*
X645000Y663667D01*
X645583Y663500D01*
X646167Y663583D01*
X646667Y663833D01*
X647000Y664167D01*
G01X649683Y663500D02*
Y666833D01*
G01Y666000D02*
X650017Y666417D01*
X650517Y666750D01*
X651183Y666833D01*
X651767Y666750D01*
X652267Y666417D01*
X652517Y665833D01*
Y663500D01*
G01X658033Y666417D02*
X657450Y666750D01*
X656950Y666833D01*
X656283Y666667D01*
X655783Y666333D01*
X655450Y665750D01*
X655367Y665167D01*
X655450Y664583D01*
X655783Y664083D01*
X656283Y663667D01*
X656950Y663500D01*
X657533Y663667D01*
X658033Y664000D01*
G01X661050Y665750D02*
X663717D01*
X663467Y666333D01*
X663050Y666667D01*
X662467Y666833D01*
X661883Y666750D01*
X661383Y666500D01*
X661050Y665917D01*
X660883Y665417D01*
Y664917D01*
X661050Y664417D01*
X661467Y663917D01*
X661967Y663583D01*
X662550Y663500D01*
X663133Y663667D01*
X663717Y664167D01*
G01X590417Y860000D02*
X592500Y855000D01*
X594583Y860000D01*
G01X596267Y856000D02*
X596767Y855417D01*
X597433Y855083D01*
X598183Y855000D01*
X598850Y855083D01*
X599517Y855500D01*
X599933Y856000D01*
X600017Y856500D01*
X599850Y857083D01*
X599267Y857500D01*
X598683Y857667D01*
X597933D01*
G01X598683D02*
X599183Y857917D01*
X599600Y858333D01*
X599767Y858833D01*
X599600Y859333D01*
X599183Y859750D01*
X598433Y860000D01*
X597683Y859917D01*
X596933Y859583D01*
G01X603700Y854833D02*
X603533Y854917D01*
Y855083D01*
X603700Y855167D01*
X603867Y855083D01*
Y854917D01*
X603700Y854833D01*
G01X610300Y855000D02*
Y860000D01*
X607217Y856417D01*
X611383D01*
G01X614900Y854833D02*
X614733Y854917D01*
Y855083D01*
X614900Y855167D01*
X615067Y855083D01*
Y854917D01*
X614900Y854833D01*
G01X620500Y855000D02*
Y860000D01*
X619500Y859000D01*
G01Y855000D02*
X621500D01*
G01X641317Y859167D02*
X641817Y859667D01*
X642400Y859917D01*
X643067Y860000D01*
X643900Y859833D01*
X644483Y859417D01*
X644650Y858917D01*
X644567Y858417D01*
X644233Y858000D01*
X642567Y857167D01*
X641817Y856583D01*
X641317Y855750D01*
X641150Y855000D01*
X644650D01*
G01X648500Y860000D02*
X647833Y859833D01*
X647333Y859417D01*
X647000Y858917D01*
X646750Y858250D01*
X646667Y857500D01*
X646750Y856750D01*
X647000Y856083D01*
X647333Y855583D01*
X647833Y855167D01*
X648500Y855000D01*
X649167Y855167D01*
X649667Y855583D01*
X650000Y856083D01*
X650250Y856750D01*
X650333Y857500D01*
X650250Y858250D01*
X650000Y858917D01*
X649667Y859417D01*
X649167Y859833D01*
X648500Y860000D01*
G01X654100Y855000D02*
Y860000D01*
X653100Y859000D01*
G01Y855000D02*
X655100D01*
G01X657867Y855750D02*
X658367Y855333D01*
X658950Y855083D01*
X659700Y855000D01*
X660450Y855167D01*
X661033Y855500D01*
X661450Y856083D01*
X661533Y856750D01*
X661367Y857417D01*
X660950Y857833D01*
X660367Y858167D01*
X659783Y858250D01*
X659200Y858167D01*
X658450Y857833D01*
X658700Y860000D01*
X660950D01*
G01X663800Y854833D02*
X666800Y860000D01*
G01X670900D02*
X670233Y859833D01*
X669733Y859417D01*
X669400Y858917D01*
X669150Y858250D01*
X669067Y857500D01*
X669150Y856750D01*
X669400Y856083D01*
X669733Y855583D01*
X670233Y855167D01*
X670900Y855000D01*
X671567Y855167D01*
X672067Y855583D01*
X672400Y856083D01*
X672650Y856750D01*
X672733Y857500D01*
X672650Y858250D01*
X672400Y858917D01*
X672067Y859417D01*
X671567Y859833D01*
X670900Y860000D01*
G01X674917Y857083D02*
X675500Y857667D01*
X676000Y858000D01*
X676667Y858167D01*
X677250Y858000D01*
X677667Y857667D01*
X678000Y857167D01*
X678083Y856583D01*
X678000Y856083D01*
X677667Y855583D01*
X677167Y855167D01*
X676583Y855000D01*
X675917Y855167D01*
X675333Y855667D01*
X675000Y856417D01*
X674917Y857250D01*
X675083Y858333D01*
X675333Y858917D01*
X675750Y859500D01*
X676333Y859917D01*
X676917Y860000D01*
X677500Y859833D01*
X677917Y859417D01*
G01X713000Y-53000D02*
X1343000D01*
G01X713000Y-23000D02*
X1343000D01*
G01X713000Y850500D02*
Y-73000D01*
X1343000D01*
Y782000D01*
X713000D01*
G01X694500Y716000D02*
Y-69500D01*
G01X713000Y85500D02*
X1343000D01*
G01X713000Y335500D02*
X1343000D01*
G01X713000Y365500D02*
X1343000D01*
G01X713000Y400500D02*
X1343000D01*
G01X650853Y438153D02*
X650020Y438987D01*
X649603Y439820D01*
Y443153D01*
X650020Y443987D01*
X650853Y444820D01*
G01X656870Y439820D02*
X656370Y439903D01*
X655870Y440237D01*
X655537Y440820D01*
X655370Y441487D01*
X655537Y442153D01*
X655870Y442737D01*
X656370Y443070D01*
X656870Y443153D01*
X657370Y443070D01*
X657870Y442737D01*
X658203Y442153D01*
X658287Y441487D01*
X658203Y440820D01*
X657870Y440237D01*
X657370Y439903D01*
X656870Y439820D01*
G01X661303D02*
Y443153D01*
G01Y442487D02*
X661720Y442820D01*
X662137Y443070D01*
X662720Y443153D01*
X663137Y443070D01*
X663637Y442820D01*
G01X713000Y435500D02*
X1343000D01*
G01X713000Y450500D02*
X1343000D01*
G01X713000Y477500D02*
X1343000D01*
G01X713000Y579500D02*
X1343000D01*
G01X713000Y604500D02*
X1343000D01*
G01X713000Y752000D02*
X1344500D01*
G01X712980Y850500D02*
X1343000D01*
G01X736937Y-65320D02*
X737437Y-65737D01*
X738020Y-65987D01*
X738770Y-66070D01*
X739520Y-65903D01*
X740103Y-65570D01*
X740520Y-64987D01*
X740603Y-64320D01*
X740437Y-63653D01*
X740020Y-63237D01*
X739437Y-62903D01*
X738853Y-62820D01*
X738270Y-62903D01*
X737520Y-63237D01*
X737770Y-61070D01*
X740020D01*
G01X744370Y-66237D02*
X744203Y-66153D01*
Y-65987D01*
X744370Y-65903D01*
X744537Y-65987D01*
Y-66153D01*
X744370Y-66237D01*
G01X749970Y-66070D02*
Y-61070D01*
X748970Y-62070D01*
G01Y-66070D02*
X750970D01*
G01X760170Y-61070D02*
X762170D01*
G01X761170D02*
Y-66070D01*
G01X760170D02*
X762170D01*
G01X766270D02*
Y-61820D01*
X766437Y-61403D01*
X766770Y-61153D01*
X767270Y-61070D01*
X767770Y-61237D01*
X768020Y-61653D01*
G01X767020Y-63070D02*
X765353D01*
G01X778470Y-63570D02*
X780137D01*
Y-65070D01*
X779637Y-65570D01*
X779053Y-65903D01*
X778220Y-66070D01*
X777387Y-65903D01*
X776803Y-65570D01*
X776303Y-65070D01*
X775970Y-64487D01*
X775803Y-63820D01*
Y-63237D01*
X775970Y-62737D01*
X776303Y-62153D01*
X776803Y-61653D01*
X777303Y-61320D01*
X777970Y-61070D01*
X778553D01*
X779220Y-61237D01*
X779720Y-61570D01*
G01X782320Y-63820D02*
X784987D01*
X784737Y-63237D01*
X784320Y-62903D01*
X783737Y-62737D01*
X783153Y-62820D01*
X782653Y-63070D01*
X782320Y-63653D01*
X782153Y-64153D01*
Y-64653D01*
X782320Y-65153D01*
X782737Y-65653D01*
X783237Y-65987D01*
X783820Y-66070D01*
X784403Y-65903D01*
X784987Y-65403D01*
G01X788003Y-66070D02*
Y-62737D01*
G01Y-63403D02*
X788420Y-63070D01*
X788837Y-62820D01*
X789420Y-62737D01*
X789837Y-62820D01*
X790337Y-63070D01*
G01X793270Y-66070D02*
Y-61070D01*
G01Y-63570D02*
X793687Y-63070D01*
X794187Y-62820D01*
X794687Y-62737D01*
X795437Y-62903D01*
X795937Y-63237D01*
X796270Y-63820D01*
Y-64487D01*
X796103Y-65153D01*
X795770Y-65653D01*
X795187Y-65987D01*
X794687Y-66070D01*
X794187Y-65987D01*
X793687Y-65737D01*
X793270Y-65320D01*
G01X799120Y-63820D02*
X801787D01*
X801537Y-63237D01*
X801120Y-62903D01*
X800537Y-62737D01*
X799953Y-62820D01*
X799453Y-63070D01*
X799120Y-63653D01*
X798953Y-64153D01*
Y-64653D01*
X799120Y-65153D01*
X799537Y-65653D01*
X800037Y-65987D01*
X800620Y-66070D01*
X801203Y-65903D01*
X801787Y-65403D01*
G01X804803Y-66070D02*
Y-62737D01*
G01Y-63403D02*
X805220Y-63070D01*
X805637Y-62820D01*
X806220Y-62737D01*
X806637Y-62820D01*
X807137Y-63070D01*
G01X815753Y-66070D02*
Y-61070D01*
G01Y-63487D02*
X816170Y-63070D01*
X816587Y-62820D01*
X817253Y-62737D01*
X817753Y-62820D01*
X818337Y-63153D01*
X818587Y-63653D01*
Y-66070D01*
G01X824270D02*
Y-62737D01*
G01Y-63320D02*
X823937Y-62987D01*
X823437Y-62820D01*
X822853Y-62737D01*
X822270Y-62903D01*
X821770Y-63237D01*
X821437Y-63737D01*
X821270Y-64403D01*
X821437Y-65070D01*
X821770Y-65570D01*
X822270Y-65903D01*
X822853Y-66070D01*
X823437Y-65987D01*
X823937Y-65737D01*
X824270Y-65403D01*
G01X827120Y-65487D02*
X827537Y-65820D01*
X828120Y-66070D01*
X828620D01*
X829120Y-65903D01*
X829453Y-65653D01*
X829620Y-65320D01*
X829537Y-64820D01*
X829203Y-64570D01*
X827703Y-64070D01*
X827370Y-63487D01*
X827537Y-63070D01*
X827870Y-62820D01*
X828370Y-62737D01*
X828870Y-62820D01*
X829370Y-63070D01*
G01X839570Y-61070D02*
Y-66070D01*
G01X838403Y-62737D02*
X840737D01*
G01X843753Y-66070D02*
Y-61070D01*
G01Y-63487D02*
X844170Y-63070D01*
X844587Y-62820D01*
X845253Y-62737D01*
X845753Y-62820D01*
X846337Y-63153D01*
X846587Y-63653D01*
Y-66070D01*
G01X850770Y-62737D02*
Y-66070D01*
G01Y-61403D02*
X850603Y-61320D01*
Y-61153D01*
X850770Y-61070D01*
X850937Y-61153D01*
Y-61320D01*
X850770Y-61403D01*
G01X855120Y-65487D02*
X855537Y-65820D01*
X856120Y-66070D01*
X856620D01*
X857120Y-65903D01*
X857453Y-65653D01*
X857620Y-65320D01*
X857537Y-64820D01*
X857203Y-64570D01*
X855703Y-64070D01*
X855370Y-63487D01*
X855537Y-63070D01*
X855870Y-62820D01*
X856370Y-62737D01*
X856870Y-62820D01*
X857370Y-63070D01*
G01X866153Y-66070D02*
Y-61070D01*
G01X868820Y-62737D02*
X866153Y-64653D01*
G01X867237Y-63903D02*
X868987Y-66070D01*
G01X873170Y-62737D02*
Y-66070D01*
G01Y-61403D02*
X873003Y-61320D01*
Y-61153D01*
X873170Y-61070D01*
X873337Y-61153D01*
Y-61320D01*
X873170Y-61403D01*
G01X877353Y-66070D02*
Y-62737D01*
G01Y-63570D02*
X877687Y-63153D01*
X878187Y-62820D01*
X878853Y-62737D01*
X879437Y-62820D01*
X879937Y-63153D01*
X880187Y-63737D01*
Y-66070D01*
G01X885870Y-61070D02*
Y-66070D01*
G01Y-65320D02*
X885537Y-65737D01*
X885037Y-65987D01*
X884453Y-66070D01*
X883787Y-65903D01*
X883287Y-65487D01*
X882953Y-64987D01*
X882870Y-64403D01*
X882953Y-63820D01*
X883287Y-63320D01*
X883787Y-62903D01*
X884453Y-62737D01*
X885037Y-62820D01*
X885453Y-62987D01*
X885870Y-63320D01*
G01X895570Y-66070D02*
X895070Y-65987D01*
X894570Y-65653D01*
X894237Y-65070D01*
X894070Y-64403D01*
X894237Y-63737D01*
X894570Y-63153D01*
X895070Y-62820D01*
X895570Y-62737D01*
X896070Y-62820D01*
X896570Y-63153D01*
X896903Y-63737D01*
X896987Y-64403D01*
X896903Y-65070D01*
X896570Y-65653D01*
X896070Y-65987D01*
X895570Y-66070D01*
G01X900670D02*
Y-61820D01*
X900837Y-61403D01*
X901170Y-61153D01*
X901670Y-61070D01*
X902170Y-61237D01*
X902420Y-61653D01*
G01X901420Y-63070D02*
X899753D01*
G01X913870Y-61070D02*
Y-66070D01*
G01Y-65320D02*
X913537Y-65737D01*
X913037Y-65987D01*
X912453Y-66070D01*
X911787Y-65903D01*
X911287Y-65487D01*
X910953Y-64987D01*
X910870Y-64403D01*
X910953Y-63820D01*
X911287Y-63320D01*
X911787Y-62903D01*
X912453Y-62737D01*
X913037Y-62820D01*
X913453Y-62987D01*
X913870Y-63320D01*
G01X916720Y-63820D02*
X919387D01*
X919137Y-63237D01*
X918720Y-62903D01*
X918137Y-62737D01*
X917553Y-62820D01*
X917053Y-63070D01*
X916720Y-63653D01*
X916553Y-64153D01*
Y-64653D01*
X916720Y-65153D01*
X917137Y-65653D01*
X917637Y-65987D01*
X918220Y-66070D01*
X918803Y-65903D01*
X919387Y-65403D01*
G01X922320Y-65487D02*
X922737Y-65820D01*
X923320Y-66070D01*
X923820D01*
X924320Y-65903D01*
X924653Y-65653D01*
X924820Y-65320D01*
X924737Y-64820D01*
X924403Y-64570D01*
X922903Y-64070D01*
X922570Y-63487D01*
X922737Y-63070D01*
X923070Y-62820D01*
X923570Y-62737D01*
X924070Y-62820D01*
X924570Y-63070D01*
G01X929170Y-62737D02*
Y-66070D01*
G01Y-61403D02*
X929003Y-61320D01*
Y-61153D01*
X929170Y-61070D01*
X929337Y-61153D01*
Y-61320D01*
X929170Y-61403D01*
G01X933603Y-67320D02*
X934187Y-67653D01*
X934853Y-67737D01*
X935437Y-67653D01*
X935937Y-67237D01*
X936270Y-66653D01*
Y-62737D01*
G01Y-63403D02*
X935937Y-63070D01*
X935437Y-62820D01*
X934853Y-62737D01*
X934187Y-62903D01*
X933770Y-63237D01*
X933437Y-63820D01*
X933270Y-64403D01*
X933353Y-64903D01*
X933687Y-65487D01*
X934187Y-65903D01*
X934853Y-66070D01*
X935353Y-65987D01*
X935937Y-65653D01*
X936270Y-65320D01*
G01X938953Y-66070D02*
Y-62737D01*
G01Y-63570D02*
X939287Y-63153D01*
X939787Y-62820D01*
X940453Y-62737D01*
X941037Y-62820D01*
X941537Y-63153D01*
X941787Y-63737D01*
Y-66070D01*
G01X945803Y-66987D02*
X946137Y-65903D01*
G01X955670Y-67737D02*
Y-62737D01*
G01Y-63487D02*
X956087Y-63070D01*
X956503Y-62820D01*
X957170Y-62737D01*
X957753Y-62820D01*
X958337Y-63237D01*
X958587Y-63820D01*
X958670Y-64403D01*
X958587Y-64987D01*
X958337Y-65570D01*
X957837Y-65903D01*
X957170Y-66070D01*
X956587Y-65987D01*
X956003Y-65737D01*
X955670Y-65403D01*
G01X962770Y-66070D02*
Y-61070D01*
G01X967120Y-63820D02*
X969787D01*
X969537Y-63237D01*
X969120Y-62903D01*
X968537Y-62737D01*
X967953Y-62820D01*
X967453Y-63070D01*
X967120Y-63653D01*
X966953Y-64153D01*
Y-64653D01*
X967120Y-65153D01*
X967537Y-65653D01*
X968037Y-65987D01*
X968620Y-66070D01*
X969203Y-65903D01*
X969787Y-65403D01*
G01X975470Y-66070D02*
Y-62737D01*
G01Y-63320D02*
X975137Y-62987D01*
X974637Y-62820D01*
X974053Y-62737D01*
X973470Y-62903D01*
X972970Y-63237D01*
X972637Y-63737D01*
X972470Y-64403D01*
X972637Y-65070D01*
X972970Y-65570D01*
X973470Y-65903D01*
X974053Y-66070D01*
X974637Y-65987D01*
X975137Y-65737D01*
X975470Y-65403D01*
G01X978320Y-65487D02*
X978737Y-65820D01*
X979320Y-66070D01*
X979820D01*
X980320Y-65903D01*
X980653Y-65653D01*
X980820Y-65320D01*
X980737Y-64820D01*
X980403Y-64570D01*
X978903Y-64070D01*
X978570Y-63487D01*
X978737Y-63070D01*
X979070Y-62820D01*
X979570Y-62737D01*
X980070Y-62820D01*
X980570Y-63070D01*
G01X983920Y-63820D02*
X986587D01*
X986337Y-63237D01*
X985920Y-62903D01*
X985337Y-62737D01*
X984753Y-62820D01*
X984253Y-63070D01*
X983920Y-63653D01*
X983753Y-64153D01*
Y-64653D01*
X983920Y-65153D01*
X984337Y-65653D01*
X984837Y-65987D01*
X985420Y-66070D01*
X986003Y-65903D01*
X986587Y-65403D01*
G01X995870Y-66070D02*
Y-61820D01*
X996037Y-61403D01*
X996370Y-61153D01*
X996870Y-61070D01*
X997370Y-61237D01*
X997620Y-61653D01*
G01X996620Y-63070D02*
X994953D01*
G01X1001970Y-66070D02*
X1001470Y-65987D01*
X1000970Y-65653D01*
X1000637Y-65070D01*
X1000470Y-64403D01*
X1000637Y-63737D01*
X1000970Y-63153D01*
X1001470Y-62820D01*
X1001970Y-62737D01*
X1002470Y-62820D01*
X1002970Y-63153D01*
X1003303Y-63737D01*
X1003387Y-64403D01*
X1003303Y-65070D01*
X1002970Y-65653D01*
X1002470Y-65987D01*
X1001970Y-66070D01*
G01X1007570D02*
Y-61070D01*
G01X1013170Y-66070D02*
Y-61070D01*
G01X1018770Y-66070D02*
X1018270Y-65987D01*
X1017770Y-65653D01*
X1017437Y-65070D01*
X1017270Y-64403D01*
X1017437Y-63737D01*
X1017770Y-63153D01*
X1018270Y-62820D01*
X1018770Y-62737D01*
X1019270Y-62820D01*
X1019770Y-63153D01*
X1020103Y-63737D01*
X1020187Y-64403D01*
X1020103Y-65070D01*
X1019770Y-65653D01*
X1019270Y-65987D01*
X1018770Y-66070D01*
G01X1022287Y-62737D02*
X1023287Y-66070D01*
X1024370Y-62737D01*
X1025453Y-66070D01*
X1026453Y-62737D01*
G01X1029970Y-66237D02*
X1029803Y-66153D01*
Y-65987D01*
X1029970Y-65903D01*
X1030137Y-65987D01*
Y-66153D01*
X1029970Y-66237D01*
G01X1040170Y-61070D02*
X1042170D01*
G01X1041170D02*
Y-66070D01*
G01X1040170D02*
X1042170D01*
G01X1046270D02*
Y-61820D01*
X1046437Y-61403D01*
X1046770Y-61153D01*
X1047270Y-61070D01*
X1047770Y-61237D01*
X1048020Y-61653D01*
G01X1047020Y-63070D02*
X1045353D01*
G01X1056553Y-66070D02*
Y-62737D01*
G01Y-63570D02*
X1056887Y-63153D01*
X1057387Y-62820D01*
X1058053Y-62737D01*
X1058637Y-62820D01*
X1059137Y-63153D01*
X1059387Y-63737D01*
Y-66070D01*
G01X1063570D02*
X1063070Y-65987D01*
X1062570Y-65653D01*
X1062237Y-65070D01*
X1062070Y-64403D01*
X1062237Y-63737D01*
X1062570Y-63153D01*
X1063070Y-62820D01*
X1063570Y-62737D01*
X1064070Y-62820D01*
X1064570Y-63153D01*
X1064903Y-63737D01*
X1064987Y-64403D01*
X1064903Y-65070D01*
X1064570Y-65653D01*
X1064070Y-65987D01*
X1063570Y-66070D01*
G01X1069170Y-61070D02*
Y-66070D01*
G01X1068003Y-62737D02*
X1070337D01*
G01X1074603Y-66987D02*
X1074937Y-65903D01*
G01X1084470Y-67737D02*
Y-62737D01*
G01Y-63487D02*
X1084887Y-63070D01*
X1085303Y-62820D01*
X1085970Y-62737D01*
X1086553Y-62820D01*
X1087137Y-63237D01*
X1087387Y-63820D01*
X1087470Y-64403D01*
X1087387Y-64987D01*
X1087137Y-65570D01*
X1086637Y-65903D01*
X1085970Y-66070D01*
X1085387Y-65987D01*
X1084803Y-65737D01*
X1084470Y-65403D01*
G01X1091570Y-66070D02*
Y-61070D01*
G01X1095920Y-63820D02*
X1098587D01*
X1098337Y-63237D01*
X1097920Y-62903D01*
X1097337Y-62737D01*
X1096753Y-62820D01*
X1096253Y-63070D01*
X1095920Y-63653D01*
X1095753Y-64153D01*
Y-64653D01*
X1095920Y-65153D01*
X1096337Y-65653D01*
X1096837Y-65987D01*
X1097420Y-66070D01*
X1098003Y-65903D01*
X1098587Y-65403D01*
G01X1104270Y-66070D02*
Y-62737D01*
G01Y-63320D02*
X1103937Y-62987D01*
X1103437Y-62820D01*
X1102853Y-62737D01*
X1102270Y-62903D01*
X1101770Y-63237D01*
X1101437Y-63737D01*
X1101270Y-64403D01*
X1101437Y-65070D01*
X1101770Y-65570D01*
X1102270Y-65903D01*
X1102853Y-66070D01*
X1103437Y-65987D01*
X1103937Y-65737D01*
X1104270Y-65403D01*
G01X1107120Y-65487D02*
X1107537Y-65820D01*
X1108120Y-66070D01*
X1108620D01*
X1109120Y-65903D01*
X1109453Y-65653D01*
X1109620Y-65320D01*
X1109537Y-64820D01*
X1109203Y-64570D01*
X1107703Y-64070D01*
X1107370Y-63487D01*
X1107537Y-63070D01*
X1107870Y-62820D01*
X1108370Y-62737D01*
X1108870Y-62820D01*
X1109370Y-63070D01*
G01X1112720Y-63820D02*
X1115387D01*
X1115137Y-63237D01*
X1114720Y-62903D01*
X1114137Y-62737D01*
X1113553Y-62820D01*
X1113053Y-63070D01*
X1112720Y-63653D01*
X1112553Y-64153D01*
Y-64653D01*
X1112720Y-65153D01*
X1113137Y-65653D01*
X1113637Y-65987D01*
X1114220Y-66070D01*
X1114803Y-65903D01*
X1115387Y-65403D01*
G01X1125170Y-62737D02*
Y-66070D01*
G01Y-61403D02*
X1125003Y-61320D01*
Y-61153D01*
X1125170Y-61070D01*
X1125337Y-61153D01*
Y-61320D01*
X1125170Y-61403D01*
G01X1132270Y-67737D02*
Y-62737D01*
G01Y-63487D02*
X1131853Y-63070D01*
X1131353Y-62820D01*
X1130770Y-62737D01*
X1130270Y-62820D01*
X1129687Y-63237D01*
X1129353Y-63820D01*
X1129270Y-64403D01*
X1129353Y-64987D01*
X1129687Y-65570D01*
X1130270Y-65987D01*
X1130770Y-66070D01*
X1131353Y-65987D01*
X1131853Y-65737D01*
X1132270Y-65320D01*
G01X1134953Y-66070D02*
Y-62737D01*
G01Y-63570D02*
X1135287Y-63153D01*
X1135787Y-62820D01*
X1136453Y-62737D01*
X1137037Y-62820D01*
X1137537Y-63153D01*
X1137787Y-63737D01*
Y-66070D01*
G01X1141970D02*
X1141470Y-65987D01*
X1140970Y-65653D01*
X1140637Y-65070D01*
X1140470Y-64403D01*
X1140637Y-63737D01*
X1140970Y-63153D01*
X1141470Y-62820D01*
X1141970Y-62737D01*
X1142470Y-62820D01*
X1142970Y-63153D01*
X1143303Y-63737D01*
X1143387Y-64403D01*
X1143303Y-65070D01*
X1142970Y-65653D01*
X1142470Y-65987D01*
X1141970Y-66070D01*
G01X1146403D02*
Y-62737D01*
G01Y-63403D02*
X1146820Y-63070D01*
X1147237Y-62820D01*
X1147820Y-62737D01*
X1148237Y-62820D01*
X1148737Y-63070D01*
G01X1151920Y-63820D02*
X1154587D01*
X1154337Y-63237D01*
X1153920Y-62903D01*
X1153337Y-62737D01*
X1152753Y-62820D01*
X1152253Y-63070D01*
X1151920Y-63653D01*
X1151753Y-64153D01*
Y-64653D01*
X1151920Y-65153D01*
X1152337Y-65653D01*
X1152837Y-65987D01*
X1153420Y-66070D01*
X1154003Y-65903D01*
X1154587Y-65403D01*
G01X1164370Y-61070D02*
Y-66070D01*
G01X1163203Y-62737D02*
X1165537D01*
G01X1168553Y-66070D02*
Y-61070D01*
G01Y-63487D02*
X1168970Y-63070D01*
X1169387Y-62820D01*
X1170053Y-62737D01*
X1170553Y-62820D01*
X1171137Y-63153D01*
X1171387Y-63653D01*
Y-66070D01*
G01X1175570Y-62737D02*
Y-66070D01*
G01Y-61403D02*
X1175403Y-61320D01*
Y-61153D01*
X1175570Y-61070D01*
X1175737Y-61153D01*
Y-61320D01*
X1175570Y-61403D01*
G01X1179920Y-65487D02*
X1180337Y-65820D01*
X1180920Y-66070D01*
X1181420D01*
X1181920Y-65903D01*
X1182253Y-65653D01*
X1182420Y-65320D01*
X1182337Y-64820D01*
X1182003Y-64570D01*
X1180503Y-64070D01*
X1180170Y-63487D01*
X1180337Y-63070D01*
X1180670Y-62820D01*
X1181170Y-62737D01*
X1181670Y-62820D01*
X1182170Y-63070D01*
G01X1191203Y-66070D02*
Y-62737D01*
G01Y-63403D02*
X1191620Y-63070D01*
X1192037Y-62820D01*
X1192620Y-62737D01*
X1193037Y-62820D01*
X1193537Y-63070D01*
G01X1196720Y-63820D02*
X1199387D01*
X1199137Y-63237D01*
X1198720Y-62903D01*
X1198137Y-62737D01*
X1197553Y-62820D01*
X1197053Y-63070D01*
X1196720Y-63653D01*
X1196553Y-64153D01*
Y-64653D01*
X1196720Y-65153D01*
X1197137Y-65653D01*
X1197637Y-65987D01*
X1198220Y-66070D01*
X1198803Y-65903D01*
X1199387Y-65403D01*
G01X1205070Y-67737D02*
Y-62737D01*
G01Y-63487D02*
X1204653Y-63070D01*
X1204153Y-62820D01*
X1203570Y-62737D01*
X1203070Y-62820D01*
X1202487Y-63237D01*
X1202153Y-63820D01*
X1202070Y-64403D01*
X1202153Y-64987D01*
X1202487Y-65570D01*
X1203070Y-65987D01*
X1203570Y-66070D01*
X1204153Y-65987D01*
X1204653Y-65737D01*
X1205070Y-65320D01*
G01X1207753Y-62737D02*
Y-65070D01*
X1208087Y-65653D01*
X1208587Y-65987D01*
X1209170Y-66070D01*
X1209753Y-65987D01*
X1210253Y-65653D01*
X1210587Y-65070D01*
G01Y-66070D02*
Y-62737D01*
G01X1213520Y-63820D02*
X1216187D01*
X1215937Y-63237D01*
X1215520Y-62903D01*
X1214937Y-62737D01*
X1214353Y-62820D01*
X1213853Y-63070D01*
X1213520Y-63653D01*
X1213353Y-64153D01*
Y-64653D01*
X1213520Y-65153D01*
X1213937Y-65653D01*
X1214437Y-65987D01*
X1215020Y-66070D01*
X1215603Y-65903D01*
X1216187Y-65403D01*
G01X1219120Y-65487D02*
X1219537Y-65820D01*
X1220120Y-66070D01*
X1220620D01*
X1221120Y-65903D01*
X1221453Y-65653D01*
X1221620Y-65320D01*
X1221537Y-64820D01*
X1221203Y-64570D01*
X1219703Y-64070D01*
X1219370Y-63487D01*
X1219537Y-63070D01*
X1219870Y-62820D01*
X1220370Y-62737D01*
X1220870Y-62820D01*
X1221370Y-63070D01*
G01X1225970Y-61070D02*
Y-66070D01*
G01X1224803Y-62737D02*
X1227137D01*
G01X1231570Y-66237D02*
X1231403Y-66153D01*
Y-65987D01*
X1231570Y-65903D01*
X1231737Y-65987D01*
Y-66153D01*
X1231570Y-66237D01*
G01X722667Y-38250D02*
X723167Y-38667D01*
X723750Y-38917D01*
X724500Y-39000D01*
X725250Y-38833D01*
X725833Y-38500D01*
X726250Y-37917D01*
X726333Y-37250D01*
X726167Y-36583D01*
X725750Y-36167D01*
X725167Y-35833D01*
X724583Y-35750D01*
X724000Y-35833D01*
X723250Y-36167D01*
X723500Y-34000D01*
X725750D01*
G01X730100Y-39167D02*
X729933Y-39083D01*
Y-38917D01*
X730100Y-38833D01*
X730267Y-38917D01*
Y-39083D01*
X730100Y-39167D01*
G01X739633Y-39000D02*
Y-34000D01*
X741717D01*
X742383Y-34250D01*
X742800Y-34583D01*
X742967Y-35250D01*
X742800Y-35917D01*
X742300Y-36333D01*
X741717Y-36583D01*
X739633D01*
G01X741717D02*
X742967Y-39000D01*
G01X745650Y-36750D02*
X748317D01*
X748067Y-36167D01*
X747650Y-35833D01*
X747067Y-35667D01*
X746483Y-35750D01*
X745983Y-36000D01*
X745650Y-36583D01*
X745483Y-37083D01*
Y-37583D01*
X745650Y-38083D01*
X746067Y-38583D01*
X746567Y-38917D01*
X747150Y-39000D01*
X747733Y-38833D01*
X748317Y-38333D01*
G01X750000Y-39000D02*
Y-35667D01*
G01Y-36583D02*
X750250Y-36167D01*
X750667Y-35833D01*
X751250Y-35667D01*
X751833Y-35833D01*
X752250Y-36167D01*
X752500Y-36583D01*
Y-39000D01*
G01Y-36583D02*
X752750Y-36167D01*
X753167Y-35833D01*
X753750Y-35667D01*
X754333Y-35833D01*
X754750Y-36167D01*
X755000Y-36667D01*
Y-39000D01*
G01X759600D02*
Y-35667D01*
G01Y-36250D02*
X759267Y-35917D01*
X758767Y-35750D01*
X758183Y-35667D01*
X757600Y-35833D01*
X757100Y-36167D01*
X756767Y-36667D01*
X756600Y-37333D01*
X756767Y-38000D01*
X757100Y-38500D01*
X757600Y-38833D01*
X758183Y-39000D01*
X758767Y-38917D01*
X759267Y-38667D01*
X759600Y-38333D01*
G01X762533Y-39000D02*
Y-35667D01*
G01Y-36333D02*
X762950Y-36000D01*
X763367Y-35750D01*
X763950Y-35667D01*
X764367Y-35750D01*
X764867Y-36000D01*
G01X767883Y-39000D02*
Y-34000D01*
G01X770550Y-35667D02*
X767883Y-37583D01*
G01X768967Y-36833D02*
X770717Y-39000D01*
G01X773067Y-39167D02*
X776733Y-35500D01*
G01X774900Y-34833D02*
Y-39833D01*
G01X776733Y-39167D02*
X773067Y-35500D01*
G01X772400Y-37333D02*
X777400D01*
G01X777167Y123000D02*
Y128000D01*
X778833D01*
X779500Y127750D01*
X780000Y127417D01*
X780417Y126917D01*
X780750Y126333D01*
X780833Y125500D01*
X780750Y124667D01*
X780417Y124083D01*
X780000Y123583D01*
X779500Y123250D01*
X778833Y123000D01*
X777167D01*
G01X783433D02*
Y126333D01*
G01Y125667D02*
X783850Y126000D01*
X784267Y126250D01*
X784850Y126333D01*
X785267Y126250D01*
X785767Y126000D01*
G01X790200Y126333D02*
Y123000D01*
G01Y127667D02*
X790033Y127750D01*
Y127917D01*
X790200Y128000D01*
X790367Y127917D01*
Y127750D01*
X790200Y127667D01*
G01X795800Y123000D02*
Y128000D01*
G01X801400Y123000D02*
Y128000D01*
G01X811017Y123000D02*
Y128000D01*
X814183D01*
G01X813017Y125583D02*
X811017D01*
G01X817033Y123000D02*
Y126333D01*
G01Y125667D02*
X817450Y126000D01*
X817867Y126250D01*
X818450Y126333D01*
X818867Y126250D01*
X819367Y126000D01*
G01X823800Y123000D02*
X823300Y123083D01*
X822800Y123417D01*
X822467Y124000D01*
X822300Y124667D01*
X822467Y125333D01*
X822800Y125917D01*
X823300Y126250D01*
X823800Y126333D01*
X824300Y126250D01*
X824800Y125917D01*
X825133Y125333D01*
X825217Y124667D01*
X825133Y124000D01*
X824800Y123417D01*
X824300Y123083D01*
X823800Y123000D01*
G01X826900D02*
Y126333D01*
G01Y125417D02*
X827150Y125833D01*
X827567Y126167D01*
X828150Y126333D01*
X828733Y126167D01*
X829150Y125833D01*
X829400Y125417D01*
Y123000D01*
G01Y125417D02*
X829650Y125833D01*
X830067Y126167D01*
X830650Y126333D01*
X831233Y126167D01*
X831650Y125833D01*
X831900Y125333D01*
Y123000D01*
G01X838933Y128000D02*
Y123000D01*
X842267D01*
G01X846200D02*
Y128000D01*
X845200Y127000D01*
G01Y123000D02*
X847200D01*
G01X856983Y121333D02*
X856150Y122167D01*
X855733Y123000D01*
Y126333D01*
X856150Y127167D01*
X856983Y128000D01*
G01X863000D02*
Y123000D01*
G01X861083Y128000D02*
X864917D01*
G01X868600Y123000D02*
X867933Y123083D01*
X867350Y123417D01*
X866850Y123917D01*
X866517Y124500D01*
X866350Y125167D01*
Y125833D01*
X866517Y126500D01*
X866850Y127083D01*
X867350Y127583D01*
X867933Y127917D01*
X868600Y128000D01*
X869267Y127917D01*
X869850Y127583D01*
X870350Y127083D01*
X870683Y126500D01*
X870850Y125833D01*
Y125167D01*
X870683Y124500D01*
X870350Y123917D01*
X869850Y123417D01*
X869267Y123083D01*
X868600Y123000D01*
G01X872533D02*
Y128000D01*
X874533D01*
X875200Y127750D01*
X875700Y127167D01*
X875867Y126500D01*
X875700Y125833D01*
X875283Y125333D01*
X874533Y125083D01*
X872533D01*
G01X880217Y121333D02*
X881050Y122167D01*
X881467Y123000D01*
Y126333D01*
X881050Y127167D01*
X880217Y128000D01*
G01X891000D02*
Y123000D01*
G01X889833Y126333D02*
X892167D01*
G01X896600Y123000D02*
X896100Y123083D01*
X895600Y123417D01*
X895267Y124000D01*
X895100Y124667D01*
X895267Y125333D01*
X895600Y125917D01*
X896100Y126250D01*
X896600Y126333D01*
X897100Y126250D01*
X897600Y125917D01*
X897933Y125333D01*
X898017Y124667D01*
X897933Y124000D01*
X897600Y123417D01*
X897100Y123083D01*
X896600Y123000D01*
G01X906133Y128000D02*
Y123000D01*
X909467D01*
G01X912150Y126333D02*
X914650Y123000D01*
G01Y126333D02*
X912150Y123000D01*
G01X777583Y104700D02*
Y99700D01*
X780917D01*
G01X783600Y103033D02*
X786100Y99700D01*
G01Y103033D02*
X783600Y99700D01*
G01X790450Y99533D02*
X790283Y99617D01*
Y99783D01*
X790450Y99867D01*
X790617Y99783D01*
Y99617D01*
X790450Y99533D01*
G01Y101783D02*
X790283Y101867D01*
Y102033D01*
X790450Y102117D01*
X790617Y102033D01*
Y101867D01*
X790450Y101783D01*
G01X799150Y99700D02*
Y103033D01*
G01Y102117D02*
X799400Y102533D01*
X799817Y102867D01*
X800400Y103033D01*
X800983Y102867D01*
X801400Y102533D01*
X801650Y102117D01*
Y99700D01*
G01Y102117D02*
X801900Y102533D01*
X802317Y102867D01*
X802900Y103033D01*
X803483Y102867D01*
X803900Y102533D01*
X804150Y102033D01*
Y99700D01*
G01X805833Y103033D02*
Y100700D01*
X806167Y100117D01*
X806667Y99783D01*
X807250Y99700D01*
X807833Y99783D01*
X808333Y100117D01*
X808667Y100700D01*
G01Y99700D02*
Y103033D01*
G01X811600Y100283D02*
X812017Y99950D01*
X812600Y99700D01*
X813100D01*
X813600Y99867D01*
X813933Y100117D01*
X814100Y100450D01*
X814017Y100950D01*
X813683Y101200D01*
X812183Y101700D01*
X811850Y102283D01*
X812017Y102700D01*
X812350Y102950D01*
X812850Y103033D01*
X813350Y102950D01*
X813850Y102700D01*
G01X818450Y104700D02*
Y99700D01*
G01X817283Y103033D02*
X819617D01*
G01X828150Y99700D02*
Y104700D01*
G01Y102200D02*
X828567Y102700D01*
X829067Y102950D01*
X829567Y103033D01*
X830317Y102867D01*
X830817Y102533D01*
X831150Y101950D01*
Y101283D01*
X830983Y100617D01*
X830650Y100117D01*
X830067Y99783D01*
X829567Y99700D01*
X829067Y99783D01*
X828567Y100033D01*
X828150Y100450D01*
G01X834000Y101950D02*
X836667D01*
X836417Y102533D01*
X836000Y102867D01*
X835417Y103033D01*
X834833Y102950D01*
X834333Y102700D01*
X834000Y102117D01*
X833833Y101617D01*
Y101117D01*
X834000Y100617D01*
X834417Y100117D01*
X834917Y99783D01*
X835500Y99700D01*
X836083Y99867D01*
X836667Y100367D01*
G01X844950Y99700D02*
Y104700D01*
G01Y102200D02*
X845367Y102700D01*
X845867Y102950D01*
X846367Y103033D01*
X847117Y102867D01*
X847617Y102533D01*
X847950Y101950D01*
Y101283D01*
X847783Y100617D01*
X847450Y100117D01*
X846867Y99783D01*
X846367Y99700D01*
X845867Y99783D01*
X845367Y100033D01*
X844950Y100450D01*
G01X850883Y99700D02*
Y103033D01*
G01Y102367D02*
X851300Y102700D01*
X851717Y102950D01*
X852300Y103033D01*
X852717Y102950D01*
X853217Y102700D01*
G01X857650Y99700D02*
X857150Y99783D01*
X856650Y100117D01*
X856317Y100700D01*
X856150Y101367D01*
X856317Y102033D01*
X856650Y102617D01*
X857150Y102950D01*
X857650Y103033D01*
X858150Y102950D01*
X858650Y102617D01*
X858983Y102033D01*
X859067Y101367D01*
X858983Y100700D01*
X858650Y100117D01*
X858150Y99783D01*
X857650Y99700D01*
G01X861833D02*
Y104700D01*
G01X864500Y103033D02*
X861833Y101117D01*
G01X862917Y101867D02*
X864667Y99700D01*
G01X867600Y101950D02*
X870267D01*
X870017Y102533D01*
X869600Y102867D01*
X869017Y103033D01*
X868433Y102950D01*
X867933Y102700D01*
X867600Y102117D01*
X867433Y101617D01*
Y101117D01*
X867600Y100617D01*
X868017Y100117D01*
X868517Y99783D01*
X869100Y99700D01*
X869683Y99867D01*
X870267Y100367D01*
G01X873033Y99700D02*
Y103033D01*
G01Y102200D02*
X873367Y102617D01*
X873867Y102950D01*
X874533Y103033D01*
X875117Y102950D01*
X875617Y102617D01*
X875867Y102033D01*
Y99700D01*
G01X885650D02*
Y104700D01*
G01X892750Y99700D02*
Y103033D01*
G01Y102450D02*
X892417Y102783D01*
X891917Y102950D01*
X891333Y103033D01*
X890750Y102867D01*
X890250Y102533D01*
X889917Y102033D01*
X889750Y101367D01*
X889917Y100700D01*
X890250Y100200D01*
X890750Y99867D01*
X891333Y99700D01*
X891917Y99783D01*
X892417Y100033D01*
X892750Y100367D01*
G01X895100Y98200D02*
X895600Y98033D01*
X896267Y98200D01*
X896683Y98533D01*
X897017Y98950D01*
X897517Y100283D01*
X898600Y103033D01*
G01X895933D02*
X897517Y100283D01*
G01X901200Y101950D02*
X903867D01*
X903617Y102533D01*
X903200Y102867D01*
X902617Y103033D01*
X902033Y102950D01*
X901533Y102700D01*
X901200Y102117D01*
X901033Y101617D01*
Y101117D01*
X901200Y100617D01*
X901617Y100117D01*
X902117Y99783D01*
X902700Y99700D01*
X903283Y99867D01*
X903867Y100367D01*
G01X906883Y99700D02*
Y103033D01*
G01Y102367D02*
X907300Y102700D01*
X907717Y102950D01*
X908300Y103033D01*
X908717Y102950D01*
X909217Y102700D01*
G01X776983Y116310D02*
Y111310D01*
X780317D01*
G01X782833D02*
Y114643D01*
G01Y113810D02*
X783167Y114227D01*
X783667Y114560D01*
X784333Y114643D01*
X784917Y114560D01*
X785417Y114227D01*
X785667Y113643D01*
Y111310D01*
G01X789850Y111143D02*
X789683Y111227D01*
Y111393D01*
X789850Y111477D01*
X790017Y111393D01*
Y111227D01*
X789850Y111143D01*
G01Y113393D02*
X789683Y113477D01*
Y113643D01*
X789850Y113727D01*
X790017Y113643D01*
Y113477D01*
X789850Y113393D01*
G01X802383Y114227D02*
X801800Y114560D01*
X801300Y114643D01*
X800633Y114477D01*
X800133Y114143D01*
X799800Y113560D01*
X799717Y112977D01*
X799800Y112393D01*
X800133Y111893D01*
X800633Y111477D01*
X801300Y111310D01*
X801883Y111477D01*
X802383Y111810D01*
G01X808150Y111310D02*
Y114643D01*
G01Y114060D02*
X807817Y114393D01*
X807317Y114560D01*
X806733Y114643D01*
X806150Y114477D01*
X805650Y114143D01*
X805317Y113643D01*
X805150Y112977D01*
X805317Y112310D01*
X805650Y111810D01*
X806150Y111477D01*
X806733Y111310D01*
X807317Y111393D01*
X807817Y111643D01*
X808150Y111977D01*
G01X810833Y111310D02*
Y114643D01*
G01Y113810D02*
X811167Y114227D01*
X811667Y114560D01*
X812333Y114643D01*
X812917Y114560D01*
X813417Y114227D01*
X813667Y113643D01*
Y111310D01*
G01X817850Y114643D02*
X818683Y115685D01*
Y116310D01*
X818058D01*
Y115685D01*
X818683D01*
G01X823450Y116310D02*
Y111310D01*
G01X822283Y114643D02*
X824617D01*
G01X833150Y111310D02*
Y116310D01*
G01Y113810D02*
X833567Y114310D01*
X834067Y114560D01*
X834567Y114643D01*
X835317Y114477D01*
X835817Y114143D01*
X836150Y113560D01*
Y112893D01*
X835983Y112227D01*
X835650Y111727D01*
X835067Y111393D01*
X834567Y111310D01*
X834067Y111393D01*
X833567Y111643D01*
X833150Y112060D01*
G01X839000Y113560D02*
X841667D01*
X841417Y114143D01*
X841000Y114477D01*
X840417Y114643D01*
X839833Y114560D01*
X839333Y114310D01*
X839000Y113727D01*
X838833Y113227D01*
Y112727D01*
X839000Y112227D01*
X839417Y111727D01*
X839917Y111393D01*
X840500Y111310D01*
X841083Y111477D01*
X841667Y111977D01*
G01X849950Y111310D02*
Y116310D01*
G01Y113810D02*
X850367Y114310D01*
X850867Y114560D01*
X851367Y114643D01*
X852117Y114477D01*
X852617Y114143D01*
X852950Y113560D01*
Y112893D01*
X852783Y112227D01*
X852450Y111727D01*
X851867Y111393D01*
X851367Y111310D01*
X850867Y111393D01*
X850367Y111643D01*
X849950Y112060D01*
G01X855883Y111310D02*
Y114643D01*
G01Y113977D02*
X856300Y114310D01*
X856717Y114560D01*
X857300Y114643D01*
X857717Y114560D01*
X858217Y114310D01*
G01X862650Y111310D02*
X862150Y111393D01*
X861650Y111727D01*
X861317Y112310D01*
X861150Y112977D01*
X861317Y113643D01*
X861650Y114227D01*
X862150Y114560D01*
X862650Y114643D01*
X863150Y114560D01*
X863650Y114227D01*
X863983Y113643D01*
X864067Y112977D01*
X863983Y112310D01*
X863650Y111727D01*
X863150Y111393D01*
X862650Y111310D01*
G01X866833D02*
Y116310D01*
G01X869500Y114643D02*
X866833Y112727D01*
G01X867917Y113477D02*
X869667Y111310D01*
G01X872600Y113560D02*
X875267D01*
X875017Y114143D01*
X874600Y114477D01*
X874017Y114643D01*
X873433Y114560D01*
X872933Y114310D01*
X872600Y113727D01*
X872433Y113227D01*
Y112727D01*
X872600Y112227D01*
X873017Y111727D01*
X873517Y111393D01*
X874100Y111310D01*
X874683Y111477D01*
X875267Y111977D01*
G01X878033Y111310D02*
Y114643D01*
G01Y113810D02*
X878367Y114227D01*
X878867Y114560D01*
X879533Y114643D01*
X880117Y114560D01*
X880617Y114227D01*
X880867Y113643D01*
Y111310D01*
G01X890650D02*
Y116310D01*
G01X897750Y111310D02*
Y114643D01*
G01Y114060D02*
X897417Y114393D01*
X896917Y114560D01*
X896333Y114643D01*
X895750Y114477D01*
X895250Y114143D01*
X894917Y113643D01*
X894750Y112977D01*
X894917Y112310D01*
X895250Y111810D01*
X895750Y111477D01*
X896333Y111310D01*
X896917Y111393D01*
X897417Y111643D01*
X897750Y111977D01*
G01X900100Y109810D02*
X900600Y109643D01*
X901267Y109810D01*
X901683Y110143D01*
X902017Y110560D01*
X902517Y111893D01*
X903600Y114643D01*
G01X900933D02*
X902517Y111893D01*
G01X906200Y113560D02*
X908867D01*
X908617Y114143D01*
X908200Y114477D01*
X907617Y114643D01*
X907033Y114560D01*
X906533Y114310D01*
X906200Y113727D01*
X906033Y113227D01*
Y112727D01*
X906200Y112227D01*
X906617Y111727D01*
X907117Y111393D01*
X907700Y111310D01*
X908283Y111477D01*
X908867Y111977D01*
G01X911883Y111310D02*
Y114643D01*
G01Y113977D02*
X912300Y114310D01*
X912717Y114560D01*
X913300Y114643D01*
X913717Y114560D01*
X914217Y114310D01*
G01X725500Y349500D02*
Y354500D01*
X722417Y350917D01*
X726583D01*
G01X730100Y349333D02*
X729933Y349417D01*
Y349583D01*
X730100Y349667D01*
X730267Y349583D01*
Y349417D01*
X730100Y349333D01*
G01X739800Y349500D02*
Y354500D01*
G01Y352000D02*
X740217Y352500D01*
X740717Y352750D01*
X741217Y352833D01*
X741967Y352667D01*
X742467Y352333D01*
X742800Y351750D01*
Y351083D01*
X742633Y350417D01*
X742300Y349917D01*
X741717Y349583D01*
X741217Y349500D01*
X740717Y349583D01*
X740217Y349833D01*
X739800Y350250D01*
G01X748400Y349500D02*
Y352833D01*
G01Y352250D02*
X748067Y352583D01*
X747567Y352750D01*
X746983Y352833D01*
X746400Y352667D01*
X745900Y352333D01*
X745567Y351833D01*
X745400Y351167D01*
X745567Y350500D01*
X745900Y350000D01*
X746400Y349667D01*
X746983Y349500D01*
X747567Y349583D01*
X748067Y349833D01*
X748400Y350167D01*
G01X753833Y352417D02*
X753250Y352750D01*
X752750Y352833D01*
X752083Y352667D01*
X751583Y352333D01*
X751250Y351750D01*
X751167Y351167D01*
X751250Y350583D01*
X751583Y350083D01*
X752083Y349667D01*
X752750Y349500D01*
X753333Y349667D01*
X753833Y350000D01*
G01X756683Y349500D02*
Y354500D01*
G01X759350Y352833D02*
X756683Y350917D01*
G01X757767Y351667D02*
X759517Y349500D01*
G01X765200Y354500D02*
Y349500D01*
G01Y350250D02*
X764867Y349833D01*
X764367Y349583D01*
X763783Y349500D01*
X763117Y349667D01*
X762617Y350083D01*
X762283Y350583D01*
X762200Y351167D01*
X762283Y351750D01*
X762617Y352250D01*
X763117Y352667D01*
X763783Y352833D01*
X764367Y352750D01*
X764783Y352583D01*
X765200Y352250D01*
G01X768133Y349500D02*
Y352833D01*
G01Y352167D02*
X768550Y352500D01*
X768967Y352750D01*
X769550Y352833D01*
X769967Y352750D01*
X770467Y352500D01*
G01X774900Y352833D02*
Y349500D01*
G01Y354167D02*
X774733Y354250D01*
Y354417D01*
X774900Y354500D01*
X775067Y354417D01*
Y354250D01*
X774900Y354167D01*
G01X780500Y349500D02*
Y354500D01*
G01X786100Y349500D02*
Y354500D01*
G01X798800Y349500D02*
Y352833D01*
G01Y352250D02*
X798467Y352583D01*
X797967Y352750D01*
X797383Y352833D01*
X796800Y352667D01*
X796300Y352333D01*
X795967Y351833D01*
X795800Y351167D01*
X795967Y350500D01*
X796300Y350000D01*
X796800Y349667D01*
X797383Y349500D01*
X797967Y349583D01*
X798467Y349833D01*
X798800Y350167D01*
G01X801483Y349500D02*
Y352833D01*
G01Y352000D02*
X801817Y352417D01*
X802317Y352750D01*
X802983Y352833D01*
X803567Y352750D01*
X804067Y352417D01*
X804317Y351833D01*
Y349500D01*
G01X810000Y354500D02*
Y349500D01*
G01Y350250D02*
X809667Y349833D01*
X809167Y349583D01*
X808583Y349500D01*
X807917Y349667D01*
X807417Y350083D01*
X807083Y350583D01*
X807000Y351167D01*
X807083Y351750D01*
X807417Y352250D01*
X807917Y352667D01*
X808583Y352833D01*
X809167Y352750D01*
X809583Y352583D01*
X810000Y352250D01*
G01X818450Y350083D02*
X818867Y349750D01*
X819450Y349500D01*
X819950D01*
X820450Y349667D01*
X820783Y349917D01*
X820950Y350250D01*
X820867Y350750D01*
X820533Y351000D01*
X819033Y351500D01*
X818700Y352083D01*
X818867Y352500D01*
X819200Y352750D01*
X819700Y352833D01*
X820200Y352750D01*
X820700Y352500D01*
G01X826800Y347833D02*
Y352833D01*
G01Y352083D02*
X826383Y352500D01*
X825883Y352750D01*
X825300Y352833D01*
X824800Y352750D01*
X824217Y352333D01*
X823883Y351750D01*
X823800Y351167D01*
X823883Y350583D01*
X824217Y350000D01*
X824800Y349583D01*
X825300Y349500D01*
X825883Y349583D01*
X826383Y349833D01*
X826800Y350250D01*
G01X829483Y352833D02*
Y350500D01*
X829817Y349917D01*
X830317Y349583D01*
X830900Y349500D01*
X831483Y349583D01*
X831983Y349917D01*
X832317Y350500D01*
G01Y349500D02*
Y352833D01*
G01X838000Y349500D02*
Y352833D01*
G01Y352250D02*
X837667Y352583D01*
X837167Y352750D01*
X836583Y352833D01*
X836000Y352667D01*
X835500Y352333D01*
X835167Y351833D01*
X835000Y351167D01*
X835167Y350500D01*
X835500Y350000D01*
X836000Y349667D01*
X836583Y349500D01*
X837167Y349583D01*
X837667Y349833D01*
X838000Y350167D01*
G01X840933Y349500D02*
Y352833D01*
G01Y352167D02*
X841350Y352500D01*
X841767Y352750D01*
X842350Y352833D01*
X842767Y352750D01*
X843267Y352500D01*
G01X846450Y351750D02*
X849117D01*
X848867Y352333D01*
X848450Y352667D01*
X847867Y352833D01*
X847283Y352750D01*
X846783Y352500D01*
X846450Y351917D01*
X846283Y351417D01*
Y350917D01*
X846450Y350417D01*
X846867Y349917D01*
X847367Y349583D01*
X847950Y349500D01*
X848533Y349667D01*
X849117Y350167D01*
G01X857483Y349500D02*
Y354500D01*
G01Y352083D02*
X857900Y352500D01*
X858317Y352750D01*
X858983Y352833D01*
X859483Y352750D01*
X860067Y352417D01*
X860317Y351917D01*
Y349500D01*
G01X864500D02*
X864000Y349583D01*
X863500Y349917D01*
X863167Y350500D01*
X863000Y351167D01*
X863167Y351833D01*
X863500Y352417D01*
X864000Y352750D01*
X864500Y352833D01*
X865000Y352750D01*
X865500Y352417D01*
X865833Y351833D01*
X865917Y351167D01*
X865833Y350500D01*
X865500Y349917D01*
X865000Y349583D01*
X864500Y349500D01*
G01X870100D02*
Y354500D01*
G01X874450Y351750D02*
X877117D01*
X876867Y352333D01*
X876450Y352667D01*
X875867Y352833D01*
X875283Y352750D01*
X874783Y352500D01*
X874450Y351917D01*
X874283Y351417D01*
Y350917D01*
X874450Y350417D01*
X874867Y349917D01*
X875367Y349583D01*
X875950Y349500D01*
X876533Y349667D01*
X877117Y350167D01*
G01X881300Y349333D02*
X881133Y349417D01*
Y349583D01*
X881300Y349667D01*
X881467Y349583D01*
Y349417D01*
X881300Y349333D01*
G01Y351583D02*
X881133Y351667D01*
Y351833D01*
X881300Y351917D01*
X881467Y351833D01*
Y351667D01*
X881300Y351583D01*
G01X721407Y374673D02*
X725073Y378340D01*
G01X723240Y379007D02*
Y374007D01*
G01X725073Y374673D02*
X721407Y378340D01*
G01X720740Y376507D02*
X725740D01*
G01X728423Y373173D02*
X727590Y374007D01*
X727173Y374840D01*
Y378173D01*
X727590Y379007D01*
X728423Y379840D01*
G01X732607Y375590D02*
X733107Y375173D01*
X733690Y374923D01*
X734440Y374840D01*
X735190Y375007D01*
X735773Y375340D01*
X736190Y375923D01*
X736273Y376590D01*
X736107Y377257D01*
X735690Y377673D01*
X735107Y378007D01*
X734523Y378090D01*
X733940Y378007D01*
X733190Y377673D01*
X733440Y379840D01*
X735690D01*
G01X740040Y374673D02*
X739873Y374757D01*
Y374923D01*
X740040Y375007D01*
X740207Y374923D01*
Y374757D01*
X740040Y374673D01*
G01X745640Y374840D02*
Y379840D01*
X744640Y378840D01*
G01Y374840D02*
X746640D01*
G01X751657Y373173D02*
X752490Y374007D01*
X752907Y374840D01*
Y378173D01*
X752490Y379007D01*
X751657Y379840D01*
G01X721107Y408303D02*
X724773Y411970D01*
G01X722940Y412637D02*
Y407637D01*
G01X724773Y408303D02*
X721107Y411970D01*
G01X720440Y410137D02*
X725440D01*
G01X728123Y406803D02*
X727290Y407637D01*
X726873Y408470D01*
Y411803D01*
X727290Y412637D01*
X728123Y413470D01*
G01X732307Y409220D02*
X732807Y408803D01*
X733390Y408553D01*
X734140Y408470D01*
X734890Y408637D01*
X735473Y408970D01*
X735890Y409553D01*
X735973Y410220D01*
X735807Y410887D01*
X735390Y411303D01*
X734807Y411637D01*
X734223Y411720D01*
X733640Y411637D01*
X732890Y411303D01*
X733140Y413470D01*
X735390D01*
G01X739740Y408303D02*
X739573Y408387D01*
Y408553D01*
X739740Y408637D01*
X739907Y408553D01*
Y408387D01*
X739740Y408303D01*
G01X745340Y408470D02*
Y413470D01*
X744340Y412470D01*
G01Y408470D02*
X746340D01*
G01X751357Y406803D02*
X752190Y407637D01*
X752607Y408470D01*
Y411803D01*
X752190Y412637D01*
X751357Y413470D01*
G01X721217Y391740D02*
X723300Y386740D01*
X725383Y391740D01*
G01X728900Y390073D02*
Y386740D01*
G01Y391407D02*
X728733Y391490D01*
Y391657D01*
X728900Y391740D01*
X729067Y391657D01*
Y391490D01*
X728900Y391407D01*
G01X736000Y386740D02*
Y390073D01*
G01Y389490D02*
X735667Y389823D01*
X735167Y389990D01*
X734583Y390073D01*
X734000Y389907D01*
X733500Y389573D01*
X733167Y389073D01*
X733000Y388407D01*
X733167Y387740D01*
X733500Y387240D01*
X734000Y386907D01*
X734583Y386740D01*
X735167Y386823D01*
X735667Y387073D01*
X736000Y387407D01*
G01X744700Y391740D02*
X746700D01*
G01X745700D02*
Y386740D01*
G01X744700D02*
X746700D01*
G01X749883D02*
Y390073D01*
G01Y389240D02*
X750217Y389657D01*
X750717Y389990D01*
X751383Y390073D01*
X751967Y389990D01*
X752467Y389657D01*
X752717Y389073D01*
Y386740D01*
G01X760833D02*
Y391740D01*
X762833D01*
X763500Y391490D01*
X764000Y390907D01*
X764167Y390240D01*
X764000Y389573D01*
X763583Y389073D01*
X762833Y388823D01*
X760833D01*
G01X769600Y386740D02*
Y390073D01*
G01Y389490D02*
X769267Y389823D01*
X768767Y389990D01*
X768183Y390073D01*
X767600Y389907D01*
X767100Y389573D01*
X766767Y389073D01*
X766600Y388407D01*
X766767Y387740D01*
X767100Y387240D01*
X767600Y386907D01*
X768183Y386740D01*
X768767Y386823D01*
X769267Y387073D01*
X769600Y387407D01*
G01X775200Y391740D02*
Y386740D01*
G01Y387490D02*
X774867Y387073D01*
X774367Y386823D01*
X773783Y386740D01*
X773117Y386907D01*
X772617Y387323D01*
X772283Y387823D01*
X772200Y388407D01*
X772283Y388990D01*
X772617Y389490D01*
X773117Y389907D01*
X773783Y390073D01*
X774367Y389990D01*
X774783Y389823D01*
X775200Y389490D01*
G01X778883Y385073D02*
X778050Y385907D01*
X777633Y386740D01*
Y390073D01*
X778050Y390907D01*
X778883Y391740D01*
G01X782817D02*
X784900Y386740D01*
X786983Y391740D01*
G01X789500D02*
X791500D01*
G01X790500D02*
Y386740D01*
G01X789500D02*
X791500D01*
G01X794433D02*
Y391740D01*
X796433D01*
X797100Y391490D01*
X797600Y390907D01*
X797767Y390240D01*
X797600Y389573D01*
X797183Y389073D01*
X796433Y388823D01*
X794433D01*
G01X802117Y385073D02*
X802950Y385907D01*
X803367Y386740D01*
Y390073D01*
X802950Y390907D01*
X802117Y391740D01*
G01X720917Y424500D02*
X723000Y419500D01*
X725083Y424500D01*
G01X728600Y422833D02*
Y419500D01*
G01Y424167D02*
X728433Y424250D01*
Y424417D01*
X728600Y424500D01*
X728767Y424417D01*
Y424250D01*
X728600Y424167D01*
G01X735700Y419500D02*
Y422833D01*
G01Y422250D02*
X735367Y422583D01*
X734867Y422750D01*
X734283Y422833D01*
X733700Y422667D01*
X733200Y422333D01*
X732867Y421833D01*
X732700Y421167D01*
X732867Y420500D01*
X733200Y420000D01*
X733700Y419667D01*
X734283Y419500D01*
X734867Y419583D01*
X735367Y419833D01*
X735700Y420167D01*
G01X745400Y419500D02*
X744733Y419583D01*
X744150Y419917D01*
X743650Y420417D01*
X743317Y421000D01*
X743150Y421667D01*
Y422333D01*
X743317Y423000D01*
X743650Y423583D01*
X744150Y424083D01*
X744733Y424417D01*
X745400Y424500D01*
X746067Y424417D01*
X746650Y424083D01*
X747150Y423583D01*
X747483Y423000D01*
X747650Y422333D01*
Y421667D01*
X747483Y421000D01*
X747150Y420417D01*
X746650Y419917D01*
X746067Y419583D01*
X745400Y419500D01*
G01X749583D02*
Y422833D01*
G01Y422000D02*
X749917Y422417D01*
X750417Y422750D01*
X751083Y422833D01*
X751667Y422750D01*
X752167Y422417D01*
X752417Y421833D01*
Y419500D01*
G01X760533D02*
Y424500D01*
X762533D01*
X763200Y424250D01*
X763700Y423667D01*
X763867Y423000D01*
X763700Y422333D01*
X763283Y421833D01*
X762533Y421583D01*
X760533D01*
G01X769300Y419500D02*
Y422833D01*
G01Y422250D02*
X768967Y422583D01*
X768467Y422750D01*
X767883Y422833D01*
X767300Y422667D01*
X766800Y422333D01*
X766467Y421833D01*
X766300Y421167D01*
X766467Y420500D01*
X766800Y420000D01*
X767300Y419667D01*
X767883Y419500D01*
X768467Y419583D01*
X768967Y419833D01*
X769300Y420167D01*
G01X774900Y424500D02*
Y419500D01*
G01Y420250D02*
X774567Y419833D01*
X774067Y419583D01*
X773483Y419500D01*
X772817Y419667D01*
X772317Y420083D01*
X771983Y420583D01*
X771900Y421167D01*
X771983Y421750D01*
X772317Y422250D01*
X772817Y422667D01*
X773483Y422833D01*
X774067Y422750D01*
X774483Y422583D01*
X774900Y422250D01*
G01X778583Y417833D02*
X777750Y418667D01*
X777333Y419500D01*
Y422833D01*
X777750Y423667D01*
X778583Y424500D01*
G01X782517D02*
X784600Y419500D01*
X786683Y424500D01*
G01X790200Y419500D02*
X789533Y419583D01*
X788950Y419917D01*
X788450Y420417D01*
X788117Y421000D01*
X787950Y421667D01*
Y422333D01*
X788117Y423000D01*
X788450Y423583D01*
X788950Y424083D01*
X789533Y424417D01*
X790200Y424500D01*
X790867Y424417D01*
X791450Y424083D01*
X791950Y423583D01*
X792283Y423000D01*
X792450Y422333D01*
Y421667D01*
X792283Y421000D01*
X791950Y420417D01*
X791450Y419917D01*
X790867Y419583D01*
X790200Y419500D01*
G01X794133D02*
Y424500D01*
X796133D01*
X796800Y424250D01*
X797300Y423667D01*
X797467Y423000D01*
X797300Y422333D01*
X796883Y421833D01*
X796133Y421583D01*
X794133D01*
G01X801817Y417833D02*
X802650Y418667D01*
X803067Y419500D01*
Y422833D01*
X802650Y423667D01*
X801817Y424500D01*
G01X723667Y443167D02*
X724000Y443417D01*
X724250Y443833D01*
X724417Y444417D01*
X724250Y444917D01*
X723917Y445250D01*
X723333Y445500D01*
X721083D01*
Y440500D01*
X723833D01*
X724417Y440833D01*
X724750Y441333D01*
X724917Y441917D01*
X724750Y442500D01*
X724250Y443000D01*
X723667Y443167D01*
X721083D01*
G01X727183Y443833D02*
Y441500D01*
X727517Y440917D01*
X728017Y440583D01*
X728600Y440500D01*
X729183Y440583D01*
X729683Y440917D01*
X730017Y441500D01*
G01Y440500D02*
Y443833D01*
G01X733033Y440500D02*
Y443833D01*
G01Y443167D02*
X733450Y443500D01*
X733867Y443750D01*
X734450Y443833D01*
X734867Y443750D01*
X735367Y443500D01*
G01X739800Y443833D02*
Y440500D01*
G01Y445167D02*
X739633Y445250D01*
Y445417D01*
X739800Y445500D01*
X739967Y445417D01*
Y445250D01*
X739800Y445167D01*
G01X744150Y442750D02*
X746817D01*
X746567Y443333D01*
X746150Y443667D01*
X745567Y443833D01*
X744983Y443750D01*
X744483Y443500D01*
X744150Y442917D01*
X743983Y442417D01*
Y441917D01*
X744150Y441417D01*
X744567Y440917D01*
X745067Y440583D01*
X745650Y440500D01*
X746233Y440667D01*
X746817Y441167D01*
G01X752500Y445500D02*
Y440500D01*
G01Y441250D02*
X752167Y440833D01*
X751667Y440583D01*
X751083Y440500D01*
X750417Y440667D01*
X749917Y441083D01*
X749583Y441583D01*
X749500Y442167D01*
X749583Y442750D01*
X749917Y443250D01*
X750417Y443667D01*
X751083Y443833D01*
X751667Y443750D01*
X752083Y443583D01*
X752500Y443250D01*
G01X760783Y440500D02*
Y445500D01*
G01Y443083D02*
X761200Y443500D01*
X761617Y443750D01*
X762283Y443833D01*
X762783Y443750D01*
X763367Y443417D01*
X763617Y442917D01*
Y440500D01*
G01X767800D02*
X767300Y440583D01*
X766800Y440917D01*
X766467Y441500D01*
X766300Y442167D01*
X766467Y442833D01*
X766800Y443417D01*
X767300Y443750D01*
X767800Y443833D01*
X768300Y443750D01*
X768800Y443417D01*
X769133Y442833D01*
X769217Y442167D01*
X769133Y441500D01*
X768800Y440917D01*
X768300Y440583D01*
X767800Y440500D01*
G01X773400D02*
Y445500D01*
G01X777750Y442750D02*
X780417D01*
X780167Y443333D01*
X779750Y443667D01*
X779167Y443833D01*
X778583Y443750D01*
X778083Y443500D01*
X777750Y442917D01*
X777583Y442417D01*
Y441917D01*
X777750Y441417D01*
X778167Y440917D01*
X778667Y440583D01*
X779250Y440500D01*
X779833Y440667D01*
X780417Y441167D01*
G01X721417Y461500D02*
Y466500D01*
X724583D01*
G01X723417Y464083D02*
X721417D01*
G01X727183Y464833D02*
Y462500D01*
X727517Y461917D01*
X728017Y461583D01*
X728600Y461500D01*
X729183Y461583D01*
X729683Y461917D01*
X730017Y462500D01*
G01Y461500D02*
Y464833D01*
G01X734200Y461500D02*
Y466500D01*
G01X739800Y461500D02*
Y466500D01*
G01X749500Y459833D02*
Y464833D01*
G01Y464083D02*
X749917Y464500D01*
X750333Y464750D01*
X751000Y464833D01*
X751583Y464750D01*
X752167Y464333D01*
X752417Y463750D01*
X752500Y463167D01*
X752417Y462583D01*
X752167Y462000D01*
X751667Y461667D01*
X751000Y461500D01*
X750417Y461583D01*
X749833Y461833D01*
X749500Y462167D01*
G01X756600Y461500D02*
Y466500D01*
G01X760783Y464833D02*
Y462500D01*
X761117Y461917D01*
X761617Y461583D01*
X762200Y461500D01*
X762783Y461583D01*
X763283Y461917D01*
X763617Y462500D01*
G01Y461500D02*
Y464833D01*
G01X766633Y460250D02*
X767217Y459917D01*
X767883Y459833D01*
X768467Y459917D01*
X768967Y460333D01*
X769300Y460917D01*
Y464833D01*
G01Y464167D02*
X768967Y464500D01*
X768467Y464750D01*
X767883Y464833D01*
X767217Y464667D01*
X766800Y464333D01*
X766467Y463750D01*
X766300Y463167D01*
X766383Y462667D01*
X766717Y462083D01*
X767217Y461667D01*
X767883Y461500D01*
X768383Y461583D01*
X768967Y461917D01*
X769300Y462250D01*
G01X772233Y460250D02*
X772817Y459917D01*
X773483Y459833D01*
X774067Y459917D01*
X774567Y460333D01*
X774900Y460917D01*
Y464833D01*
G01Y464167D02*
X774567Y464500D01*
X774067Y464750D01*
X773483Y464833D01*
X772817Y464667D01*
X772400Y464333D01*
X772067Y463750D01*
X771900Y463167D01*
X771983Y462667D01*
X772317Y462083D01*
X772817Y461667D01*
X773483Y461500D01*
X773983Y461583D01*
X774567Y461917D01*
X774900Y462250D01*
G01X779000Y464833D02*
Y461500D01*
G01Y466167D02*
X778833Y466250D01*
Y466417D01*
X779000Y466500D01*
X779167Y466417D01*
Y466250D01*
X779000Y466167D01*
G01X783183Y461500D02*
Y464833D01*
G01Y464000D02*
X783517Y464417D01*
X784017Y464750D01*
X784683Y464833D01*
X785267Y464750D01*
X785767Y464417D01*
X786017Y463833D01*
Y461500D01*
G01X789033Y460250D02*
X789617Y459917D01*
X790283Y459833D01*
X790867Y459917D01*
X791367Y460333D01*
X791700Y460917D01*
Y464833D01*
G01Y464167D02*
X791367Y464500D01*
X790867Y464750D01*
X790283Y464833D01*
X789617Y464667D01*
X789200Y464333D01*
X788867Y463750D01*
X788700Y463167D01*
X788783Y462667D01*
X789117Y462083D01*
X789617Y461667D01*
X790283Y461500D01*
X790783Y461583D01*
X791367Y461917D01*
X791700Y462250D01*
G01X721250Y530000D02*
Y535000D01*
G01X724750D02*
Y530000D01*
G01Y532500D02*
X721250D01*
G01X730100Y530000D02*
Y533333D01*
G01Y532750D02*
X729767Y533083D01*
X729267Y533250D01*
X728683Y533333D01*
X728100Y533167D01*
X727600Y532833D01*
X727267Y532333D01*
X727100Y531667D01*
X727267Y531000D01*
X727600Y530500D01*
X728100Y530167D01*
X728683Y530000D01*
X729267Y530083D01*
X729767Y530333D01*
X730100Y530667D01*
G01X734200Y530000D02*
Y535000D01*
G01X739300Y530000D02*
Y534250D01*
X739467Y534667D01*
X739800Y534917D01*
X740300Y535000D01*
X740800Y534833D01*
X741050Y534417D01*
G01X740050Y533000D02*
X738383D01*
G01X749333Y530000D02*
Y535000D01*
X751333D01*
X752000Y534750D01*
X752500Y534167D01*
X752667Y533500D01*
X752500Y532833D01*
X752083Y532333D01*
X751333Y532083D01*
X749333D01*
G01X756600Y530000D02*
Y535000D01*
G01X760783Y533333D02*
Y531000D01*
X761117Y530417D01*
X761617Y530083D01*
X762200Y530000D01*
X762783Y530083D01*
X763283Y530417D01*
X763617Y531000D01*
G01Y530000D02*
Y533333D01*
G01X766633Y528750D02*
X767217Y528417D01*
X767883Y528333D01*
X768467Y528417D01*
X768967Y528833D01*
X769300Y529417D01*
Y533333D01*
G01Y532667D02*
X768967Y533000D01*
X768467Y533250D01*
X767883Y533333D01*
X767217Y533167D01*
X766800Y532833D01*
X766467Y532250D01*
X766300Y531667D01*
X766383Y531167D01*
X766717Y530583D01*
X767217Y530167D01*
X767883Y530000D01*
X768383Y530083D01*
X768967Y530417D01*
X769300Y530750D01*
G01X772233Y528750D02*
X772817Y528417D01*
X773483Y528333D01*
X774067Y528417D01*
X774567Y528833D01*
X774900Y529417D01*
Y533333D01*
G01Y532667D02*
X774567Y533000D01*
X774067Y533250D01*
X773483Y533333D01*
X772817Y533167D01*
X772400Y532833D01*
X772067Y532250D01*
X771900Y531667D01*
X771983Y531167D01*
X772317Y530583D01*
X772817Y530167D01*
X773483Y530000D01*
X773983Y530083D01*
X774567Y530417D01*
X774900Y530750D01*
G01X779000Y533333D02*
Y530000D01*
G01Y534667D02*
X778833Y534750D01*
Y534917D01*
X779000Y535000D01*
X779167Y534917D01*
Y534750D01*
X779000Y534667D01*
G01X783183Y530000D02*
Y533333D01*
G01Y532500D02*
X783517Y532917D01*
X784017Y533250D01*
X784683Y533333D01*
X785267Y533250D01*
X785767Y532917D01*
X786017Y532333D01*
Y530000D01*
G01X789033Y528750D02*
X789617Y528417D01*
X790283Y528333D01*
X790867Y528417D01*
X791367Y528833D01*
X791700Y529417D01*
Y533333D01*
G01Y532667D02*
X791367Y533000D01*
X790867Y533250D01*
X790283Y533333D01*
X789617Y533167D01*
X789200Y532833D01*
X788867Y532250D01*
X788700Y531667D01*
X788783Y531167D01*
X789117Y530583D01*
X789617Y530167D01*
X790283Y530000D01*
X790783Y530083D01*
X791367Y530417D01*
X791700Y530750D01*
G01X722833Y589000D02*
Y594000D01*
X724833D01*
X725500Y593750D01*
X726000Y593167D01*
X726167Y592500D01*
X726000Y591833D01*
X725583Y591333D01*
X724833Y591083D01*
X722833D01*
G01X730100Y589000D02*
Y594000D01*
G01X734283Y592333D02*
Y590000D01*
X734617Y589417D01*
X735117Y589083D01*
X735700Y589000D01*
X736283Y589083D01*
X736783Y589417D01*
X737117Y590000D01*
G01Y589000D02*
Y592333D01*
G01X740133Y587750D02*
X740717Y587417D01*
X741383Y587333D01*
X741967Y587417D01*
X742467Y587833D01*
X742800Y588417D01*
Y592333D01*
G01Y591667D02*
X742467Y592000D01*
X741967Y592250D01*
X741383Y592333D01*
X740717Y592167D01*
X740300Y591833D01*
X739967Y591250D01*
X739800Y590667D01*
X739883Y590167D01*
X740217Y589583D01*
X740717Y589167D01*
X741383Y589000D01*
X741883Y589083D01*
X742467Y589417D01*
X742800Y589750D01*
G01X745733Y587750D02*
X746317Y587417D01*
X746983Y587333D01*
X747567Y587417D01*
X748067Y587833D01*
X748400Y588417D01*
Y592333D01*
G01Y591667D02*
X748067Y592000D01*
X747567Y592250D01*
X746983Y592333D01*
X746317Y592167D01*
X745900Y591833D01*
X745567Y591250D01*
X745400Y590667D01*
X745483Y590167D01*
X745817Y589583D01*
X746317Y589167D01*
X746983Y589000D01*
X747483Y589083D01*
X748067Y589417D01*
X748400Y589750D01*
G01X752500Y592333D02*
Y589000D01*
G01Y593667D02*
X752333Y593750D01*
Y593917D01*
X752500Y594000D01*
X752667Y593917D01*
Y593750D01*
X752500Y593667D01*
G01X756683Y589000D02*
Y592333D01*
G01Y591500D02*
X757017Y591917D01*
X757517Y592250D01*
X758183Y592333D01*
X758767Y592250D01*
X759267Y591917D01*
X759517Y591333D01*
Y589000D01*
G01X762533Y587750D02*
X763117Y587417D01*
X763783Y587333D01*
X764367Y587417D01*
X764867Y587833D01*
X765200Y588417D01*
Y592333D01*
G01Y591667D02*
X764867Y592000D01*
X764367Y592250D01*
X763783Y592333D01*
X763117Y592167D01*
X762700Y591833D01*
X762367Y591250D01*
X762200Y590667D01*
X762283Y590167D01*
X762617Y589583D01*
X763117Y589167D01*
X763783Y589000D01*
X764283Y589083D01*
X764867Y589417D01*
X765200Y589750D01*
G01X776400Y594000D02*
Y589000D01*
G01Y589750D02*
X776067Y589333D01*
X775567Y589083D01*
X774983Y589000D01*
X774317Y589167D01*
X773817Y589583D01*
X773483Y590083D01*
X773400Y590667D01*
X773483Y591250D01*
X773817Y591750D01*
X774317Y592167D01*
X774983Y592333D01*
X775567Y592250D01*
X775983Y592083D01*
X776400Y591750D01*
G01X779250Y591250D02*
X781917D01*
X781667Y591833D01*
X781250Y592167D01*
X780667Y592333D01*
X780083Y592250D01*
X779583Y592000D01*
X779250Y591417D01*
X779083Y590917D01*
Y590417D01*
X779250Y589917D01*
X779667Y589417D01*
X780167Y589083D01*
X780750Y589000D01*
X781333Y589167D01*
X781917Y589667D01*
G01X785600Y589000D02*
Y593250D01*
X785767Y593667D01*
X786100Y593917D01*
X786600Y594000D01*
X787100Y593833D01*
X787350Y593417D01*
G01X786350Y592000D02*
X784683D01*
G01X791700Y592333D02*
Y589000D01*
G01Y593667D02*
X791533Y593750D01*
Y593917D01*
X791700Y594000D01*
X791867Y593917D01*
Y593750D01*
X791700Y593667D01*
G01X795883Y589000D02*
Y592333D01*
G01Y591500D02*
X796217Y591917D01*
X796717Y592250D01*
X797383Y592333D01*
X797967Y592250D01*
X798467Y591917D01*
X798717Y591333D01*
Y589000D01*
G01X801650Y591250D02*
X804317D01*
X804067Y591833D01*
X803650Y592167D01*
X803067Y592333D01*
X802483Y592250D01*
X801983Y592000D01*
X801650Y591417D01*
X801483Y590917D01*
Y590417D01*
X801650Y589917D01*
X802067Y589417D01*
X802567Y589083D01*
X803150Y589000D01*
X803733Y589167D01*
X804317Y589667D01*
G01X722667Y765000D02*
X723167Y764417D01*
X723833Y764083D01*
X724583Y764000D01*
X725250Y764083D01*
X725917Y764500D01*
X726333Y765000D01*
X726417Y765500D01*
X726250Y766083D01*
X725667Y766500D01*
X725083Y766667D01*
X724333D01*
G01X725083D02*
X725583Y766917D01*
X726000Y767333D01*
X726167Y767833D01*
X726000Y768333D01*
X725583Y768750D01*
X724833Y769000D01*
X724083Y768917D01*
X723333Y768583D01*
G01X730100Y763833D02*
X729933Y763917D01*
Y764083D01*
X730100Y764167D01*
X730267Y764083D01*
Y763917D01*
X730100Y763833D01*
G01X739633Y764000D02*
Y769000D01*
X741633D01*
X742300Y768750D01*
X742800Y768167D01*
X742967Y767500D01*
X742800Y766833D01*
X742383Y766333D01*
X741633Y766083D01*
X739633D01*
G01X746900Y764000D02*
Y769000D01*
G01X751083Y767333D02*
Y765000D01*
X751417Y764417D01*
X751917Y764083D01*
X752500Y764000D01*
X753083Y764083D01*
X753583Y764417D01*
X753917Y765000D01*
G01Y764000D02*
Y767333D01*
G01X756933Y762750D02*
X757517Y762417D01*
X758183Y762333D01*
X758767Y762417D01*
X759267Y762833D01*
X759600Y763417D01*
Y767333D01*
G01Y766667D02*
X759267Y767000D01*
X758767Y767250D01*
X758183Y767333D01*
X757517Y767167D01*
X757100Y766833D01*
X756767Y766250D01*
X756600Y765667D01*
X756683Y765167D01*
X757017Y764583D01*
X757517Y764167D01*
X758183Y764000D01*
X758683Y764083D01*
X759267Y764417D01*
X759600Y764750D01*
G01X767800Y767333D02*
X769300Y764000D01*
X770800Y767333D01*
G01X774900D02*
Y764000D01*
G01Y768667D02*
X774733Y768750D01*
Y768917D01*
X774900Y769000D01*
X775067Y768917D01*
Y768750D01*
X774900Y768667D01*
G01X782000Y764000D02*
Y767333D01*
G01Y766750D02*
X781667Y767083D01*
X781167Y767250D01*
X780583Y767333D01*
X780000Y767167D01*
X779500Y766833D01*
X779167Y766333D01*
X779000Y765667D01*
X779167Y765000D01*
X779500Y764500D01*
X780000Y764167D01*
X780583Y764000D01*
X781167Y764083D01*
X781667Y764333D01*
X782000Y764667D01*
G01X790200Y763833D02*
X793200Y769000D01*
G01X795217D02*
X797300Y764000D01*
X799383Y769000D01*
G01X802900Y764000D02*
X802233Y764083D01*
X801650Y764417D01*
X801150Y764917D01*
X800817Y765500D01*
X800650Y766167D01*
Y766833D01*
X800817Y767500D01*
X801150Y768083D01*
X801650Y768583D01*
X802233Y768917D01*
X802900Y769000D01*
X803567Y768917D01*
X804150Y768583D01*
X804650Y768083D01*
X804983Y767500D01*
X805150Y766833D01*
Y766167D01*
X804983Y765500D01*
X804650Y764917D01*
X804150Y764417D01*
X803567Y764083D01*
X802900Y764000D01*
G01X806833D02*
Y769000D01*
X808833D01*
X809500Y768750D01*
X810000Y768167D01*
X810167Y767500D01*
X810000Y766833D01*
X809583Y766333D01*
X808833Y766083D01*
X806833D01*
G01X812600Y763833D02*
X815600Y769000D01*
G01X817617D02*
X819700Y764000D01*
X821783Y769000D01*
G01X824300D02*
X826300D01*
G01X825300D02*
Y764000D01*
G01X824300D02*
X826300D01*
G01X829233D02*
Y769000D01*
X831233D01*
X831900Y768750D01*
X832400Y768167D01*
X832567Y767500D01*
X832400Y766833D01*
X831983Y766333D01*
X831233Y766083D01*
X829233D01*
G01X836500Y763833D02*
X836333Y763917D01*
Y764083D01*
X836500Y764167D01*
X836667Y764083D01*
Y763917D01*
X836500Y763833D01*
G01Y766083D02*
X836333Y766167D01*
Y766333D01*
X836500Y766417D01*
X836667Y766333D01*
Y766167D01*
X836500Y766083D01*
G01X724813Y813000D02*
Y818000D01*
X726897D01*
X727563Y817750D01*
X727980Y817417D01*
X728147Y816750D01*
X727980Y816083D01*
X727480Y815667D01*
X726897Y815417D01*
X724813D01*
G01X726897D02*
X728147Y813000D01*
G01X732080D02*
X731580Y813083D01*
X731080Y813417D01*
X730747Y814000D01*
X730580Y814667D01*
X730747Y815333D01*
X731080Y815917D01*
X731580Y816250D01*
X732080Y816333D01*
X732580Y816250D01*
X733080Y815917D01*
X733413Y815333D01*
X733497Y814667D01*
X733413Y814000D01*
X733080Y813417D01*
X732580Y813083D01*
X732080Y813000D01*
G01X736263Y816333D02*
Y814000D01*
X736597Y813417D01*
X737097Y813083D01*
X737680Y813000D01*
X738263Y813083D01*
X738763Y813417D01*
X739097Y814000D01*
G01Y813000D02*
Y816333D01*
G01X743280Y818000D02*
Y813000D01*
G01X742113Y816333D02*
X744447D01*
G01X748880D02*
Y813000D01*
G01Y817667D02*
X748713Y817750D01*
Y817917D01*
X748880Y818000D01*
X749047Y817917D01*
Y817750D01*
X748880Y817667D01*
G01X753063Y813000D02*
Y816333D01*
G01Y815500D02*
X753397Y815917D01*
X753897Y816250D01*
X754563Y816333D01*
X755147Y816250D01*
X755647Y815917D01*
X755897Y815333D01*
Y813000D01*
G01X758913Y811750D02*
X759497Y811417D01*
X760163Y811333D01*
X760747Y811417D01*
X761247Y811833D01*
X761580Y812417D01*
Y816333D01*
G01Y815667D02*
X761247Y816000D01*
X760747Y816250D01*
X760163Y816333D01*
X759497Y816167D01*
X759080Y815833D01*
X758747Y815250D01*
X758580Y814667D01*
X758663Y814167D01*
X758997Y813583D01*
X759497Y813167D01*
X760163Y813000D01*
X760663Y813083D01*
X761247Y813417D01*
X761580Y813750D01*
G01X802167Y-15500D02*
Y-10500D01*
X803833D01*
X804500Y-10750D01*
X805000Y-11083D01*
X805417Y-11583D01*
X805750Y-12167D01*
X805833Y-13000D01*
X805750Y-13833D01*
X805417Y-14417D01*
X805000Y-14917D01*
X804500Y-15250D01*
X803833Y-15500D01*
X802167D01*
G01X809600D02*
Y-10500D01*
X808600Y-11500D01*
G01Y-15500D02*
X810600D01*
G01X813617Y-13417D02*
X814200Y-12833D01*
X814700Y-12500D01*
X815367Y-12333D01*
X815950Y-12500D01*
X816367Y-12833D01*
X816700Y-13333D01*
X816783Y-13917D01*
X816700Y-14417D01*
X816367Y-14917D01*
X815867Y-15333D01*
X815283Y-15500D01*
X814617Y-15333D01*
X814033Y-14833D01*
X813700Y-14083D01*
X813617Y-13250D01*
X813783Y-12167D01*
X814033Y-11583D01*
X814450Y-11000D01*
X815033Y-10583D01*
X815617Y-10500D01*
X816200Y-10667D01*
X816617Y-11083D01*
G01X827667Y150500D02*
Y155500D01*
X829333D01*
X830000Y155250D01*
X830500Y154917D01*
X830917Y154417D01*
X831250Y153833D01*
X831333Y153000D01*
X831250Y152167D01*
X830917Y151583D01*
X830500Y151083D01*
X830000Y150750D01*
X829333Y150500D01*
X827667D01*
G01X835100D02*
Y155500D01*
X834100Y154500D01*
G01Y150500D02*
X836100D01*
G01X825667Y314500D02*
Y319500D01*
X827333D01*
X828000Y319250D01*
X828500Y318917D01*
X828917Y318417D01*
X829250Y317833D01*
X829333Y317000D01*
X829250Y316167D01*
X828917Y315583D01*
X828500Y315083D01*
X828000Y314750D01*
X827333Y314500D01*
X825667D01*
G01X831517Y318667D02*
X832017Y319167D01*
X832600Y319417D01*
X833267Y319500D01*
X834100Y319333D01*
X834683Y318917D01*
X834850Y318417D01*
X834767Y317917D01*
X834433Y317500D01*
X832767Y316667D01*
X832017Y316083D01*
X831517Y315250D01*
X831350Y314500D01*
X834850D01*
G01X821590Y376450D02*
Y379783D01*
G01Y379200D02*
X821257Y379533D01*
X820757Y379700D01*
X820173Y379783D01*
X819590Y379617D01*
X819090Y379283D01*
X818757Y378783D01*
X818590Y378117D01*
X818757Y377450D01*
X819090Y376950D01*
X819590Y376617D01*
X820173Y376450D01*
X820757Y376533D01*
X821257Y376783D01*
X821590Y377117D01*
G01X824273Y376450D02*
Y379783D01*
G01Y378950D02*
X824607Y379367D01*
X825107Y379700D01*
X825773Y379783D01*
X826357Y379700D01*
X826857Y379367D01*
X827107Y378783D01*
Y376450D01*
G01X832790Y381450D02*
Y376450D01*
G01Y377200D02*
X832457Y376783D01*
X831957Y376533D01*
X831373Y376450D01*
X830707Y376617D01*
X830207Y377033D01*
X829873Y377533D01*
X829790Y378117D01*
X829873Y378700D01*
X830207Y379200D01*
X830707Y379617D01*
X831373Y379783D01*
X831957Y379700D01*
X832373Y379533D01*
X832790Y379200D01*
G01X843823Y379367D02*
X843240Y379700D01*
X842740Y379783D01*
X842073Y379617D01*
X841573Y379283D01*
X841240Y378700D01*
X841157Y378117D01*
X841240Y377533D01*
X841573Y377033D01*
X842073Y376617D01*
X842740Y376450D01*
X843323Y376617D01*
X843823Y376950D01*
G01X848090Y376450D02*
X847590Y376533D01*
X847090Y376867D01*
X846757Y377450D01*
X846590Y378117D01*
X846757Y378783D01*
X847090Y379367D01*
X847590Y379700D01*
X848090Y379783D01*
X848590Y379700D01*
X849090Y379367D01*
X849423Y378783D01*
X849507Y378117D01*
X849423Y377450D01*
X849090Y376867D01*
X848590Y376533D01*
X848090Y376450D01*
G01X852190Y379783D02*
X853690Y376450D01*
X855190Y379783D01*
G01X858040Y378700D02*
X860707D01*
X860457Y379283D01*
X860040Y379617D01*
X859457Y379783D01*
X858873Y379700D01*
X858373Y379450D01*
X858040Y378867D01*
X857873Y378367D01*
Y377867D01*
X858040Y377367D01*
X858457Y376867D01*
X858957Y376533D01*
X859540Y376450D01*
X860123Y376617D01*
X860707Y377117D01*
G01X863723Y376450D02*
Y379783D01*
G01Y379117D02*
X864140Y379450D01*
X864557Y379700D01*
X865140Y379783D01*
X865557Y379700D01*
X866057Y379450D01*
G01X869240Y378700D02*
X871907D01*
X871657Y379283D01*
X871240Y379617D01*
X870657Y379783D01*
X870073Y379700D01*
X869573Y379450D01*
X869240Y378867D01*
X869073Y378367D01*
Y377867D01*
X869240Y377367D01*
X869657Y376867D01*
X870157Y376533D01*
X870740Y376450D01*
X871323Y376617D01*
X871907Y377117D01*
G01X877590Y381450D02*
Y376450D01*
G01Y377200D02*
X877257Y376783D01*
X876757Y376533D01*
X876173Y376450D01*
X875507Y376617D01*
X875007Y377033D01*
X874673Y377533D01*
X874590Y378117D01*
X874673Y378700D01*
X875007Y379200D01*
X875507Y379617D01*
X876173Y379783D01*
X876757Y379700D01*
X877173Y379533D01*
X877590Y379200D01*
G01X885207Y379783D02*
X886207Y376450D01*
X887290Y379783D01*
X888373Y376450D01*
X889373Y379783D01*
G01X892890D02*
Y376450D01*
G01Y381117D02*
X892723Y381200D01*
Y381367D01*
X892890Y381450D01*
X893057Y381367D01*
Y381200D01*
X892890Y381117D01*
G01X898490Y381450D02*
Y376450D01*
G01X897323Y379783D02*
X899657D01*
G01X902673Y376450D02*
Y381450D01*
G01Y379033D02*
X903090Y379450D01*
X903507Y379700D01*
X904173Y379783D01*
X904673Y379700D01*
X905257Y379367D01*
X905507Y378867D01*
Y376450D01*
G01X916623Y379367D02*
X916040Y379700D01*
X915540Y379783D01*
X914873Y379617D01*
X914373Y379283D01*
X914040Y378700D01*
X913957Y378117D01*
X914040Y377533D01*
X914373Y377033D01*
X914873Y376617D01*
X915540Y376450D01*
X916123Y376617D01*
X916623Y376950D01*
G01X920890Y376450D02*
X920390Y376533D01*
X919890Y376867D01*
X919557Y377450D01*
X919390Y378117D01*
X919557Y378783D01*
X919890Y379367D01*
X920390Y379700D01*
X920890Y379783D01*
X921390Y379700D01*
X921890Y379367D01*
X922223Y378783D01*
X922307Y378117D01*
X922223Y377450D01*
X921890Y376867D01*
X921390Y376533D01*
X920890Y376450D01*
G01X924990Y374783D02*
Y379783D01*
G01Y379033D02*
X925407Y379450D01*
X925823Y379700D01*
X926490Y379783D01*
X927073Y379700D01*
X927657Y379283D01*
X927907Y378700D01*
X927990Y378117D01*
X927907Y377533D01*
X927657Y376950D01*
X927157Y376617D01*
X926490Y376450D01*
X925907Y376533D01*
X925323Y376783D01*
X924990Y377117D01*
G01X930590Y374783D02*
Y379783D01*
G01Y379033D02*
X931007Y379450D01*
X931423Y379700D01*
X932090Y379783D01*
X932673Y379700D01*
X933257Y379283D01*
X933507Y378700D01*
X933590Y378117D01*
X933507Y377533D01*
X933257Y376950D01*
X932757Y376617D01*
X932090Y376450D01*
X931507Y376533D01*
X930923Y376783D01*
X930590Y377117D01*
G01X936440Y378700D02*
X939107D01*
X938857Y379283D01*
X938440Y379617D01*
X937857Y379783D01*
X937273Y379700D01*
X936773Y379450D01*
X936440Y378867D01*
X936273Y378367D01*
Y377867D01*
X936440Y377367D01*
X936857Y376867D01*
X937357Y376533D01*
X937940Y376450D01*
X938523Y376617D01*
X939107Y377117D01*
G01X942123Y376450D02*
Y379783D01*
G01Y379117D02*
X942540Y379450D01*
X942957Y379700D01*
X943540Y379783D01*
X943957Y379700D01*
X944457Y379450D01*
G01X821500Y419500D02*
Y423750D01*
X821667Y424167D01*
X822000Y424417D01*
X822500Y424500D01*
X823000Y424333D01*
X823250Y423917D01*
G01X822250Y422500D02*
X820583D01*
G01X827600Y419500D02*
X827100Y419583D01*
X826600Y419917D01*
X826267Y420500D01*
X826100Y421167D01*
X826267Y421833D01*
X826600Y422417D01*
X827100Y422750D01*
X827600Y422833D01*
X828100Y422750D01*
X828600Y422417D01*
X828933Y421833D01*
X829017Y421167D01*
X828933Y420500D01*
X828600Y419917D01*
X828100Y419583D01*
X827600Y419500D01*
G01X833200D02*
Y424500D01*
G01X838800Y419500D02*
Y424500D01*
G01X844400Y419500D02*
X843900Y419583D01*
X843400Y419917D01*
X843067Y420500D01*
X842900Y421167D01*
X843067Y421833D01*
X843400Y422417D01*
X843900Y422750D01*
X844400Y422833D01*
X844900Y422750D01*
X845400Y422417D01*
X845733Y421833D01*
X845817Y421167D01*
X845733Y420500D01*
X845400Y419917D01*
X844900Y419583D01*
X844400Y419500D01*
G01X847917Y422833D02*
X848917Y419500D01*
X850000Y422833D01*
X851083Y419500D01*
X852083Y422833D01*
G01X861700Y422000D02*
X863367D01*
Y420500D01*
X862867Y420000D01*
X862283Y419667D01*
X861450Y419500D01*
X860617Y419667D01*
X860033Y420000D01*
X859533Y420500D01*
X859200Y421083D01*
X859033Y421750D01*
Y422333D01*
X859200Y422833D01*
X859533Y423417D01*
X860033Y423917D01*
X860533Y424250D01*
X861200Y424500D01*
X861783D01*
X862450Y424333D01*
X862950Y424000D01*
G01X865550Y421750D02*
X868217D01*
X867967Y422333D01*
X867550Y422667D01*
X866967Y422833D01*
X866383Y422750D01*
X865883Y422500D01*
X865550Y421917D01*
X865383Y421417D01*
Y420917D01*
X865550Y420417D01*
X865967Y419917D01*
X866467Y419583D01*
X867050Y419500D01*
X867633Y419667D01*
X868217Y420167D01*
G01X871233Y419500D02*
Y422833D01*
G01Y422167D02*
X871650Y422500D01*
X872067Y422750D01*
X872650Y422833D01*
X873067Y422750D01*
X873567Y422500D01*
G01X876500Y419500D02*
Y424500D01*
G01Y422000D02*
X876917Y422500D01*
X877417Y422750D01*
X877917Y422833D01*
X878667Y422667D01*
X879167Y422333D01*
X879500Y421750D01*
Y421083D01*
X879333Y420417D01*
X879000Y419917D01*
X878417Y419583D01*
X877917Y419500D01*
X877417Y419583D01*
X876917Y419833D01*
X876500Y420250D01*
G01X882350Y421750D02*
X885017D01*
X884767Y422333D01*
X884350Y422667D01*
X883767Y422833D01*
X883183Y422750D01*
X882683Y422500D01*
X882350Y421917D01*
X882183Y421417D01*
Y420917D01*
X882350Y420417D01*
X882767Y419917D01*
X883267Y419583D01*
X883850Y419500D01*
X884433Y419667D01*
X885017Y420167D01*
G01X888033Y419500D02*
Y422833D01*
G01Y422167D02*
X888450Y422500D01*
X888867Y422750D01*
X889450Y422833D01*
X889867Y422750D01*
X890367Y422500D01*
G01X901900Y419500D02*
Y422833D01*
G01Y422250D02*
X901567Y422583D01*
X901067Y422750D01*
X900483Y422833D01*
X899900Y422667D01*
X899400Y422333D01*
X899067Y421833D01*
X898900Y421167D01*
X899067Y420500D01*
X899400Y420000D01*
X899900Y419667D01*
X900483Y419500D01*
X901067Y419583D01*
X901567Y419833D01*
X901900Y420167D01*
G01X904583Y419500D02*
Y422833D01*
G01Y422000D02*
X904917Y422417D01*
X905417Y422750D01*
X906083Y422833D01*
X906667Y422750D01*
X907167Y422417D01*
X907417Y421833D01*
Y419500D01*
G01X913100Y424500D02*
Y419500D01*
G01Y420250D02*
X912767Y419833D01*
X912267Y419583D01*
X911683Y419500D01*
X911017Y419667D01*
X910517Y420083D01*
X910183Y420583D01*
X910100Y421167D01*
X910183Y421750D01*
X910517Y422250D01*
X911017Y422667D01*
X911683Y422833D01*
X912267Y422750D01*
X912683Y422583D01*
X913100Y422250D01*
G01X921300Y417833D02*
Y422833D01*
G01Y422083D02*
X921717Y422500D01*
X922133Y422750D01*
X922800Y422833D01*
X923383Y422750D01*
X923967Y422333D01*
X924217Y421750D01*
X924300Y421167D01*
X924217Y420583D01*
X923967Y420000D01*
X923467Y419667D01*
X922800Y419500D01*
X922217Y419583D01*
X921633Y419833D01*
X921300Y420167D01*
G01X928400Y419500D02*
Y424500D01*
G01X932583Y422833D02*
Y420500D01*
X932917Y419917D01*
X933417Y419583D01*
X934000Y419500D01*
X934583Y419583D01*
X935083Y419917D01*
X935417Y420500D01*
G01Y419500D02*
Y422833D01*
G01X938433Y418250D02*
X939017Y417917D01*
X939683Y417833D01*
X940267Y417917D01*
X940767Y418333D01*
X941100Y418917D01*
Y422833D01*
G01Y422167D02*
X940767Y422500D01*
X940267Y422750D01*
X939683Y422833D01*
X939017Y422667D01*
X938600Y422333D01*
X938267Y421750D01*
X938100Y421167D01*
X938183Y420667D01*
X938517Y420083D01*
X939017Y419667D01*
X939683Y419500D01*
X940183Y419583D01*
X940767Y419917D01*
X941100Y420250D01*
G01X948717Y422833D02*
X949717Y419500D01*
X950800Y422833D01*
X951883Y419500D01*
X952883Y422833D01*
G01X956400D02*
Y419500D01*
G01Y424167D02*
X956233Y424250D01*
Y424417D01*
X956400Y424500D01*
X956567Y424417D01*
Y424250D01*
X956400Y424167D01*
G01X962000Y424500D02*
Y419500D01*
G01X960833Y422833D02*
X963167D01*
G01X966183Y419500D02*
Y424500D01*
G01Y422083D02*
X966600Y422500D01*
X967017Y422750D01*
X967683Y422833D01*
X968183Y422750D01*
X968767Y422417D01*
X969017Y421917D01*
Y419500D01*
G01X977633D02*
Y422833D01*
G01Y422167D02*
X978050Y422500D01*
X978467Y422750D01*
X979050Y422833D01*
X979467Y422750D01*
X979967Y422500D01*
G01X983150Y421750D02*
X985817D01*
X985567Y422333D01*
X985150Y422667D01*
X984567Y422833D01*
X983983Y422750D01*
X983483Y422500D01*
X983150Y421917D01*
X982983Y421417D01*
Y420917D01*
X983150Y420417D01*
X983567Y419917D01*
X984067Y419583D01*
X984650Y419500D01*
X985233Y419667D01*
X985817Y420167D01*
G01X988750Y420083D02*
X989167Y419750D01*
X989750Y419500D01*
X990250D01*
X990750Y419667D01*
X991083Y419917D01*
X991250Y420250D01*
X991167Y420750D01*
X990833Y421000D01*
X989333Y421500D01*
X989000Y422083D01*
X989167Y422500D01*
X989500Y422750D01*
X990000Y422833D01*
X990500Y422750D01*
X991000Y422500D01*
G01X995600Y422833D02*
Y419500D01*
G01Y424167D02*
X995433Y424250D01*
Y424417D01*
X995600Y424500D01*
X995767Y424417D01*
Y424250D01*
X995600Y424167D01*
G01X999783Y419500D02*
Y422833D01*
G01Y422000D02*
X1000117Y422417D01*
X1000617Y422750D01*
X1001283Y422833D01*
X1001867Y422750D01*
X1002367Y422417D01*
X1002617Y421833D01*
Y419500D01*
G01X819590Y389810D02*
Y394060D01*
X819757Y394477D01*
X820090Y394727D01*
X820590Y394810D01*
X821090Y394643D01*
X821340Y394227D01*
G01X820340Y392810D02*
X818673D01*
G01X825690Y389810D02*
X825190Y389893D01*
X824690Y390227D01*
X824357Y390810D01*
X824190Y391477D01*
X824357Y392143D01*
X824690Y392727D01*
X825190Y393060D01*
X825690Y393143D01*
X826190Y393060D01*
X826690Y392727D01*
X827023Y392143D01*
X827107Y391477D01*
X827023Y390810D01*
X826690Y390227D01*
X826190Y389893D01*
X825690Y389810D01*
G01X831290D02*
Y394810D01*
G01X836890Y389810D02*
Y394810D01*
G01X842490Y389810D02*
X841990Y389893D01*
X841490Y390227D01*
X841157Y390810D01*
X840990Y391477D01*
X841157Y392143D01*
X841490Y392727D01*
X841990Y393060D01*
X842490Y393143D01*
X842990Y393060D01*
X843490Y392727D01*
X843823Y392143D01*
X843907Y391477D01*
X843823Y390810D01*
X843490Y390227D01*
X842990Y389893D01*
X842490Y389810D01*
G01X846007Y393143D02*
X847007Y389810D01*
X848090Y393143D01*
X849173Y389810D01*
X850173Y393143D01*
G01X859790Y392310D02*
X861457D01*
Y390810D01*
X860957Y390310D01*
X860373Y389977D01*
X859540Y389810D01*
X858707Y389977D01*
X858123Y390310D01*
X857623Y390810D01*
X857290Y391393D01*
X857123Y392060D01*
Y392643D01*
X857290Y393143D01*
X857623Y393727D01*
X858123Y394227D01*
X858623Y394560D01*
X859290Y394810D01*
X859873D01*
X860540Y394643D01*
X861040Y394310D01*
G01X863640Y392060D02*
X866307D01*
X866057Y392643D01*
X865640Y392977D01*
X865057Y393143D01*
X864473Y393060D01*
X863973Y392810D01*
X863640Y392227D01*
X863473Y391727D01*
Y391227D01*
X863640Y390727D01*
X864057Y390227D01*
X864557Y389893D01*
X865140Y389810D01*
X865723Y389977D01*
X866307Y390477D01*
G01X869323Y389810D02*
Y393143D01*
G01Y392477D02*
X869740Y392810D01*
X870157Y393060D01*
X870740Y393143D01*
X871157Y393060D01*
X871657Y392810D01*
G01X874590Y389810D02*
Y394810D01*
G01Y392310D02*
X875007Y392810D01*
X875507Y393060D01*
X876007Y393143D01*
X876757Y392977D01*
X877257Y392643D01*
X877590Y392060D01*
Y391393D01*
X877423Y390727D01*
X877090Y390227D01*
X876507Y389893D01*
X876007Y389810D01*
X875507Y389893D01*
X875007Y390143D01*
X874590Y390560D01*
G01X880440Y392060D02*
X883107D01*
X882857Y392643D01*
X882440Y392977D01*
X881857Y393143D01*
X881273Y393060D01*
X880773Y392810D01*
X880440Y392227D01*
X880273Y391727D01*
Y391227D01*
X880440Y390727D01*
X880857Y390227D01*
X881357Y389893D01*
X881940Y389810D01*
X882523Y389977D01*
X883107Y390477D01*
G01X886123Y389810D02*
Y393143D01*
G01Y392477D02*
X886540Y392810D01*
X886957Y393060D01*
X887540Y393143D01*
X887957Y393060D01*
X888457Y392810D01*
G01X899990Y389810D02*
Y393143D01*
G01Y392560D02*
X899657Y392893D01*
X899157Y393060D01*
X898573Y393143D01*
X897990Y392977D01*
X897490Y392643D01*
X897157Y392143D01*
X896990Y391477D01*
X897157Y390810D01*
X897490Y390310D01*
X897990Y389977D01*
X898573Y389810D01*
X899157Y389893D01*
X899657Y390143D01*
X899990Y390477D01*
G01X902673Y389810D02*
Y393143D01*
G01Y392310D02*
X903007Y392727D01*
X903507Y393060D01*
X904173Y393143D01*
X904757Y393060D01*
X905257Y392727D01*
X905507Y392143D01*
Y389810D01*
G01X911190Y394810D02*
Y389810D01*
G01Y390560D02*
X910857Y390143D01*
X910357Y389893D01*
X909773Y389810D01*
X909107Y389977D01*
X908607Y390393D01*
X908273Y390893D01*
X908190Y391477D01*
X908273Y392060D01*
X908607Y392560D01*
X909107Y392977D01*
X909773Y393143D01*
X910357Y393060D01*
X910773Y392893D01*
X911190Y392560D01*
G01X919390Y388143D02*
Y393143D01*
G01Y392393D02*
X919807Y392810D01*
X920223Y393060D01*
X920890Y393143D01*
X921473Y393060D01*
X922057Y392643D01*
X922307Y392060D01*
X922390Y391477D01*
X922307Y390893D01*
X922057Y390310D01*
X921557Y389977D01*
X920890Y389810D01*
X920307Y389893D01*
X919723Y390143D01*
X919390Y390477D01*
G01X926490Y389810D02*
Y394810D01*
G01X930673Y393143D02*
Y390810D01*
X931007Y390227D01*
X931507Y389893D01*
X932090Y389810D01*
X932673Y389893D01*
X933173Y390227D01*
X933507Y390810D01*
G01Y389810D02*
Y393143D01*
G01X936523Y388560D02*
X937107Y388227D01*
X937773Y388143D01*
X938357Y388227D01*
X938857Y388643D01*
X939190Y389227D01*
Y393143D01*
G01Y392477D02*
X938857Y392810D01*
X938357Y393060D01*
X937773Y393143D01*
X937107Y392977D01*
X936690Y392643D01*
X936357Y392060D01*
X936190Y391477D01*
X936273Y390977D01*
X936607Y390393D01*
X937107Y389977D01*
X937773Y389810D01*
X938273Y389893D01*
X938857Y390227D01*
X939190Y390560D01*
G01X946807Y393143D02*
X947807Y389810D01*
X948890Y393143D01*
X949973Y389810D01*
X950973Y393143D01*
G01X954490D02*
Y389810D01*
G01Y394477D02*
X954323Y394560D01*
Y394727D01*
X954490Y394810D01*
X954657Y394727D01*
Y394560D01*
X954490Y394477D01*
G01X960090Y394810D02*
Y389810D01*
G01X958923Y393143D02*
X961257D01*
G01X964273Y389810D02*
Y394810D01*
G01Y392393D02*
X964690Y392810D01*
X965107Y393060D01*
X965773Y393143D01*
X966273Y393060D01*
X966857Y392727D01*
X967107Y392227D01*
Y389810D01*
G01X975723D02*
Y393143D01*
G01Y392477D02*
X976140Y392810D01*
X976557Y393060D01*
X977140Y393143D01*
X977557Y393060D01*
X978057Y392810D01*
G01X981240Y392060D02*
X983907D01*
X983657Y392643D01*
X983240Y392977D01*
X982657Y393143D01*
X982073Y393060D01*
X981573Y392810D01*
X981240Y392227D01*
X981073Y391727D01*
Y391227D01*
X981240Y390727D01*
X981657Y390227D01*
X982157Y389893D01*
X982740Y389810D01*
X983323Y389977D01*
X983907Y390477D01*
G01X986840Y390393D02*
X987257Y390060D01*
X987840Y389810D01*
X988340D01*
X988840Y389977D01*
X989173Y390227D01*
X989340Y390560D01*
X989257Y391060D01*
X988923Y391310D01*
X987423Y391810D01*
X987090Y392393D01*
X987257Y392810D01*
X987590Y393060D01*
X988090Y393143D01*
X988590Y393060D01*
X989090Y392810D01*
G01X993690Y393143D02*
Y389810D01*
G01Y394477D02*
X993523Y394560D01*
Y394727D01*
X993690Y394810D01*
X993857Y394727D01*
Y394560D01*
X993690Y394477D01*
G01X997873Y389810D02*
Y393143D01*
G01Y392310D02*
X998207Y392727D01*
X998707Y393060D01*
X999373Y393143D01*
X999957Y393060D01*
X1000457Y392727D01*
X1000707Y392143D01*
Y389810D01*
G01X812000Y604500D02*
Y366000D01*
G01X823500Y455500D02*
Y458833D01*
G01Y458250D02*
X823167Y458583D01*
X822667Y458750D01*
X822083Y458833D01*
X821500Y458667D01*
X821000Y458333D01*
X820667Y457833D01*
X820500Y457167D01*
X820667Y456500D01*
X821000Y456000D01*
X821500Y455667D01*
X822083Y455500D01*
X822667Y455583D01*
X823167Y455833D01*
X823500Y456167D01*
G01X826183Y455500D02*
Y458833D01*
G01Y458000D02*
X826517Y458417D01*
X827017Y458750D01*
X827683Y458833D01*
X828267Y458750D01*
X828767Y458417D01*
X829017Y457833D01*
Y455500D01*
G01X834700Y460500D02*
Y455500D01*
G01Y456250D02*
X834367Y455833D01*
X833867Y455583D01*
X833283Y455500D01*
X832617Y455667D01*
X832117Y456083D01*
X831783Y456583D01*
X831700Y457167D01*
X831783Y457750D01*
X832117Y458250D01*
X832617Y458667D01*
X833283Y458833D01*
X833867Y458750D01*
X834283Y458583D01*
X834700Y458250D01*
G01X842900Y455500D02*
Y460500D01*
G01Y458000D02*
X843317Y458500D01*
X843817Y458750D01*
X844317Y458833D01*
X845067Y458667D01*
X845567Y458333D01*
X845900Y457750D01*
Y457083D01*
X845733Y456417D01*
X845400Y455917D01*
X844817Y455583D01*
X844317Y455500D01*
X843817Y455583D01*
X843317Y455833D01*
X842900Y456250D01*
G01X850000Y455500D02*
X849500Y455583D01*
X849000Y455917D01*
X848667Y456500D01*
X848500Y457167D01*
X848667Y457833D01*
X849000Y458417D01*
X849500Y458750D01*
X850000Y458833D01*
X850500Y458750D01*
X851000Y458417D01*
X851333Y457833D01*
X851417Y457167D01*
X851333Y456500D01*
X851000Y455917D01*
X850500Y455583D01*
X850000Y455500D01*
G01X855600Y460500D02*
Y455500D01*
G01X854433Y458833D02*
X856767D01*
G01X861200Y460500D02*
Y455500D01*
G01X860033Y458833D02*
X862367D01*
G01X866800Y455500D02*
X866300Y455583D01*
X865800Y455917D01*
X865467Y456500D01*
X865300Y457167D01*
X865467Y457833D01*
X865800Y458417D01*
X866300Y458750D01*
X866800Y458833D01*
X867300Y458750D01*
X867800Y458417D01*
X868133Y457833D01*
X868217Y457167D01*
X868133Y456500D01*
X867800Y455917D01*
X867300Y455583D01*
X866800Y455500D01*
G01X869900D02*
Y458833D01*
G01Y457917D02*
X870150Y458333D01*
X870567Y458667D01*
X871150Y458833D01*
X871733Y458667D01*
X872150Y458333D01*
X872400Y457917D01*
Y455500D01*
G01Y457917D02*
X872650Y458333D01*
X873067Y458667D01*
X873650Y458833D01*
X874233Y458667D01*
X874650Y458333D01*
X874900Y457833D01*
Y455500D01*
G01X882350Y456083D02*
X882767Y455750D01*
X883350Y455500D01*
X883850D01*
X884350Y455667D01*
X884683Y455917D01*
X884850Y456250D01*
X884767Y456750D01*
X884433Y457000D01*
X882933Y457500D01*
X882600Y458083D01*
X882767Y458500D01*
X883100Y458750D01*
X883600Y458833D01*
X884100Y458750D01*
X884600Y458500D01*
G01X889200Y458833D02*
Y455500D01*
G01Y460167D02*
X889033Y460250D01*
Y460417D01*
X889200Y460500D01*
X889367Y460417D01*
Y460250D01*
X889200Y460167D01*
G01X896300Y460500D02*
Y455500D01*
G01Y456250D02*
X895967Y455833D01*
X895467Y455583D01*
X894883Y455500D01*
X894217Y455667D01*
X893717Y456083D01*
X893383Y456583D01*
X893300Y457167D01*
X893383Y457750D01*
X893717Y458250D01*
X894217Y458667D01*
X894883Y458833D01*
X895467Y458750D01*
X895883Y458583D01*
X896300Y458250D01*
G01X899150Y457750D02*
X901817D01*
X901567Y458333D01*
X901150Y458667D01*
X900567Y458833D01*
X899983Y458750D01*
X899483Y458500D01*
X899150Y457917D01*
X898983Y457417D01*
Y456917D01*
X899150Y456417D01*
X899567Y455917D01*
X900067Y455583D01*
X900650Y455500D01*
X901233Y455667D01*
X901817Y456167D01*
G01X819917Y470833D02*
X820917Y467500D01*
X822000Y470833D01*
X823083Y467500D01*
X824083Y470833D01*
G01X827600D02*
Y467500D01*
G01Y472167D02*
X827433Y472250D01*
Y472417D01*
X827600Y472500D01*
X827767Y472417D01*
Y472250D01*
X827600Y472167D01*
G01X833200Y472500D02*
Y467500D01*
G01X832033Y470833D02*
X834367D01*
G01X837383Y467500D02*
Y472500D01*
G01Y470083D02*
X837800Y470500D01*
X838217Y470750D01*
X838883Y470833D01*
X839383Y470750D01*
X839967Y470417D01*
X840217Y469917D01*
Y467500D01*
G01X844400D02*
X843900Y467583D01*
X843400Y467917D01*
X843067Y468500D01*
X842900Y469167D01*
X843067Y469833D01*
X843400Y470417D01*
X843900Y470750D01*
X844400Y470833D01*
X844900Y470750D01*
X845400Y470417D01*
X845733Y469833D01*
X845817Y469167D01*
X845733Y468500D01*
X845400Y467917D01*
X844900Y467583D01*
X844400Y467500D01*
G01X848583Y470833D02*
Y468500D01*
X848917Y467917D01*
X849417Y467583D01*
X850000Y467500D01*
X850583Y467583D01*
X851083Y467917D01*
X851417Y468500D01*
G01Y467500D02*
Y470833D01*
G01X855600Y472500D02*
Y467500D01*
G01X854433Y470833D02*
X856767D01*
G01X865550Y468083D02*
X865967Y467750D01*
X866550Y467500D01*
X867050D01*
X867550Y467667D01*
X867883Y467917D01*
X868050Y468250D01*
X867967Y468750D01*
X867633Y469000D01*
X866133Y469500D01*
X865800Y470083D01*
X865967Y470500D01*
X866300Y470750D01*
X866800Y470833D01*
X867300Y470750D01*
X867800Y470500D01*
G01X872400Y467500D02*
X871900Y467583D01*
X871400Y467917D01*
X871067Y468500D01*
X870900Y469167D01*
X871067Y469833D01*
X871400Y470417D01*
X871900Y470750D01*
X872400Y470833D01*
X872900Y470750D01*
X873400Y470417D01*
X873733Y469833D01*
X873817Y469167D01*
X873733Y468500D01*
X873400Y467917D01*
X872900Y467583D01*
X872400Y467500D01*
G01X878000D02*
Y472500D01*
G01X885100D02*
Y467500D01*
G01Y468250D02*
X884767Y467833D01*
X884267Y467583D01*
X883683Y467500D01*
X883017Y467667D01*
X882517Y468083D01*
X882183Y468583D01*
X882100Y469167D01*
X882183Y469750D01*
X882517Y470250D01*
X883017Y470667D01*
X883683Y470833D01*
X884267Y470750D01*
X884683Y470583D01*
X885100Y470250D01*
G01X887950Y469750D02*
X890617D01*
X890367Y470333D01*
X889950Y470667D01*
X889367Y470833D01*
X888783Y470750D01*
X888283Y470500D01*
X887950Y469917D01*
X887783Y469417D01*
Y468917D01*
X887950Y468417D01*
X888367Y467917D01*
X888867Y467583D01*
X889450Y467500D01*
X890033Y467667D01*
X890617Y468167D01*
G01X893633Y467500D02*
Y470833D01*
G01Y470167D02*
X894050Y470500D01*
X894467Y470750D01*
X895050Y470833D01*
X895467Y470750D01*
X895967Y470500D01*
G01X903500Y467500D02*
Y470833D01*
G01Y469917D02*
X903750Y470333D01*
X904167Y470667D01*
X904750Y470833D01*
X905333Y470667D01*
X905750Y470333D01*
X906000Y469917D01*
Y467500D01*
G01Y469917D02*
X906250Y470333D01*
X906667Y470667D01*
X907250Y470833D01*
X907833Y470667D01*
X908250Y470333D01*
X908500Y469833D01*
Y467500D01*
G01X913100D02*
Y470833D01*
G01Y470250D02*
X912767Y470583D01*
X912267Y470750D01*
X911683Y470833D01*
X911100Y470667D01*
X910600Y470333D01*
X910267Y469833D01*
X910100Y469167D01*
X910267Y468500D01*
X910600Y468000D01*
X911100Y467667D01*
X911683Y467500D01*
X912267Y467583D01*
X912767Y467833D01*
X913100Y468167D01*
G01X915950Y468083D02*
X916367Y467750D01*
X916950Y467500D01*
X917450D01*
X917950Y467667D01*
X918283Y467917D01*
X918450Y468250D01*
X918367Y468750D01*
X918033Y469000D01*
X916533Y469500D01*
X916200Y470083D01*
X916367Y470500D01*
X916700Y470750D01*
X917200Y470833D01*
X917700Y470750D01*
X918200Y470500D01*
G01X921383Y467500D02*
Y472500D01*
G01X924050Y470833D02*
X921383Y468917D01*
G01X922467Y469667D02*
X924217Y467500D01*
G01X932500Y465833D02*
Y470833D01*
G01Y470083D02*
X932917Y470500D01*
X933333Y470750D01*
X934000Y470833D01*
X934583Y470750D01*
X935167Y470333D01*
X935417Y469750D01*
X935500Y469167D01*
X935417Y468583D01*
X935167Y468000D01*
X934667Y467667D01*
X934000Y467500D01*
X933417Y467583D01*
X932833Y467833D01*
X932500Y468167D01*
G01X941100Y467500D02*
Y470833D01*
G01Y470250D02*
X940767Y470583D01*
X940267Y470750D01*
X939683Y470833D01*
X939100Y470667D01*
X938600Y470333D01*
X938267Y469833D01*
X938100Y469167D01*
X938267Y468500D01*
X938600Y468000D01*
X939100Y467667D01*
X939683Y467500D01*
X940267Y467583D01*
X940767Y467833D01*
X941100Y468167D01*
G01X946700Y472500D02*
Y467500D01*
G01Y468250D02*
X946367Y467833D01*
X945867Y467583D01*
X945283Y467500D01*
X944617Y467667D01*
X944117Y468083D01*
X943783Y468583D01*
X943700Y469167D01*
X943783Y469750D01*
X944117Y470250D01*
X944617Y470667D01*
X945283Y470833D01*
X945867Y470750D01*
X946283Y470583D01*
X946700Y470250D01*
G01X956400Y467500D02*
X955900Y467583D01*
X955400Y467917D01*
X955067Y468500D01*
X954900Y469167D01*
X955067Y469833D01*
X955400Y470417D01*
X955900Y470750D01*
X956400Y470833D01*
X956900Y470750D01*
X957400Y470417D01*
X957733Y469833D01*
X957817Y469167D01*
X957733Y468500D01*
X957400Y467917D01*
X956900Y467583D01*
X956400Y467500D01*
G01X960583D02*
Y470833D01*
G01Y470000D02*
X960917Y470417D01*
X961417Y470750D01*
X962083Y470833D01*
X962667Y470750D01*
X963167Y470417D01*
X963417Y469833D01*
Y467500D01*
G01X973200Y472500D02*
Y467500D01*
G01X972033Y470833D02*
X974367D01*
G01X978800Y467500D02*
X978300Y467583D01*
X977800Y467917D01*
X977467Y468500D01*
X977300Y469167D01*
X977467Y469833D01*
X977800Y470417D01*
X978300Y470750D01*
X978800Y470833D01*
X979300Y470750D01*
X979800Y470417D01*
X980133Y469833D01*
X980217Y469167D01*
X980133Y468500D01*
X979800Y467917D01*
X979300Y467583D01*
X978800Y467500D01*
G01X982900Y465833D02*
Y470833D01*
G01Y470083D02*
X983317Y470500D01*
X983733Y470750D01*
X984400Y470833D01*
X984983Y470750D01*
X985567Y470333D01*
X985817Y469750D01*
X985900Y469167D01*
X985817Y468583D01*
X985567Y468000D01*
X985067Y467667D01*
X984400Y467500D01*
X983817Y467583D01*
X983233Y467833D01*
X982900Y468167D01*
G01X821500Y440500D02*
Y444750D01*
X821667Y445167D01*
X822000Y445417D01*
X822500Y445500D01*
X823000Y445333D01*
X823250Y444917D01*
G01X822250Y443500D02*
X820583D01*
G01X827600Y440500D02*
X827100Y440583D01*
X826600Y440917D01*
X826267Y441500D01*
X826100Y442167D01*
X826267Y442833D01*
X826600Y443417D01*
X827100Y443750D01*
X827600Y443833D01*
X828100Y443750D01*
X828600Y443417D01*
X828933Y442833D01*
X829017Y442167D01*
X828933Y441500D01*
X828600Y440917D01*
X828100Y440583D01*
X827600Y440500D01*
G01X833200D02*
Y445500D01*
G01X838800Y440500D02*
Y445500D01*
G01X844400Y440500D02*
X843900Y440583D01*
X843400Y440917D01*
X843067Y441500D01*
X842900Y442167D01*
X843067Y442833D01*
X843400Y443417D01*
X843900Y443750D01*
X844400Y443833D01*
X844900Y443750D01*
X845400Y443417D01*
X845733Y442833D01*
X845817Y442167D01*
X845733Y441500D01*
X845400Y440917D01*
X844900Y440583D01*
X844400Y440500D01*
G01X847917Y443833D02*
X848917Y440500D01*
X850000Y443833D01*
X851083Y440500D01*
X852083Y443833D01*
G01X861700Y443000D02*
X863367D01*
Y441500D01*
X862867Y441000D01*
X862283Y440667D01*
X861450Y440500D01*
X860617Y440667D01*
X860033Y441000D01*
X859533Y441500D01*
X859200Y442083D01*
X859033Y442750D01*
Y443333D01*
X859200Y443833D01*
X859533Y444417D01*
X860033Y444917D01*
X860533Y445250D01*
X861200Y445500D01*
X861783D01*
X862450Y445333D01*
X862950Y445000D01*
G01X865550Y442750D02*
X868217D01*
X867967Y443333D01*
X867550Y443667D01*
X866967Y443833D01*
X866383Y443750D01*
X865883Y443500D01*
X865550Y442917D01*
X865383Y442417D01*
Y441917D01*
X865550Y441417D01*
X865967Y440917D01*
X866467Y440583D01*
X867050Y440500D01*
X867633Y440667D01*
X868217Y441167D01*
G01X871233Y440500D02*
Y443833D01*
G01Y443167D02*
X871650Y443500D01*
X872067Y443750D01*
X872650Y443833D01*
X873067Y443750D01*
X873567Y443500D01*
G01X876500Y440500D02*
Y445500D01*
G01Y443000D02*
X876917Y443500D01*
X877417Y443750D01*
X877917Y443833D01*
X878667Y443667D01*
X879167Y443333D01*
X879500Y442750D01*
Y442083D01*
X879333Y441417D01*
X879000Y440917D01*
X878417Y440583D01*
X877917Y440500D01*
X877417Y440583D01*
X876917Y440833D01*
X876500Y441250D01*
G01X882350Y442750D02*
X885017D01*
X884767Y443333D01*
X884350Y443667D01*
X883767Y443833D01*
X883183Y443750D01*
X882683Y443500D01*
X882350Y442917D01*
X882183Y442417D01*
Y441917D01*
X882350Y441417D01*
X882767Y440917D01*
X883267Y440583D01*
X883850Y440500D01*
X884433Y440667D01*
X885017Y441167D01*
G01X888033Y440500D02*
Y443833D01*
G01Y443167D02*
X888450Y443500D01*
X888867Y443750D01*
X889450Y443833D01*
X889867Y443750D01*
X890367Y443500D01*
G01X829750Y542583D02*
X830167Y542250D01*
X830750Y542000D01*
X831250D01*
X831750Y542167D01*
X832083Y542417D01*
X832250Y542750D01*
X832167Y543250D01*
X831833Y543500D01*
X830333Y544000D01*
X830000Y544583D01*
X830167Y545000D01*
X830500Y545250D01*
X831000Y545333D01*
X831500Y545250D01*
X832000Y545000D01*
G01X836600Y542000D02*
X836100Y542083D01*
X835600Y542417D01*
X835267Y543000D01*
X835100Y543667D01*
X835267Y544333D01*
X835600Y544917D01*
X836100Y545250D01*
X836600Y545333D01*
X837100Y545250D01*
X837600Y544917D01*
X837933Y544333D01*
X838017Y543667D01*
X837933Y543000D01*
X837600Y542417D01*
X837100Y542083D01*
X836600Y542000D01*
G01X842200D02*
Y547000D01*
G01X849300D02*
Y542000D01*
G01Y542750D02*
X848967Y542333D01*
X848467Y542083D01*
X847883Y542000D01*
X847217Y542167D01*
X846717Y542583D01*
X846383Y543083D01*
X846300Y543667D01*
X846383Y544250D01*
X846717Y544750D01*
X847217Y545167D01*
X847883Y545333D01*
X848467Y545250D01*
X848883Y545083D01*
X849300Y544750D01*
G01X852150Y544250D02*
X854817D01*
X854567Y544833D01*
X854150Y545167D01*
X853567Y545333D01*
X852983Y545250D01*
X852483Y545000D01*
X852150Y544417D01*
X851983Y543917D01*
Y543417D01*
X852150Y542917D01*
X852567Y542417D01*
X853067Y542083D01*
X853650Y542000D01*
X854233Y542167D01*
X854817Y542667D01*
G01X857833Y542000D02*
Y545333D01*
G01Y544667D02*
X858250Y545000D01*
X858667Y545250D01*
X859250Y545333D01*
X859667Y545250D01*
X860167Y545000D01*
G01X867700Y542000D02*
Y545333D01*
G01Y544417D02*
X867950Y544833D01*
X868367Y545167D01*
X868950Y545333D01*
X869533Y545167D01*
X869950Y544833D01*
X870200Y544417D01*
Y542000D01*
G01Y544417D02*
X870450Y544833D01*
X870867Y545167D01*
X871450Y545333D01*
X872033Y545167D01*
X872450Y544833D01*
X872700Y544333D01*
Y542000D01*
G01X877300D02*
Y545333D01*
G01Y544750D02*
X876967Y545083D01*
X876467Y545250D01*
X875883Y545333D01*
X875300Y545167D01*
X874800Y544833D01*
X874467Y544333D01*
X874300Y543667D01*
X874467Y543000D01*
X874800Y542500D01*
X875300Y542167D01*
X875883Y542000D01*
X876467Y542083D01*
X876967Y542333D01*
X877300Y542667D01*
G01X880150Y542583D02*
X880567Y542250D01*
X881150Y542000D01*
X881650D01*
X882150Y542167D01*
X882483Y542417D01*
X882650Y542750D01*
X882567Y543250D01*
X882233Y543500D01*
X880733Y544000D01*
X880400Y544583D01*
X880567Y545000D01*
X880900Y545250D01*
X881400Y545333D01*
X881900Y545250D01*
X882400Y545000D01*
G01X885583Y542000D02*
Y547000D01*
G01X888250Y545333D02*
X885583Y543417D01*
G01X886667Y544167D02*
X888417Y542000D01*
G01X896700Y540333D02*
Y545333D01*
G01Y544583D02*
X897117Y545000D01*
X897533Y545250D01*
X898200Y545333D01*
X898783Y545250D01*
X899367Y544833D01*
X899617Y544250D01*
X899700Y543667D01*
X899617Y543083D01*
X899367Y542500D01*
X898867Y542167D01*
X898200Y542000D01*
X897617Y542083D01*
X897033Y542333D01*
X896700Y542667D01*
G01X905300Y542000D02*
Y545333D01*
G01Y544750D02*
X904967Y545083D01*
X904467Y545250D01*
X903883Y545333D01*
X903300Y545167D01*
X902800Y544833D01*
X902467Y544333D01*
X902300Y543667D01*
X902467Y543000D01*
X902800Y542500D01*
X903300Y542167D01*
X903883Y542000D01*
X904467Y542083D01*
X904967Y542333D01*
X905300Y542667D01*
G01X910900Y547000D02*
Y542000D01*
G01Y542750D02*
X910567Y542333D01*
X910067Y542083D01*
X909483Y542000D01*
X908817Y542167D01*
X908317Y542583D01*
X907983Y543083D01*
X907900Y543667D01*
X907983Y544250D01*
X908317Y544750D01*
X908817Y545167D01*
X909483Y545333D01*
X910067Y545250D01*
X910483Y545083D01*
X910900Y544750D01*
G01X829917Y563333D02*
X830917Y560000D01*
X832000Y563333D01*
X833083Y560000D01*
X834083Y563333D01*
G01X836183Y560000D02*
Y565000D01*
G01Y562583D02*
X836600Y563000D01*
X837017Y563250D01*
X837683Y563333D01*
X838183Y563250D01*
X838767Y562917D01*
X839017Y562417D01*
Y560000D01*
G01X843200Y563333D02*
Y560000D01*
G01Y564667D02*
X843033Y564750D01*
Y564917D01*
X843200Y565000D01*
X843367Y564917D01*
Y564750D01*
X843200Y564667D01*
G01X850133Y562917D02*
X849550Y563250D01*
X849050Y563333D01*
X848383Y563167D01*
X847883Y562833D01*
X847550Y562250D01*
X847467Y561667D01*
X847550Y561083D01*
X847883Y560583D01*
X848383Y560167D01*
X849050Y560000D01*
X849633Y560167D01*
X850133Y560500D01*
G01X852983Y560000D02*
Y565000D01*
G01Y562583D02*
X853400Y563000D01*
X853817Y563250D01*
X854483Y563333D01*
X854983Y563250D01*
X855567Y562917D01*
X855817Y562417D01*
Y560000D01*
G01X864350Y560583D02*
X864767Y560250D01*
X865350Y560000D01*
X865850D01*
X866350Y560167D01*
X866683Y560417D01*
X866850Y560750D01*
X866767Y561250D01*
X866433Y561500D01*
X864933Y562000D01*
X864600Y562583D01*
X864767Y563000D01*
X865100Y563250D01*
X865600Y563333D01*
X866100Y563250D01*
X866600Y563000D01*
G01X871200Y563333D02*
Y560000D01*
G01Y564667D02*
X871033Y564750D01*
Y564917D01*
X871200Y565000D01*
X871367Y564917D01*
Y564750D01*
X871200Y564667D01*
G01X875550Y563333D02*
X878050D01*
X875550Y560000D01*
X878050D01*
G01X881150Y562250D02*
X883817D01*
X883567Y562833D01*
X883150Y563167D01*
X882567Y563333D01*
X881983Y563250D01*
X881483Y563000D01*
X881150Y562417D01*
X880983Y561917D01*
Y561417D01*
X881150Y560917D01*
X881567Y560417D01*
X882067Y560083D01*
X882650Y560000D01*
X883233Y560167D01*
X883817Y560667D01*
G01X893600Y563333D02*
Y560000D01*
G01Y564667D02*
X893433Y564750D01*
Y564917D01*
X893600Y565000D01*
X893767Y564917D01*
Y564750D01*
X893600Y564667D01*
G01X897950Y560583D02*
X898367Y560250D01*
X898950Y560000D01*
X899450D01*
X899950Y560167D01*
X900283Y560417D01*
X900450Y560750D01*
X900367Y561250D01*
X900033Y561500D01*
X898533Y562000D01*
X898200Y562583D01*
X898367Y563000D01*
X898700Y563250D01*
X899200Y563333D01*
X899700Y563250D01*
X900200Y563000D01*
G01X908900Y560000D02*
Y565000D01*
G01Y562500D02*
X909317Y563000D01*
X909817Y563250D01*
X910317Y563333D01*
X911067Y563167D01*
X911567Y562833D01*
X911900Y562250D01*
Y561583D01*
X911733Y560917D01*
X911400Y560417D01*
X910817Y560083D01*
X910317Y560000D01*
X909817Y560083D01*
X909317Y560333D01*
X908900Y560750D01*
G01X916000Y563333D02*
Y560000D01*
G01Y564667D02*
X915833Y564750D01*
Y564917D01*
X916000Y565000D01*
X916167Y564917D01*
Y564750D01*
X916000Y564667D01*
G01X920433Y558750D02*
X921017Y558417D01*
X921683Y558333D01*
X922267Y558417D01*
X922767Y558833D01*
X923100Y559417D01*
Y563333D01*
G01Y562667D02*
X922767Y563000D01*
X922267Y563250D01*
X921683Y563333D01*
X921017Y563167D01*
X920600Y562833D01*
X920267Y562250D01*
X920100Y561667D01*
X920183Y561167D01*
X920517Y560583D01*
X921017Y560167D01*
X921683Y560000D01*
X922183Y560083D01*
X922767Y560417D01*
X923100Y560750D01*
G01X926033Y558750D02*
X926617Y558417D01*
X927283Y558333D01*
X927867Y558417D01*
X928367Y558833D01*
X928700Y559417D01*
Y563333D01*
G01Y562667D02*
X928367Y563000D01*
X927867Y563250D01*
X927283Y563333D01*
X926617Y563167D01*
X926200Y562833D01*
X925867Y562250D01*
X925700Y561667D01*
X925783Y561167D01*
X926117Y560583D01*
X926617Y560167D01*
X927283Y560000D01*
X927783Y560083D01*
X928367Y560417D01*
X928700Y560750D01*
G01X931550Y562250D02*
X934217D01*
X933967Y562833D01*
X933550Y563167D01*
X932967Y563333D01*
X932383Y563250D01*
X931883Y563000D01*
X931550Y562417D01*
X931383Y561917D01*
Y561417D01*
X931550Y560917D01*
X931967Y560417D01*
X932467Y560083D01*
X933050Y560000D01*
X933633Y560167D01*
X934217Y560667D01*
G01X937233Y560000D02*
Y563333D01*
G01Y562667D02*
X937650Y563000D01*
X938067Y563250D01*
X938650Y563333D01*
X939067Y563250D01*
X939567Y563000D01*
G01X949600Y565000D02*
Y560000D01*
G01X948433Y563333D02*
X950767D01*
G01X953783Y560000D02*
Y565000D01*
G01Y562583D02*
X954200Y563000D01*
X954617Y563250D01*
X955283Y563333D01*
X955783Y563250D01*
X956367Y562917D01*
X956617Y562417D01*
Y560000D01*
G01X962300D02*
Y563333D01*
G01Y562750D02*
X961967Y563083D01*
X961467Y563250D01*
X960883Y563333D01*
X960300Y563167D01*
X959800Y562833D01*
X959467Y562333D01*
X959300Y561667D01*
X959467Y561000D01*
X959800Y560500D01*
X960300Y560167D01*
X960883Y560000D01*
X961467Y560083D01*
X961967Y560333D01*
X962300Y560667D01*
G01X964983Y560000D02*
Y563333D01*
G01Y562500D02*
X965317Y562917D01*
X965817Y563250D01*
X966483Y563333D01*
X967067Y563250D01*
X967567Y562917D01*
X967817Y562333D01*
Y560000D01*
G01X979100D02*
Y563333D01*
G01Y562750D02*
X978767Y563083D01*
X978267Y563250D01*
X977683Y563333D01*
X977100Y563167D01*
X976600Y562833D01*
X976267Y562333D01*
X976100Y561667D01*
X976267Y561000D01*
X976600Y560500D01*
X977100Y560167D01*
X977683Y560000D01*
X978267Y560083D01*
X978767Y560333D01*
X979100Y560667D01*
G01X981783Y560000D02*
Y563333D01*
G01Y562500D02*
X982117Y562917D01*
X982617Y563250D01*
X983283Y563333D01*
X983867Y563250D01*
X984367Y562917D01*
X984617Y562333D01*
Y560000D01*
G01X987383D02*
Y563333D01*
G01Y562500D02*
X987717Y562917D01*
X988217Y563250D01*
X988883Y563333D01*
X989467Y563250D01*
X989967Y562917D01*
X990217Y562333D01*
Y560000D01*
G01X992983Y563333D02*
Y561000D01*
X993317Y560417D01*
X993817Y560083D01*
X994400Y560000D01*
X994983Y560083D01*
X995483Y560417D01*
X995817Y561000D01*
G01Y560000D02*
Y563333D01*
G01X1001500Y560000D02*
Y563333D01*
G01Y562750D02*
X1001167Y563083D01*
X1000667Y563250D01*
X1000083Y563333D01*
X999500Y563167D01*
X999000Y562833D01*
X998667Y562333D01*
X998500Y561667D01*
X998667Y561000D01*
X999000Y560500D01*
X999500Y560167D01*
X1000083Y560000D01*
X1000667Y560083D01*
X1001167Y560333D01*
X1001500Y560667D01*
G01X1005600Y560000D02*
Y565000D01*
G01X831333Y551000D02*
Y554333D01*
G01Y553667D02*
X831750Y554000D01*
X832167Y554250D01*
X832750Y554333D01*
X833167Y554250D01*
X833667Y554000D01*
G01X838100Y554333D02*
Y551000D01*
G01Y555667D02*
X837933Y555750D01*
Y555917D01*
X838100Y556000D01*
X838267Y555917D01*
Y555750D01*
X838100Y555667D01*
G01X842283Y551000D02*
Y554333D01*
G01Y553500D02*
X842617Y553917D01*
X843117Y554250D01*
X843783Y554333D01*
X844367Y554250D01*
X844867Y553917D01*
X845117Y553333D01*
Y551000D01*
G01X848133Y549750D02*
X848717Y549417D01*
X849383Y549333D01*
X849967Y549417D01*
X850467Y549833D01*
X850800Y550417D01*
Y554333D01*
G01Y553667D02*
X850467Y554000D01*
X849967Y554250D01*
X849383Y554333D01*
X848717Y554167D01*
X848300Y553833D01*
X847967Y553250D01*
X847800Y552667D01*
X847883Y552167D01*
X848217Y551583D01*
X848717Y551167D01*
X849383Y551000D01*
X849883Y551083D01*
X850467Y551417D01*
X850800Y551750D01*
G01X859250Y551583D02*
X859667Y551250D01*
X860250Y551000D01*
X860750D01*
X861250Y551167D01*
X861583Y551417D01*
X861750Y551750D01*
X861667Y552250D01*
X861333Y552500D01*
X859833Y553000D01*
X859500Y553583D01*
X859667Y554000D01*
X860000Y554250D01*
X860500Y554333D01*
X861000Y554250D01*
X861500Y554000D01*
G01X866100Y554333D02*
Y551000D01*
G01Y555667D02*
X865933Y555750D01*
Y555917D01*
X866100Y556000D01*
X866267Y555917D01*
Y555750D01*
X866100Y555667D01*
G01X870450Y554333D02*
X872950D01*
X870450Y551000D01*
X872950D01*
G01X876050Y553250D02*
X878717D01*
X878467Y553833D01*
X878050Y554167D01*
X877467Y554333D01*
X876883Y554250D01*
X876383Y554000D01*
X876050Y553417D01*
X875883Y552917D01*
Y552417D01*
X876050Y551917D01*
X876467Y551417D01*
X876967Y551083D01*
X877550Y551000D01*
X878133Y551167D01*
X878717Y551667D01*
G01X888333Y550083D02*
X888667Y551167D01*
G01X822000Y569000D02*
Y574000D01*
X821000Y573000D01*
G01Y569000D02*
X823000D01*
G01X827600Y568833D02*
X827433Y568917D01*
Y569083D01*
X827600Y569167D01*
X827767Y569083D01*
Y568917D01*
X827600Y568833D01*
G01X833200Y569000D02*
X832533Y569083D01*
X831950Y569417D01*
X831450Y569917D01*
X831117Y570500D01*
X830950Y571167D01*
Y571833D01*
X831117Y572500D01*
X831450Y573083D01*
X831950Y573583D01*
X832533Y573917D01*
X833200Y574000D01*
X833867Y573917D01*
X834450Y573583D01*
X834950Y573083D01*
X835283Y572500D01*
X835450Y571833D01*
Y571167D01*
X835283Y570500D01*
X834950Y569917D01*
X834450Y569417D01*
X833867Y569083D01*
X833200Y569000D01*
G01X837383D02*
Y572333D01*
G01Y571500D02*
X837717Y571917D01*
X838217Y572250D01*
X838883Y572333D01*
X839467Y572250D01*
X839967Y571917D01*
X840217Y571333D01*
Y569000D01*
G01X843150Y571250D02*
X845817D01*
X845567Y571833D01*
X845150Y572167D01*
X844567Y572333D01*
X843983Y572250D01*
X843483Y572000D01*
X843150Y571417D01*
X842983Y570917D01*
Y570417D01*
X843150Y569917D01*
X843567Y569417D01*
X844067Y569083D01*
X844650Y569000D01*
X845233Y569167D01*
X845817Y569667D01*
G01X854350Y569583D02*
X854767Y569250D01*
X855350Y569000D01*
X855850D01*
X856350Y569167D01*
X856683Y569417D01*
X856850Y569750D01*
X856767Y570250D01*
X856433Y570500D01*
X854933Y571000D01*
X854600Y571583D01*
X854767Y572000D01*
X855100Y572250D01*
X855600Y572333D01*
X856100Y572250D01*
X856600Y572000D01*
G01X861200Y572333D02*
Y569000D01*
G01Y573667D02*
X861033Y573750D01*
Y573917D01*
X861200Y574000D01*
X861367Y573917D01*
Y573750D01*
X861200Y573667D01*
G01X868300Y574000D02*
Y569000D01*
G01Y569750D02*
X867967Y569333D01*
X867467Y569083D01*
X866883Y569000D01*
X866217Y569167D01*
X865717Y569583D01*
X865383Y570083D01*
X865300Y570667D01*
X865383Y571250D01*
X865717Y571750D01*
X866217Y572167D01*
X866883Y572333D01*
X867467Y572250D01*
X867883Y572083D01*
X868300Y571750D01*
G01X871150Y571250D02*
X873817D01*
X873567Y571833D01*
X873150Y572167D01*
X872567Y572333D01*
X871983Y572250D01*
X871483Y572000D01*
X871150Y571417D01*
X870983Y570917D01*
Y570417D01*
X871150Y569917D01*
X871567Y569417D01*
X872067Y569083D01*
X872650Y569000D01*
X873233Y569167D01*
X873817Y569667D01*
G01X881517Y572333D02*
X882517Y569000D01*
X883600Y572333D01*
X884683Y569000D01*
X885683Y572333D01*
G01X889200D02*
Y569000D01*
G01Y573667D02*
X889033Y573750D01*
Y573917D01*
X889200Y574000D01*
X889367Y573917D01*
Y573750D01*
X889200Y573667D01*
G01X894800Y574000D02*
Y569000D01*
G01X893633Y572333D02*
X895967D01*
G01X898983Y569000D02*
Y574000D01*
G01Y571583D02*
X899400Y572000D01*
X899817Y572250D01*
X900483Y572333D01*
X900983Y572250D01*
X901567Y571917D01*
X901817Y571417D01*
Y569000D01*
G01X910350Y569583D02*
X910767Y569250D01*
X911350Y569000D01*
X911850D01*
X912350Y569167D01*
X912683Y569417D01*
X912850Y569750D01*
X912767Y570250D01*
X912433Y570500D01*
X910933Y571000D01*
X910600Y571583D01*
X910767Y572000D01*
X911100Y572250D01*
X911600Y572333D01*
X912100Y572250D01*
X912600Y572000D01*
G01X917200Y569000D02*
X916700Y569083D01*
X916200Y569417D01*
X915867Y570000D01*
X915700Y570667D01*
X915867Y571333D01*
X916200Y571917D01*
X916700Y572250D01*
X917200Y572333D01*
X917700Y572250D01*
X918200Y571917D01*
X918533Y571333D01*
X918617Y570667D01*
X918533Y570000D01*
X918200Y569417D01*
X917700Y569083D01*
X917200Y569000D01*
G01X922800D02*
Y574000D01*
G01X929900D02*
Y569000D01*
G01Y569750D02*
X929567Y569333D01*
X929067Y569083D01*
X928483Y569000D01*
X927817Y569167D01*
X927317Y569583D01*
X926983Y570083D01*
X926900Y570667D01*
X926983Y571250D01*
X927317Y571750D01*
X927817Y572167D01*
X928483Y572333D01*
X929067Y572250D01*
X929483Y572083D01*
X929900Y571750D01*
G01X932750Y571250D02*
X935417D01*
X935167Y571833D01*
X934750Y572167D01*
X934167Y572333D01*
X933583Y572250D01*
X933083Y572000D01*
X932750Y571417D01*
X932583Y570917D01*
Y570417D01*
X932750Y569917D01*
X933167Y569417D01*
X933667Y569083D01*
X934250Y569000D01*
X934833Y569167D01*
X935417Y569667D01*
G01X938433Y569000D02*
Y572333D01*
G01Y571667D02*
X938850Y572000D01*
X939267Y572250D01*
X939850Y572333D01*
X940267Y572250D01*
X940767Y572000D01*
G01X948300Y569000D02*
Y572333D01*
G01Y571417D02*
X948550Y571833D01*
X948967Y572167D01*
X949550Y572333D01*
X950133Y572167D01*
X950550Y571833D01*
X950800Y571417D01*
Y569000D01*
G01Y571417D02*
X951050Y571833D01*
X951467Y572167D01*
X952050Y572333D01*
X952633Y572167D01*
X953050Y571833D01*
X953300Y571333D01*
Y569000D01*
G01X957900D02*
Y572333D01*
G01Y571750D02*
X957567Y572083D01*
X957067Y572250D01*
X956483Y572333D01*
X955900Y572167D01*
X955400Y571833D01*
X955067Y571333D01*
X954900Y570667D01*
X955067Y570000D01*
X955400Y569500D01*
X955900Y569167D01*
X956483Y569000D01*
X957067Y569083D01*
X957567Y569333D01*
X957900Y569667D01*
G01X960750Y569583D02*
X961167Y569250D01*
X961750Y569000D01*
X962250D01*
X962750Y569167D01*
X963083Y569417D01*
X963250Y569750D01*
X963167Y570250D01*
X962833Y570500D01*
X961333Y571000D01*
X961000Y571583D01*
X961167Y572000D01*
X961500Y572250D01*
X962000Y572333D01*
X962500Y572250D01*
X963000Y572000D01*
G01X966183Y569000D02*
Y574000D01*
G01X968850Y572333D02*
X966183Y570417D01*
G01X967267Y571167D02*
X969017Y569000D01*
G01X977300Y567333D02*
Y572333D01*
G01Y571583D02*
X977717Y572000D01*
X978133Y572250D01*
X978800Y572333D01*
X979383Y572250D01*
X979967Y571833D01*
X980217Y571250D01*
X980300Y570667D01*
X980217Y570083D01*
X979967Y569500D01*
X979467Y569167D01*
X978800Y569000D01*
X978217Y569083D01*
X977633Y569333D01*
X977300Y569667D01*
G01X985900Y569000D02*
Y572333D01*
G01Y571750D02*
X985567Y572083D01*
X985067Y572250D01*
X984483Y572333D01*
X983900Y572167D01*
X983400Y571833D01*
X983067Y571333D01*
X982900Y570667D01*
X983067Y570000D01*
X983400Y569500D01*
X983900Y569167D01*
X984483Y569000D01*
X985067Y569083D01*
X985567Y569333D01*
X985900Y569667D01*
G01X991500Y574000D02*
Y569000D01*
G01Y569750D02*
X991167Y569333D01*
X990667Y569083D01*
X990083Y569000D01*
X989417Y569167D01*
X988917Y569583D01*
X988583Y570083D01*
X988500Y570667D01*
X988583Y571250D01*
X988917Y571750D01*
X989417Y572167D01*
X990083Y572333D01*
X990667Y572250D01*
X991083Y572083D01*
X991500Y571750D01*
G01X794500Y674500D02*
Y669500D01*
G01X793333Y672833D02*
X795667D01*
G01X798683Y669500D02*
Y674500D01*
G01Y672083D02*
X799100Y672500D01*
X799517Y672750D01*
X800183Y672833D01*
X800683Y672750D01*
X801267Y672417D01*
X801517Y671917D01*
Y669500D01*
G01X805700Y672833D02*
Y669500D01*
G01Y674167D02*
X805533Y674250D01*
Y674417D01*
X805700Y674500D01*
X805867Y674417D01*
Y674250D01*
X805700Y674167D01*
G01X812633Y672417D02*
X812050Y672750D01*
X811550Y672833D01*
X810883Y672667D01*
X810383Y672333D01*
X810050Y671750D01*
X809967Y671167D01*
X810050Y670583D01*
X810383Y670083D01*
X810883Y669667D01*
X811550Y669500D01*
X812133Y669667D01*
X812633Y670000D01*
G01X815483Y669500D02*
Y674500D01*
G01X818150Y672833D02*
X815483Y670917D01*
G01X816567Y671667D02*
X818317Y669500D01*
G01X821083D02*
Y672833D01*
G01Y672000D02*
X821417Y672417D01*
X821917Y672750D01*
X822583Y672833D01*
X823167Y672750D01*
X823667Y672417D01*
X823917Y671833D01*
Y669500D01*
G01X826850Y671750D02*
X829517D01*
X829267Y672333D01*
X828850Y672667D01*
X828267Y672833D01*
X827683Y672750D01*
X827183Y672500D01*
X826850Y671917D01*
X826683Y671417D01*
Y670917D01*
X826850Y670417D01*
X827267Y669917D01*
X827767Y669583D01*
X828350Y669500D01*
X828933Y669667D01*
X829517Y670167D01*
G01X832450Y670083D02*
X832867Y669750D01*
X833450Y669500D01*
X833950D01*
X834450Y669667D01*
X834783Y669917D01*
X834950Y670250D01*
X834867Y670750D01*
X834533Y671000D01*
X833033Y671500D01*
X832700Y672083D01*
X832867Y672500D01*
X833200Y672750D01*
X833700Y672833D01*
X834200Y672750D01*
X834700Y672500D01*
G01X838050Y670083D02*
X838467Y669750D01*
X839050Y669500D01*
X839550D01*
X840050Y669667D01*
X840383Y669917D01*
X840550Y670250D01*
X840467Y670750D01*
X840133Y671000D01*
X838633Y671500D01*
X838300Y672083D01*
X838467Y672500D01*
X838800Y672750D01*
X839300Y672833D01*
X839800Y672750D01*
X840300Y672500D01*
G01X809000Y686500D02*
Y691500D01*
G01Y689000D02*
X809417Y689500D01*
X809917Y689750D01*
X810417Y689833D01*
X811167Y689667D01*
X811667Y689333D01*
X812000Y688750D01*
Y688083D01*
X811833Y687417D01*
X811500Y686917D01*
X810917Y686583D01*
X810417Y686500D01*
X809917Y686583D01*
X809417Y686833D01*
X809000Y687250D01*
G01X816100Y686500D02*
X815600Y686583D01*
X815100Y686917D01*
X814767Y687500D01*
X814600Y688167D01*
X814767Y688833D01*
X815100Y689417D01*
X815600Y689750D01*
X816100Y689833D01*
X816600Y689750D01*
X817100Y689417D01*
X817433Y688833D01*
X817517Y688167D01*
X817433Y687500D01*
X817100Y686917D01*
X816600Y686583D01*
X816100Y686500D01*
G01X823200D02*
Y689833D01*
G01Y689250D02*
X822867Y689583D01*
X822367Y689750D01*
X821783Y689833D01*
X821200Y689667D01*
X820700Y689333D01*
X820367Y688833D01*
X820200Y688167D01*
X820367Y687500D01*
X820700Y687000D01*
X821200Y686667D01*
X821783Y686500D01*
X822367Y686583D01*
X822867Y686833D01*
X823200Y687167D01*
G01X826133Y686500D02*
Y689833D01*
G01Y689167D02*
X826550Y689500D01*
X826967Y689750D01*
X827550Y689833D01*
X827967Y689750D01*
X828467Y689500D01*
G01X834400Y691500D02*
Y686500D01*
G01Y687250D02*
X834067Y686833D01*
X833567Y686583D01*
X832983Y686500D01*
X832317Y686667D01*
X831817Y687083D01*
X831483Y687583D01*
X831400Y688167D01*
X831483Y688750D01*
X831817Y689250D01*
X832317Y689667D01*
X832983Y689833D01*
X833567Y689750D01*
X833983Y689583D01*
X834400Y689250D01*
G01X843083Y734500D02*
Y739500D01*
G01Y737083D02*
X843500Y737500D01*
X843917Y737750D01*
X844583Y737833D01*
X845083Y737750D01*
X845667Y737417D01*
X845917Y736917D01*
Y734500D01*
G01X851600D02*
Y737833D01*
G01Y737250D02*
X851267Y737583D01*
X850767Y737750D01*
X850183Y737833D01*
X849600Y737667D01*
X849100Y737333D01*
X848767Y736833D01*
X848600Y736167D01*
X848767Y735500D01*
X849100Y735000D01*
X849600Y734667D01*
X850183Y734500D01*
X850767Y734583D01*
X851267Y734833D01*
X851600Y735167D01*
G01X855700Y734500D02*
Y739500D01*
G01X860800Y734500D02*
Y738750D01*
X860967Y739167D01*
X861300Y739417D01*
X861800Y739500D01*
X862300Y739333D01*
X862550Y738917D01*
G01X861550Y737500D02*
X859883D01*
G01X871000Y732833D02*
Y737833D01*
G01Y737083D02*
X871417Y737500D01*
X871833Y737750D01*
X872500Y737833D01*
X873083Y737750D01*
X873667Y737333D01*
X873917Y736750D01*
X874000Y736167D01*
X873917Y735583D01*
X873667Y735000D01*
X873167Y734667D01*
X872500Y734500D01*
X871917Y734583D01*
X871333Y734833D01*
X871000Y735167D01*
G01X878100Y734500D02*
Y739500D01*
G01X882283Y737833D02*
Y735500D01*
X882617Y734917D01*
X883117Y734583D01*
X883700Y734500D01*
X884283Y734583D01*
X884783Y734917D01*
X885117Y735500D01*
G01Y734500D02*
Y737833D01*
G01X888133Y733250D02*
X888717Y732917D01*
X889383Y732833D01*
X889967Y732917D01*
X890467Y733333D01*
X890800Y733917D01*
Y737833D01*
G01Y737167D02*
X890467Y737500D01*
X889967Y737750D01*
X889383Y737833D01*
X888717Y737667D01*
X888300Y737333D01*
X887967Y736750D01*
X887800Y736167D01*
X887883Y735667D01*
X888217Y735083D01*
X888717Y734667D01*
X889383Y734500D01*
X889883Y734583D01*
X890467Y734917D01*
X890800Y735250D01*
G01X893733Y733250D02*
X894317Y732917D01*
X894983Y732833D01*
X895567Y732917D01*
X896067Y733333D01*
X896400Y733917D01*
Y737833D01*
G01Y737167D02*
X896067Y737500D01*
X895567Y737750D01*
X894983Y737833D01*
X894317Y737667D01*
X893900Y737333D01*
X893567Y736750D01*
X893400Y736167D01*
X893483Y735667D01*
X893817Y735083D01*
X894317Y734667D01*
X894983Y734500D01*
X895483Y734583D01*
X896067Y734917D01*
X896400Y735250D01*
G01X900500Y737833D02*
Y734500D01*
G01Y739167D02*
X900333Y739250D01*
Y739417D01*
X900500Y739500D01*
X900667Y739417D01*
Y739250D01*
X900500Y739167D01*
G01X904683Y734500D02*
Y737833D01*
G01Y737000D02*
X905017Y737417D01*
X905517Y737750D01*
X906183Y737833D01*
X906767Y737750D01*
X907267Y737417D01*
X907517Y736833D01*
Y734500D01*
G01X910533Y733250D02*
X911117Y732917D01*
X911783Y732833D01*
X912367Y732917D01*
X912867Y733333D01*
X913200Y733917D01*
Y737833D01*
G01Y737167D02*
X912867Y737500D01*
X912367Y737750D01*
X911783Y737833D01*
X911117Y737667D01*
X910700Y737333D01*
X910367Y736750D01*
X910200Y736167D01*
X910283Y735667D01*
X910617Y735083D01*
X911117Y734667D01*
X911783Y734500D01*
X912283Y734583D01*
X912867Y734917D01*
X913200Y735250D01*
G01X798500Y795500D02*
Y790500D01*
G01X796583Y795500D02*
X800417D01*
G01X802017Y793833D02*
X803017Y790500D01*
X804100Y793833D01*
X805183Y790500D01*
X806183Y793833D01*
G01X809700D02*
Y790500D01*
G01Y795167D02*
X809533Y795250D01*
Y795417D01*
X809700Y795500D01*
X809867Y795417D01*
Y795250D01*
X809700Y795167D01*
G01X814050Y791083D02*
X814467Y790750D01*
X815050Y790500D01*
X815550D01*
X816050Y790667D01*
X816383Y790917D01*
X816550Y791250D01*
X816467Y791750D01*
X816133Y792000D01*
X814633Y792500D01*
X814300Y793083D01*
X814467Y793500D01*
X814800Y793750D01*
X815300Y793833D01*
X815800Y793750D01*
X816300Y793500D01*
G01X820900Y795500D02*
Y790500D01*
G01X819733Y793833D02*
X822067D01*
G01X833600Y790500D02*
Y793833D01*
G01Y793250D02*
X833267Y793583D01*
X832767Y793750D01*
X832183Y793833D01*
X831600Y793667D01*
X831100Y793333D01*
X830767Y792833D01*
X830600Y792167D01*
X830767Y791500D01*
X831100Y791000D01*
X831600Y790667D01*
X832183Y790500D01*
X832767Y790583D01*
X833267Y790833D01*
X833600Y791167D01*
G01X836283Y790500D02*
Y793833D01*
G01Y793000D02*
X836617Y793417D01*
X837117Y793750D01*
X837783Y793833D01*
X838367Y793750D01*
X838867Y793417D01*
X839117Y792833D01*
Y790500D01*
G01X844800Y795500D02*
Y790500D01*
G01Y791250D02*
X844467Y790833D01*
X843967Y790583D01*
X843383Y790500D01*
X842717Y790667D01*
X842217Y791083D01*
X841883Y791583D01*
X841800Y792167D01*
X841883Y792750D01*
X842217Y793250D01*
X842717Y793667D01*
X843383Y793833D01*
X843967Y793750D01*
X844383Y793583D01*
X844800Y793250D01*
G01X853000Y790500D02*
Y795500D01*
G01Y793000D02*
X853417Y793500D01*
X853917Y793750D01*
X854417Y793833D01*
X855167Y793667D01*
X855667Y793333D01*
X856000Y792750D01*
Y792083D01*
X855833Y791417D01*
X855500Y790917D01*
X854917Y790583D01*
X854417Y790500D01*
X853917Y790583D01*
X853417Y790833D01*
X853000Y791250D01*
G01X860100Y790500D02*
X859600Y790583D01*
X859100Y790917D01*
X858767Y791500D01*
X858600Y792167D01*
X858767Y792833D01*
X859100Y793417D01*
X859600Y793750D01*
X860100Y793833D01*
X860600Y793750D01*
X861100Y793417D01*
X861433Y792833D01*
X861517Y792167D01*
X861433Y791500D01*
X861100Y790917D01*
X860600Y790583D01*
X860100Y790500D01*
G01X863617Y793833D02*
X864617Y790500D01*
X865700Y793833D01*
X866783Y790500D01*
X867783Y793833D01*
G01X796833Y826500D02*
Y831500D01*
X798917D01*
X799583Y831250D01*
X800000Y830917D01*
X800167Y830250D01*
X800000Y829583D01*
X799500Y829167D01*
X798917Y828917D01*
X796833D01*
G01X798917D02*
X800167Y826500D01*
G01X804100D02*
X803600Y826583D01*
X803100Y826917D01*
X802767Y827500D01*
X802600Y828167D01*
X802767Y828833D01*
X803100Y829417D01*
X803600Y829750D01*
X804100Y829833D01*
X804600Y829750D01*
X805100Y829417D01*
X805433Y828833D01*
X805517Y828167D01*
X805433Y827500D01*
X805100Y826917D01*
X804600Y826583D01*
X804100Y826500D01*
G01X808283Y829833D02*
Y827500D01*
X808617Y826917D01*
X809117Y826583D01*
X809700Y826500D01*
X810283Y826583D01*
X810783Y826917D01*
X811117Y827500D01*
G01Y826500D02*
Y829833D01*
G01X815300Y831500D02*
Y826500D01*
G01X814133Y829833D02*
X816467D01*
G01X820900D02*
Y826500D01*
G01Y831167D02*
X820733Y831250D01*
Y831417D01*
X820900Y831500D01*
X821067Y831417D01*
Y831250D01*
X820900Y831167D01*
G01X825083Y826500D02*
Y829833D01*
G01Y829000D02*
X825417Y829417D01*
X825917Y829750D01*
X826583Y829833D01*
X827167Y829750D01*
X827667Y829417D01*
X827917Y828833D01*
Y826500D01*
G01X830933Y825250D02*
X831517Y824917D01*
X832183Y824833D01*
X832767Y824917D01*
X833267Y825333D01*
X833600Y825917D01*
Y829833D01*
G01Y829167D02*
X833267Y829500D01*
X832767Y829750D01*
X832183Y829833D01*
X831517Y829667D01*
X831100Y829333D01*
X830767Y828750D01*
X830600Y828167D01*
X830683Y827667D01*
X831017Y827083D01*
X831517Y826667D01*
X832183Y826500D01*
X832683Y826583D01*
X833267Y826917D01*
X833600Y827250D01*
G01X843300Y831500D02*
Y826500D01*
G01X842133Y829833D02*
X844467D01*
G01X848900Y826500D02*
X848400Y826583D01*
X847900Y826917D01*
X847567Y827500D01*
X847400Y828167D01*
X847567Y828833D01*
X847900Y829417D01*
X848400Y829750D01*
X848900Y829833D01*
X849400Y829750D01*
X849900Y829417D01*
X850233Y828833D01*
X850317Y828167D01*
X850233Y827500D01*
X849900Y826917D01*
X849400Y826583D01*
X848900Y826500D01*
G01X854500D02*
Y831500D01*
G01X858850Y828750D02*
X861517D01*
X861267Y829333D01*
X860850Y829667D01*
X860267Y829833D01*
X859683Y829750D01*
X859183Y829500D01*
X858850Y828917D01*
X858683Y828417D01*
Y827917D01*
X858850Y827417D01*
X859267Y826917D01*
X859767Y826583D01*
X860350Y826500D01*
X860933Y826667D01*
X861517Y827167D01*
G01X864533Y826500D02*
Y829833D01*
G01Y829167D02*
X864950Y829500D01*
X865367Y829750D01*
X865950Y829833D01*
X866367Y829750D01*
X866867Y829500D01*
G01X872800Y826500D02*
Y829833D01*
G01Y829250D02*
X872467Y829583D01*
X871967Y829750D01*
X871383Y829833D01*
X870800Y829667D01*
X870300Y829333D01*
X869967Y828833D01*
X869800Y828167D01*
X869967Y827500D01*
X870300Y827000D01*
X870800Y826667D01*
X871383Y826500D01*
X871967Y826583D01*
X872467Y826833D01*
X872800Y827167D01*
G01X875483Y826500D02*
Y829833D01*
G01Y829000D02*
X875817Y829417D01*
X876317Y829750D01*
X876983Y829833D01*
X877567Y829750D01*
X878067Y829417D01*
X878317Y828833D01*
Y826500D01*
G01X883833Y829417D02*
X883250Y829750D01*
X882750Y829833D01*
X882083Y829667D01*
X881583Y829333D01*
X881250Y828750D01*
X881167Y828167D01*
X881250Y827583D01*
X881583Y827083D01*
X882083Y826667D01*
X882750Y826500D01*
X883333Y826667D01*
X883833Y827000D01*
G01X886850Y828750D02*
X889517D01*
X889267Y829333D01*
X888850Y829667D01*
X888267Y829833D01*
X887683Y829750D01*
X887183Y829500D01*
X886850Y828917D01*
X886683Y828417D01*
Y827917D01*
X886850Y827417D01*
X887267Y826917D01*
X887767Y826583D01*
X888350Y826500D01*
X888933Y826667D01*
X889517Y827167D01*
G01X788000Y850610D02*
Y782110D01*
G01Y805500D02*
X1343000D01*
G01X928583Y23083D02*
X929167Y22667D01*
X929833Y22500D01*
X930500Y22667D01*
X931083Y23167D01*
X931500Y23917D01*
X931667Y24667D01*
Y25583D01*
X931500Y26333D01*
X931083Y27000D01*
X930583Y27333D01*
X930000Y27500D01*
X929333Y27333D01*
X928833Y27000D01*
X928500Y26500D01*
X928333Y25833D01*
X928500Y25250D01*
X928917Y24667D01*
X929417Y24333D01*
X930000Y24250D01*
X930667Y24417D01*
X931167Y24833D01*
X931667Y25583D01*
G01X934017Y24583D02*
X934600Y25167D01*
X935100Y25500D01*
X935767Y25667D01*
X936350Y25500D01*
X936767Y25167D01*
X937100Y24667D01*
X937183Y24083D01*
X937100Y23583D01*
X936767Y23083D01*
X936267Y22667D01*
X935683Y22500D01*
X935017Y22667D01*
X934433Y23167D01*
X934100Y23917D01*
X934017Y24750D01*
X934183Y25833D01*
X934433Y26417D01*
X934850Y27000D01*
X935433Y27417D01*
X936017Y27500D01*
X936600Y27333D01*
X937017Y26917D01*
G01X909000Y67500D02*
Y72500D01*
X905917Y68917D01*
X910083D01*
G01X911767Y68250D02*
X912267Y67833D01*
X912850Y67583D01*
X913600Y67500D01*
X914350Y67667D01*
X914933Y68000D01*
X915350Y68583D01*
X915433Y69250D01*
X915267Y69917D01*
X914850Y70333D01*
X914267Y70667D01*
X913683Y70750D01*
X913100Y70667D01*
X912350Y70333D01*
X912600Y72500D01*
X914850D01*
G01X909250Y184083D02*
X909667Y183750D01*
X910250Y183500D01*
X910750D01*
X911250Y183667D01*
X911583Y183917D01*
X911750Y184250D01*
X911667Y184750D01*
X911333Y185000D01*
X909833Y185500D01*
X909500Y186083D01*
X909667Y186500D01*
X910000Y186750D01*
X910500Y186833D01*
X911000Y186750D01*
X911500Y186500D01*
G01X916100Y188500D02*
Y183500D01*
G01X914933Y186833D02*
X917267D01*
G01X920283D02*
Y184500D01*
X920617Y183917D01*
X921117Y183583D01*
X921700Y183500D01*
X922283Y183583D01*
X922783Y183917D01*
X923117Y184500D01*
G01Y183500D02*
Y186833D01*
G01X925800Y183500D02*
Y188500D01*
G01Y186000D02*
X926217Y186500D01*
X926717Y186750D01*
X927217Y186833D01*
X927967Y186667D01*
X928467Y186333D01*
X928800Y185750D01*
Y185083D01*
X928633Y184417D01*
X928300Y183917D01*
X927717Y183583D01*
X927217Y183500D01*
X926717Y183583D01*
X926217Y183833D01*
X925800Y184250D01*
G01X938500Y183500D02*
Y188500D01*
G01X942850Y185750D02*
X945517D01*
X945267Y186333D01*
X944850Y186667D01*
X944267Y186833D01*
X943683Y186750D01*
X943183Y186500D01*
X942850Y185917D01*
X942683Y185417D01*
Y184917D01*
X942850Y184417D01*
X943267Y183917D01*
X943767Y183583D01*
X944350Y183500D01*
X944933Y183667D01*
X945517Y184167D01*
G01X948283Y183500D02*
Y186833D01*
G01Y186000D02*
X948617Y186417D01*
X949117Y186750D01*
X949783Y186833D01*
X950367Y186750D01*
X950867Y186417D01*
X951117Y185833D01*
Y183500D01*
G01X954133Y182250D02*
X954717Y181917D01*
X955383Y181833D01*
X955967Y181917D01*
X956467Y182333D01*
X956800Y182917D01*
Y186833D01*
G01Y186167D02*
X956467Y186500D01*
X955967Y186750D01*
X955383Y186833D01*
X954717Y186667D01*
X954300Y186333D01*
X953967Y185750D01*
X953800Y185167D01*
X953883Y184667D01*
X954217Y184083D01*
X954717Y183667D01*
X955383Y183500D01*
X955883Y183583D01*
X956467Y183917D01*
X956800Y184250D01*
G01X960900Y188500D02*
Y183500D01*
G01X959733Y186833D02*
X962067D01*
G01X965083Y183500D02*
Y188500D01*
G01Y186083D02*
X965500Y186500D01*
X965917Y186750D01*
X966583Y186833D01*
X967083Y186750D01*
X967667Y186417D01*
X967917Y185917D01*
Y183500D01*
G01X971017Y184417D02*
X973183D01*
G01Y185917D02*
X971017D01*
G01X976117Y185583D02*
X976700Y186167D01*
X977200Y186500D01*
X977867Y186667D01*
X978450Y186500D01*
X978867Y186167D01*
X979200Y185667D01*
X979283Y185083D01*
X979200Y184583D01*
X978867Y184083D01*
X978367Y183667D01*
X977783Y183500D01*
X977117Y183667D01*
X976533Y184167D01*
X976200Y184917D01*
X976117Y185750D01*
X976283Y186833D01*
X976533Y187417D01*
X976950Y188000D01*
X977533Y188417D01*
X978117Y188500D01*
X978700Y188333D01*
X979117Y187917D01*
G01X982383Y185167D02*
X984383D01*
G01X983300Y186250D02*
Y184083D01*
G01X987400Y183333D02*
X990400Y188500D01*
G01X993417Y185167D02*
X995583D01*
G01X998267Y184250D02*
X998767Y183833D01*
X999350Y183583D01*
X1000100Y183500D01*
X1000850Y183667D01*
X1001433Y184000D01*
X1001850Y184583D01*
X1001933Y185250D01*
X1001767Y185917D01*
X1001350Y186333D01*
X1000767Y186667D01*
X1000183Y186750D01*
X999600Y186667D01*
X998850Y186333D01*
X999100Y188500D01*
X1001350D01*
G01X1003200Y183500D02*
Y186833D01*
G01Y185917D02*
X1003450Y186333D01*
X1003867Y186667D01*
X1004450Y186833D01*
X1005033Y186667D01*
X1005450Y186333D01*
X1005700Y185917D01*
Y183500D01*
G01Y185917D02*
X1005950Y186333D01*
X1006367Y186667D01*
X1006950Y186833D01*
X1007533Y186667D01*
X1007950Y186333D01*
X1008200Y185833D01*
Y183500D01*
G01X1011300Y186833D02*
Y183500D01*
G01Y188167D02*
X1011133Y188250D01*
Y188417D01*
X1011300Y188500D01*
X1011467Y188417D01*
Y188250D01*
X1011300Y188167D01*
G01X1016900Y183500D02*
Y188500D01*
G01X868250Y152000D02*
Y157000D01*
G01X871750D02*
Y152000D01*
G01Y154500D02*
X868250D01*
G01X875600Y152000D02*
X874933Y152083D01*
X874350Y152417D01*
X873850Y152917D01*
X873517Y153500D01*
X873350Y154167D01*
Y154833D01*
X873517Y155500D01*
X873850Y156083D01*
X874350Y156583D01*
X874933Y156917D01*
X875600Y157000D01*
X876267Y156917D01*
X876850Y156583D01*
X877350Y156083D01*
X877683Y155500D01*
X877850Y154833D01*
Y154167D01*
X877683Y153500D01*
X877350Y152917D01*
X876850Y152417D01*
X876267Y152083D01*
X875600Y152000D01*
G01X879533Y157000D02*
Y152000D01*
X882867D01*
G01X888467D02*
X885133D01*
Y157000D01*
X888467D01*
G01X887133Y154583D02*
X885133D01*
G01X912300Y152000D02*
Y155333D01*
G01Y154417D02*
X912550Y154833D01*
X912967Y155167D01*
X913550Y155333D01*
X914133Y155167D01*
X914550Y154833D01*
X914800Y154417D01*
Y152000D01*
G01Y154417D02*
X915050Y154833D01*
X915467Y155167D01*
X916050Y155333D01*
X916633Y155167D01*
X917050Y154833D01*
X917300Y154333D01*
Y152000D01*
G01X920400Y155333D02*
Y152000D01*
G01Y156667D02*
X920233Y156750D01*
Y156917D01*
X920400Y157000D01*
X920567Y156917D01*
Y156750D01*
X920400Y156667D01*
G01X926000Y152000D02*
Y157000D01*
G01X930350Y152583D02*
X930767Y152250D01*
X931350Y152000D01*
X931850D01*
X932350Y152167D01*
X932683Y152417D01*
X932850Y152750D01*
X932767Y153250D01*
X932433Y153500D01*
X930933Y154000D01*
X930600Y154583D01*
X930767Y155000D01*
X931100Y155250D01*
X931600Y155333D01*
X932100Y155250D01*
X932600Y155000D01*
G01X936783Y150333D02*
X935950Y151167D01*
X935533Y152000D01*
Y155333D01*
X935950Y156167D01*
X936783Y157000D01*
G01X941133Y152000D02*
Y157000D01*
X943133D01*
X943800Y156750D01*
X944300Y156167D01*
X944467Y155500D01*
X944300Y154833D01*
X943883Y154333D01*
X943133Y154083D01*
X941133D01*
G01X948400Y157000D02*
Y152000D01*
G01X946483Y157000D02*
X950317D01*
G01X952250Y152000D02*
Y157000D01*
G01X955750D02*
Y152000D01*
G01Y154500D02*
X952250D01*
G01X960017Y150333D02*
X960850Y151167D01*
X961267Y152000D01*
Y155333D01*
X960850Y156167D01*
X960017Y157000D01*
G01X900833Y214500D02*
Y209500D01*
X904167D01*
G01X906683D02*
Y212833D01*
G01Y212000D02*
X907017Y212417D01*
X907517Y212750D01*
X908183Y212833D01*
X908767Y212750D01*
X909267Y212417D01*
X909517Y211833D01*
Y209500D01*
G01X902833Y255500D02*
Y250500D01*
X906167D01*
G01X908850Y253833D02*
X911350Y250500D01*
G01Y253833D02*
X908850Y250500D01*
G01X889267Y349073D02*
X892933Y352740D01*
G01X891100Y353407D02*
Y348407D01*
G01X892933Y349073D02*
X889267Y352740D01*
G01X888600Y350907D02*
X893600D01*
G01X896283Y347573D02*
X895450Y348407D01*
X895033Y349240D01*
Y352573D01*
X895450Y353407D01*
X896283Y354240D01*
G01X900467Y349990D02*
X900967Y349573D01*
X901550Y349323D01*
X902300Y349240D01*
X903050Y349407D01*
X903633Y349740D01*
X904050Y350323D01*
X904133Y350990D01*
X903967Y351657D01*
X903550Y352073D01*
X902967Y352407D01*
X902383Y352490D01*
X901800Y352407D01*
X901050Y352073D01*
X901300Y354240D01*
X903550D01*
G01X907900Y349073D02*
X907733Y349157D01*
Y349323D01*
X907900Y349407D01*
X908067Y349323D01*
Y349157D01*
X907900Y349073D01*
G01X913500Y349240D02*
Y354240D01*
X912500Y353240D01*
G01Y349240D02*
X914500D01*
G01X919517Y347573D02*
X920350Y348407D01*
X920767Y349240D01*
Y352573D01*
X920350Y353407D01*
X919517Y354240D01*
G01X868167Y308167D02*
X868500Y308417D01*
X868750Y308833D01*
X868917Y309417D01*
X868750Y309917D01*
X868417Y310250D01*
X867833Y310500D01*
X865583D01*
Y305500D01*
X868333D01*
X868917Y305833D01*
X869250Y306333D01*
X869417Y306917D01*
X869250Y307500D01*
X868750Y308000D01*
X868167Y308167D01*
X865583D01*
G01X871017Y305500D02*
X873100Y310500D01*
X875183Y305500D01*
G01X874433Y307250D02*
X871767D01*
G01X880533Y310083D02*
X880033Y310333D01*
X879450Y310500D01*
X878783D01*
X878033Y310250D01*
X877450Y309833D01*
X877033Y309333D01*
X876700Y308500D01*
X876617Y307750D01*
X876783Y307000D01*
X877033Y306500D01*
X877533Y306000D01*
X878117Y305667D01*
X878700Y305500D01*
X879283D01*
X879867Y305667D01*
X880367Y305917D01*
X880783Y306250D01*
G01X882467Y305500D02*
Y310500D01*
G01X885633D02*
X882467Y307417D01*
G01X886133Y305500D02*
X883883Y308833D01*
G01X893667Y305500D02*
Y310500D01*
X895333D01*
X896000Y310250D01*
X896500Y309917D01*
X896917Y309417D01*
X897250Y308833D01*
X897333Y308000D01*
X897250Y307167D01*
X896917Y306583D01*
X896500Y306083D01*
X896000Y305750D01*
X895333Y305500D01*
X893667D01*
G01X899433D02*
Y310500D01*
X901517D01*
X902183Y310250D01*
X902600Y309917D01*
X902767Y309250D01*
X902600Y308583D01*
X902100Y308167D01*
X901517Y307917D01*
X899433D01*
G01X901517D02*
X902767Y305500D01*
G01X905700Y310500D02*
X907700D01*
G01X906700D02*
Y305500D01*
G01X905700D02*
X907700D01*
G01X910633Y310500D02*
Y305500D01*
X913967D01*
G01X916233Y310500D02*
Y305500D01*
X919567D01*
G01X943400D02*
Y308833D01*
G01Y307917D02*
X943650Y308333D01*
X944067Y308667D01*
X944650Y308833D01*
X945233Y308667D01*
X945650Y308333D01*
X945900Y307917D01*
Y305500D01*
G01Y307917D02*
X946150Y308333D01*
X946567Y308667D01*
X947150Y308833D01*
X947733Y308667D01*
X948150Y308333D01*
X948400Y307833D01*
Y305500D01*
G01X951500Y308833D02*
Y305500D01*
G01Y310167D02*
X951333Y310250D01*
Y310417D01*
X951500Y310500D01*
X951667Y310417D01*
Y310250D01*
X951500Y310167D01*
G01X957100Y305500D02*
Y310500D01*
G01X961450Y306083D02*
X961867Y305750D01*
X962450Y305500D01*
X962950D01*
X963450Y305667D01*
X963783Y305917D01*
X963950Y306250D01*
X963867Y306750D01*
X963533Y307000D01*
X962033Y307500D01*
X961700Y308083D01*
X961867Y308500D01*
X962200Y308750D01*
X962700Y308833D01*
X963200Y308750D01*
X963700Y308500D01*
G01X967883Y303833D02*
X967050Y304667D01*
X966633Y305500D01*
Y308833D01*
X967050Y309667D01*
X967883Y310500D01*
G01X971983Y305500D02*
Y310500D01*
X975817Y305500D01*
Y310500D01*
G01X977833Y305500D02*
Y310500D01*
X979833D01*
X980500Y310250D01*
X981000Y309667D01*
X981167Y309000D01*
X981000Y308333D01*
X980583Y307833D01*
X979833Y307583D01*
X977833D01*
G01X985100Y310500D02*
Y305500D01*
G01X983183Y310500D02*
X987017D01*
G01X988950Y305500D02*
Y310500D01*
G01X992450D02*
Y305500D01*
G01Y308000D02*
X988950D01*
G01X996717Y303833D02*
X997550Y304667D01*
X997967Y305500D01*
Y308833D01*
X997550Y309667D01*
X996717Y310500D01*
G01X894000Y556000D02*
Y551000D01*
G01X892833Y554333D02*
X895167D01*
G01X898183Y551000D02*
Y556000D01*
G01Y553583D02*
X898600Y554000D01*
X899017Y554250D01*
X899683Y554333D01*
X900183Y554250D01*
X900767Y553917D01*
X901017Y553417D01*
Y551000D01*
G01X903950Y553250D02*
X906617D01*
X906367Y553833D01*
X905950Y554167D01*
X905367Y554333D01*
X904783Y554250D01*
X904283Y554000D01*
X903950Y553417D01*
X903783Y552917D01*
Y552417D01*
X903950Y551917D01*
X904367Y551417D01*
X904867Y551083D01*
X905450Y551000D01*
X906033Y551167D01*
X906617Y551667D01*
G01X916400Y551000D02*
X915900Y551083D01*
X915400Y551417D01*
X915067Y552000D01*
X914900Y552667D01*
X915067Y553333D01*
X915400Y553917D01*
X915900Y554250D01*
X916400Y554333D01*
X916900Y554250D01*
X917400Y553917D01*
X917733Y553333D01*
X917817Y552667D01*
X917733Y552000D01*
X917400Y551417D01*
X916900Y551083D01*
X916400Y551000D01*
G01X922000Y556000D02*
Y551000D01*
G01X920833Y554333D02*
X923167D01*
G01X926183Y551000D02*
Y556000D01*
G01Y553583D02*
X926600Y554000D01*
X927017Y554250D01*
X927683Y554333D01*
X928183Y554250D01*
X928767Y553917D01*
X929017Y553417D01*
Y551000D01*
G01X931950Y553250D02*
X934617D01*
X934367Y553833D01*
X933950Y554167D01*
X933367Y554333D01*
X932783Y554250D01*
X932283Y554000D01*
X931950Y553417D01*
X931783Y552917D01*
Y552417D01*
X931950Y551917D01*
X932367Y551417D01*
X932867Y551083D01*
X933450Y551000D01*
X934033Y551167D01*
X934617Y551667D01*
G01X937633Y551000D02*
Y554333D01*
G01Y553667D02*
X938050Y554000D01*
X938467Y554250D01*
X939050Y554333D01*
X939467Y554250D01*
X939967Y554000D01*
G01X948750Y551583D02*
X949167Y551250D01*
X949750Y551000D01*
X950250D01*
X950750Y551167D01*
X951083Y551417D01*
X951250Y551750D01*
X951167Y552250D01*
X950833Y552500D01*
X949333Y553000D01*
X949000Y553583D01*
X949167Y554000D01*
X949500Y554250D01*
X950000Y554333D01*
X950500Y554250D01*
X951000Y554000D01*
G01X955600Y554333D02*
Y551000D01*
G01Y555667D02*
X955433Y555750D01*
Y555917D01*
X955600Y556000D01*
X955767Y555917D01*
Y555750D01*
X955600Y555667D01*
G01X962700Y556000D02*
Y551000D01*
G01Y551750D02*
X962367Y551333D01*
X961867Y551083D01*
X961283Y551000D01*
X960617Y551167D01*
X960117Y551583D01*
X959783Y552083D01*
X959700Y552667D01*
X959783Y553250D01*
X960117Y553750D01*
X960617Y554167D01*
X961283Y554333D01*
X961867Y554250D01*
X962283Y554083D01*
X962700Y553750D01*
G01X965550Y553250D02*
X968217D01*
X967967Y553833D01*
X967550Y554167D01*
X966967Y554333D01*
X966383Y554250D01*
X965883Y554000D01*
X965550Y553417D01*
X965383Y552917D01*
Y552417D01*
X965550Y551917D01*
X965967Y551417D01*
X966467Y551083D01*
X967050Y551000D01*
X967633Y551167D01*
X968217Y551667D01*
G01X975917Y554333D02*
X976917Y551000D01*
X978000Y554333D01*
X979083Y551000D01*
X980083Y554333D01*
G01X983600D02*
Y551000D01*
G01Y555667D02*
X983433Y555750D01*
Y555917D01*
X983600Y556000D01*
X983767Y555917D01*
Y555750D01*
X983600Y555667D01*
G01X989200Y556000D02*
Y551000D01*
G01X988033Y554333D02*
X990367D01*
G01X993383Y551000D02*
Y556000D01*
G01Y553583D02*
X993800Y554000D01*
X994217Y554250D01*
X994883Y554333D01*
X995383Y554250D01*
X995967Y553917D01*
X996217Y553417D01*
Y551000D01*
G01X1000400D02*
X999900Y551083D01*
X999400Y551417D01*
X999067Y552000D01*
X998900Y552667D01*
X999067Y553333D01*
X999400Y553917D01*
X999900Y554250D01*
X1000400Y554333D01*
X1000900Y554250D01*
X1001400Y553917D01*
X1001733Y553333D01*
X1001817Y552667D01*
X1001733Y552000D01*
X1001400Y551417D01*
X1000900Y551083D01*
X1000400Y551000D01*
G01X1004583Y554333D02*
Y552000D01*
X1004917Y551417D01*
X1005417Y551083D01*
X1006000Y551000D01*
X1006583Y551083D01*
X1007083Y551417D01*
X1007417Y552000D01*
G01Y551000D02*
Y554333D01*
G01X1011600Y556000D02*
Y551000D01*
G01X1010433Y554333D02*
X1012767D01*
G01X878000Y591500D02*
X879667D01*
Y590000D01*
X879167Y589500D01*
X878583Y589167D01*
X877750Y589000D01*
X876917Y589167D01*
X876333Y589500D01*
X875833Y590000D01*
X875500Y590583D01*
X875333Y591250D01*
Y591833D01*
X875500Y592333D01*
X875833Y592917D01*
X876333Y593417D01*
X876833Y593750D01*
X877500Y594000D01*
X878083D01*
X878750Y593833D01*
X879250Y593500D01*
G01X881850Y591250D02*
X884517D01*
X884267Y591833D01*
X883850Y592167D01*
X883267Y592333D01*
X882683Y592250D01*
X882183Y592000D01*
X881850Y591417D01*
X881683Y590917D01*
Y590417D01*
X881850Y589917D01*
X882267Y589417D01*
X882767Y589083D01*
X883350Y589000D01*
X883933Y589167D01*
X884517Y589667D01*
G01X887533Y589000D02*
Y592333D01*
G01Y591667D02*
X887950Y592000D01*
X888367Y592250D01*
X888950Y592333D01*
X889367Y592250D01*
X889867Y592000D01*
G01X892800Y589000D02*
Y594000D01*
G01Y591500D02*
X893217Y592000D01*
X893717Y592250D01*
X894217Y592333D01*
X894967Y592167D01*
X895467Y591833D01*
X895800Y591250D01*
Y590583D01*
X895633Y589917D01*
X895300Y589417D01*
X894717Y589083D01*
X894217Y589000D01*
X893717Y589083D01*
X893217Y589333D01*
X892800Y589750D01*
G01X898650Y591250D02*
X901317D01*
X901067Y591833D01*
X900650Y592167D01*
X900067Y592333D01*
X899483Y592250D01*
X898983Y592000D01*
X898650Y591417D01*
X898483Y590917D01*
Y590417D01*
X898650Y589917D01*
X899067Y589417D01*
X899567Y589083D01*
X900150Y589000D01*
X900733Y589167D01*
X901317Y589667D01*
G01X904333Y589000D02*
Y592333D01*
G01Y591667D02*
X904750Y592000D01*
X905167Y592250D01*
X905750Y592333D01*
X906167Y592250D01*
X906667Y592000D01*
G01X918200Y594000D02*
Y589000D01*
G01Y589750D02*
X917867Y589333D01*
X917367Y589083D01*
X916783Y589000D01*
X916117Y589167D01*
X915617Y589583D01*
X915283Y590083D01*
X915200Y590667D01*
X915283Y591250D01*
X915617Y591750D01*
X916117Y592167D01*
X916783Y592333D01*
X917367Y592250D01*
X917783Y592083D01*
X918200Y591750D01*
G01X921050Y591250D02*
X923717D01*
X923467Y591833D01*
X923050Y592167D01*
X922467Y592333D01*
X921883Y592250D01*
X921383Y592000D01*
X921050Y591417D01*
X920883Y590917D01*
Y590417D01*
X921050Y589917D01*
X921467Y589417D01*
X921967Y589083D01*
X922550Y589000D01*
X923133Y589167D01*
X923717Y589667D01*
G01X926650Y589583D02*
X927067Y589250D01*
X927650Y589000D01*
X928150D01*
X928650Y589167D01*
X928983Y589417D01*
X929150Y589750D01*
X929067Y590250D01*
X928733Y590500D01*
X927233Y591000D01*
X926900Y591583D01*
X927067Y592000D01*
X927400Y592250D01*
X927900Y592333D01*
X928400Y592250D01*
X928900Y592000D01*
G01X933500Y592333D02*
Y589000D01*
G01Y593667D02*
X933333Y593750D01*
Y593917D01*
X933500Y594000D01*
X933667Y593917D01*
Y593750D01*
X933500Y593667D01*
G01X937933Y587750D02*
X938517Y587417D01*
X939183Y587333D01*
X939767Y587417D01*
X940267Y587833D01*
X940600Y588417D01*
Y592333D01*
G01Y591667D02*
X940267Y592000D01*
X939767Y592250D01*
X939183Y592333D01*
X938517Y592167D01*
X938100Y591833D01*
X937767Y591250D01*
X937600Y590667D01*
X937683Y590167D01*
X938017Y589583D01*
X938517Y589167D01*
X939183Y589000D01*
X939683Y589083D01*
X940267Y589417D01*
X940600Y589750D01*
G01X943283Y589000D02*
Y592333D01*
G01Y591500D02*
X943617Y591917D01*
X944117Y592250D01*
X944783Y592333D01*
X945367Y592250D01*
X945867Y591917D01*
X946117Y591333D01*
Y589000D01*
G01X929000Y734500D02*
Y738750D01*
X929167Y739167D01*
X929500Y739417D01*
X930000Y739500D01*
X930500Y739333D01*
X930750Y738917D01*
G01X929750Y737500D02*
X928083D01*
G01X933683Y737833D02*
Y735500D01*
X934017Y734917D01*
X934517Y734583D01*
X935100Y734500D01*
X935683Y734583D01*
X936183Y734917D01*
X936517Y735500D01*
G01Y734500D02*
Y737833D01*
G01X940700Y734500D02*
Y739500D01*
G01X946300Y734500D02*
Y739500D01*
G01X956000Y732833D02*
Y737833D01*
G01Y737083D02*
X956417Y737500D01*
X956833Y737750D01*
X957500Y737833D01*
X958083Y737750D01*
X958667Y737333D01*
X958917Y736750D01*
X959000Y736167D01*
X958917Y735583D01*
X958667Y735000D01*
X958167Y734667D01*
X957500Y734500D01*
X956917Y734583D01*
X956333Y734833D01*
X956000Y735167D01*
G01X963100Y734500D02*
Y739500D01*
G01X967283Y737833D02*
Y735500D01*
X967617Y734917D01*
X968117Y734583D01*
X968700Y734500D01*
X969283Y734583D01*
X969783Y734917D01*
X970117Y735500D01*
G01Y734500D02*
Y737833D01*
G01X973133Y733250D02*
X973717Y732917D01*
X974383Y732833D01*
X974967Y732917D01*
X975467Y733333D01*
X975800Y733917D01*
Y737833D01*
G01Y737167D02*
X975467Y737500D01*
X974967Y737750D01*
X974383Y737833D01*
X973717Y737667D01*
X973300Y737333D01*
X972967Y736750D01*
X972800Y736167D01*
X972883Y735667D01*
X973217Y735083D01*
X973717Y734667D01*
X974383Y734500D01*
X974883Y734583D01*
X975467Y734917D01*
X975800Y735250D01*
G01X978733Y733250D02*
X979317Y732917D01*
X979983Y732833D01*
X980567Y732917D01*
X981067Y733333D01*
X981400Y733917D01*
Y737833D01*
G01Y737167D02*
X981067Y737500D01*
X980567Y737750D01*
X979983Y737833D01*
X979317Y737667D01*
X978900Y737333D01*
X978567Y736750D01*
X978400Y736167D01*
X978483Y735667D01*
X978817Y735083D01*
X979317Y734667D01*
X979983Y734500D01*
X980483Y734583D01*
X981067Y734917D01*
X981400Y735250D01*
G01X985500Y737833D02*
Y734500D01*
G01Y739167D02*
X985333Y739250D01*
Y739417D01*
X985500Y739500D01*
X985667Y739417D01*
Y739250D01*
X985500Y739167D01*
G01X989683Y734500D02*
Y737833D01*
G01Y737000D02*
X990017Y737417D01*
X990517Y737750D01*
X991183Y737833D01*
X991767Y737750D01*
X992267Y737417D01*
X992517Y736833D01*
Y734500D01*
G01X995533Y733250D02*
X996117Y732917D01*
X996783Y732833D01*
X997367Y732917D01*
X997867Y733333D01*
X998200Y733917D01*
Y737833D01*
G01Y737167D02*
X997867Y737500D01*
X997367Y737750D01*
X996783Y737833D01*
X996117Y737667D01*
X995700Y737333D01*
X995367Y736750D01*
X995200Y736167D01*
X995283Y735667D01*
X995617Y735083D01*
X996117Y734667D01*
X996783Y734500D01*
X997283Y734583D01*
X997867Y734917D01*
X998200Y735250D01*
G01X995667Y5500D02*
Y10500D01*
X997333D01*
X998000Y10250D01*
X998500Y9917D01*
X998917Y9417D01*
X999250Y8833D01*
X999333Y8000D01*
X999250Y7167D01*
X998917Y6583D01*
X998500Y6083D01*
X998000Y5750D01*
X997333Y5500D01*
X995667D01*
G01X1003100D02*
Y10500D01*
X1002100Y9500D01*
G01Y5500D02*
X1004100D01*
G01X1007117Y7583D02*
X1007700Y8167D01*
X1008200Y8500D01*
X1008867Y8667D01*
X1009450Y8500D01*
X1009867Y8167D01*
X1010200Y7667D01*
X1010283Y7083D01*
X1010200Y6583D01*
X1009867Y6083D01*
X1009367Y5667D01*
X1008783Y5500D01*
X1008117Y5667D01*
X1007533Y6167D01*
X1007200Y6917D01*
X1007117Y7750D01*
X1007283Y8833D01*
X1007533Y9417D01*
X1007950Y10000D01*
X1008533Y10417D01*
X1009117Y10500D01*
X1009700Y10333D01*
X1010117Y9917D01*
G01X1014300Y5333D02*
X1014133Y5417D01*
Y5583D01*
X1014300Y5667D01*
X1014467Y5583D01*
Y5417D01*
X1014300Y5333D01*
G01Y7583D02*
X1014133Y7667D01*
Y7833D01*
X1014300Y7917D01*
X1014467Y7833D01*
Y7667D01*
X1014300Y7583D01*
G01X1018067Y5500D02*
Y10500D01*
X1019733D01*
X1020400Y10250D01*
X1020900Y9917D01*
X1021317Y9417D01*
X1021650Y8833D01*
X1021733Y8000D01*
X1021650Y7167D01*
X1021317Y6583D01*
X1020900Y6083D01*
X1020400Y5750D01*
X1019733Y5500D01*
X1018067D01*
G01X1025500Y8833D02*
Y5500D01*
G01Y10167D02*
X1025333Y10250D01*
Y10417D01*
X1025500Y10500D01*
X1025667Y10417D01*
Y10250D01*
X1025500Y10167D01*
G01X1032600Y5500D02*
Y8833D01*
G01Y8250D02*
X1032267Y8583D01*
X1031767Y8750D01*
X1031183Y8833D01*
X1030600Y8667D01*
X1030100Y8333D01*
X1029767Y7833D01*
X1029600Y7167D01*
X1029767Y6500D01*
X1030100Y6000D01*
X1030600Y5667D01*
X1031183Y5500D01*
X1031767Y5583D01*
X1032267Y5833D01*
X1032600Y6167D01*
G01X1034200Y5500D02*
Y8833D01*
G01Y7917D02*
X1034450Y8333D01*
X1034867Y8667D01*
X1035450Y8833D01*
X1036033Y8667D01*
X1036450Y8333D01*
X1036700Y7917D01*
Y5500D01*
G01Y7917D02*
X1036950Y8333D01*
X1037367Y8667D01*
X1037950Y8833D01*
X1038533Y8667D01*
X1038950Y8333D01*
X1039200Y7833D01*
Y5500D01*
G01X1041050Y7750D02*
X1043717D01*
X1043467Y8333D01*
X1043050Y8667D01*
X1042467Y8833D01*
X1041883Y8750D01*
X1041383Y8500D01*
X1041050Y7917D01*
X1040883Y7417D01*
Y6917D01*
X1041050Y6417D01*
X1041467Y5917D01*
X1041967Y5583D01*
X1042550Y5500D01*
X1043133Y5667D01*
X1043717Y6167D01*
G01X1047900Y10500D02*
Y5500D01*
G01X1046733Y8833D02*
X1049067D01*
G01X1052250Y7750D02*
X1054917D01*
X1054667Y8333D01*
X1054250Y8667D01*
X1053667Y8833D01*
X1053083Y8750D01*
X1052583Y8500D01*
X1052250Y7917D01*
X1052083Y7417D01*
Y6917D01*
X1052250Y6417D01*
X1052667Y5917D01*
X1053167Y5583D01*
X1053750Y5500D01*
X1054333Y5667D01*
X1054917Y6167D01*
G01X1057933Y5500D02*
Y8833D01*
G01Y8167D02*
X1058350Y8500D01*
X1058767Y8750D01*
X1059350Y8833D01*
X1059767Y8750D01*
X1060267Y8500D01*
G01X1070300Y5500D02*
Y10500D01*
X1069300Y9500D01*
G01Y5500D02*
X1071300D01*
G01X1074317Y7583D02*
X1074900Y8167D01*
X1075400Y8500D01*
X1076067Y8667D01*
X1076650Y8500D01*
X1077067Y8167D01*
X1077400Y7667D01*
X1077483Y7083D01*
X1077400Y6583D01*
X1077067Y6083D01*
X1076567Y5667D01*
X1075983Y5500D01*
X1075317Y5667D01*
X1074733Y6167D01*
X1074400Y6917D01*
X1074317Y7750D01*
X1074483Y8833D01*
X1074733Y9417D01*
X1075150Y10000D01*
X1075733Y10417D01*
X1076317Y10500D01*
X1076900Y10333D01*
X1077317Y9917D01*
G01X1079000Y5500D02*
Y8833D01*
G01Y7917D02*
X1079250Y8333D01*
X1079667Y8667D01*
X1080250Y8833D01*
X1080833Y8667D01*
X1081250Y8333D01*
X1081500Y7917D01*
Y5500D01*
G01Y7917D02*
X1081750Y8333D01*
X1082167Y8667D01*
X1082750Y8833D01*
X1083333Y8667D01*
X1083750Y8333D01*
X1084000Y7833D01*
Y5500D01*
G01X1087100Y8833D02*
Y5500D01*
G01Y10167D02*
X1086933Y10250D01*
Y10417D01*
X1087100Y10500D01*
X1087267Y10417D01*
Y10250D01*
X1087100Y10167D01*
G01X1092700Y5500D02*
Y10500D01*
G01X980667Y16500D02*
X977333D01*
Y21500D01*
X980667D01*
G01X979333Y19083D02*
X977333D01*
G01X983350Y19833D02*
X985850Y16500D01*
G01Y19833D02*
X983350Y16500D01*
G01X990200Y16333D02*
X990033Y16417D01*
Y16583D01*
X990200Y16667D01*
X990367Y16583D01*
Y16417D01*
X990200Y16333D01*
G01X994050Y16500D02*
Y21500D01*
G01X997550D02*
Y16500D01*
G01Y19000D02*
X994050D01*
G01X999733Y16500D02*
Y21500D01*
X1001817D01*
X1002483Y21250D01*
X1002900Y20917D01*
X1003067Y20250D01*
X1002900Y19583D01*
X1002400Y19167D01*
X1001817Y18917D01*
X999733D01*
G01X1001817D02*
X1003067Y16500D01*
G01X1008667D02*
X1005333D01*
Y21500D01*
X1008667D01*
G01X1007333Y19083D02*
X1005333D01*
G01X1013600Y16500D02*
Y21500D01*
X1010517Y17917D01*
X1014683D01*
G01X1016367Y17250D02*
X1016867Y16833D01*
X1017450Y16583D01*
X1018200Y16500D01*
X1018950Y16667D01*
X1019533Y17000D01*
X1019950Y17583D01*
X1020033Y18250D01*
X1019867Y18917D01*
X1019450Y19333D01*
X1018867Y19667D01*
X1018283Y19750D01*
X1017700Y19667D01*
X1016950Y19333D01*
X1017200Y21500D01*
X1019450D01*
G01X1022050Y16500D02*
X1025550Y21500D01*
G01X1022050D02*
X1025550Y16500D01*
G01X1027983Y17083D02*
X1028567Y16667D01*
X1029233Y16500D01*
X1029900Y16667D01*
X1030483Y17167D01*
X1030900Y17917D01*
X1031067Y18667D01*
Y19583D01*
X1030900Y20333D01*
X1030483Y21000D01*
X1029983Y21333D01*
X1029400Y21500D01*
X1028733Y21333D01*
X1028233Y21000D01*
X1027900Y20500D01*
X1027733Y19833D01*
X1027900Y19250D01*
X1028317Y18667D01*
X1028817Y18333D01*
X1029400Y18250D01*
X1030067Y18417D01*
X1030567Y18833D01*
X1031067Y19583D01*
G01X1033417Y18583D02*
X1034000Y19167D01*
X1034500Y19500D01*
X1035167Y19667D01*
X1035750Y19500D01*
X1036167Y19167D01*
X1036500Y18667D01*
X1036583Y18083D01*
X1036500Y17583D01*
X1036167Y17083D01*
X1035667Y16667D01*
X1035083Y16500D01*
X1034417Y16667D01*
X1033833Y17167D01*
X1033500Y17917D01*
X1033417Y18750D01*
X1033583Y19833D01*
X1033833Y20417D01*
X1034250Y21000D01*
X1034833Y21417D01*
X1035417Y21500D01*
X1036000Y21333D01*
X1036417Y20917D01*
G01X1040183Y14833D02*
X1039350Y15667D01*
X1038933Y16500D01*
Y19833D01*
X1039350Y20667D01*
X1040183Y21500D01*
G01X1044367Y16500D02*
Y21500D01*
X1046033D01*
X1046700Y21250D01*
X1047200Y20917D01*
X1047617Y20417D01*
X1047950Y19833D01*
X1048033Y19000D01*
X1047950Y18167D01*
X1047617Y17583D01*
X1047200Y17083D01*
X1046700Y16750D01*
X1046033Y16500D01*
X1044367D01*
G01X1051800D02*
Y21500D01*
X1050800Y20500D01*
G01Y16500D02*
X1052800D01*
G01X1055817Y18583D02*
X1056400Y19167D01*
X1056900Y19500D01*
X1057567Y19667D01*
X1058150Y19500D01*
X1058567Y19167D01*
X1058900Y18667D01*
X1058983Y18083D01*
X1058900Y17583D01*
X1058567Y17083D01*
X1058067Y16667D01*
X1057483Y16500D01*
X1056817Y16667D01*
X1056233Y17167D01*
X1055900Y17917D01*
X1055817Y18750D01*
X1055983Y19833D01*
X1056233Y20417D01*
X1056650Y21000D01*
X1057233Y21417D01*
X1057817Y21500D01*
X1058400Y21333D01*
X1058817Y20917D01*
G01X1061250Y16500D02*
X1064750Y21500D01*
G01X1061250D02*
X1064750Y16500D01*
G01X1069600D02*
Y21500D01*
X1066517Y17917D01*
X1070683D01*
G01X1074617Y14833D02*
X1075450Y15667D01*
X1075867Y16500D01*
Y19833D01*
X1075450Y20667D01*
X1074617Y21500D01*
G01X977333Y65500D02*
Y70500D01*
X979417D01*
X980083Y70250D01*
X980500Y69917D01*
X980667Y69250D01*
X980500Y68583D01*
X980000Y68167D01*
X979417Y67917D01*
X977333D01*
G01X979417D02*
X980667Y65500D01*
G01X986267D02*
X982933D01*
Y70500D01*
X986267D01*
G01X984933Y68083D02*
X982933D01*
G01X992033Y70083D02*
X991533Y70333D01*
X990950Y70500D01*
X990283D01*
X989533Y70250D01*
X988950Y69833D01*
X988533Y69333D01*
X988200Y68500D01*
X988117Y67750D01*
X988283Y67000D01*
X988533Y66500D01*
X989033Y66000D01*
X989617Y65667D01*
X990200Y65500D01*
X990783D01*
X991367Y65667D01*
X991867Y65917D01*
X992283Y66250D01*
G01X995800Y70500D02*
Y65500D01*
G01X993883Y70500D02*
X997717D01*
G01X999317Y65500D02*
X1001400Y70500D01*
X1003483Y65500D01*
G01X1002733Y67250D02*
X1000067D01*
G01X1005083Y65500D02*
Y70500D01*
X1008917Y65500D01*
Y70500D01*
G01X1013100Y68000D02*
X1014767D01*
Y66500D01*
X1014267Y66000D01*
X1013683Y65667D01*
X1012850Y65500D01*
X1012017Y65667D01*
X1011433Y66000D01*
X1010933Y66500D01*
X1010600Y67083D01*
X1010433Y67750D01*
Y68333D01*
X1010600Y68833D01*
X1010933Y69417D01*
X1011433Y69917D01*
X1011933Y70250D01*
X1012600Y70500D01*
X1013183D01*
X1013850Y70333D01*
X1014350Y70000D01*
G01X1016533Y70500D02*
Y65500D01*
X1019867D01*
G01X1025467D02*
X1022133D01*
Y70500D01*
X1025467D01*
G01X1024133Y68083D02*
X1022133D01*
G01X1033167Y65500D02*
Y70500D01*
X1034833D01*
X1035500Y70250D01*
X1036000Y69917D01*
X1036417Y69417D01*
X1036750Y68833D01*
X1036833Y68000D01*
X1036750Y67167D01*
X1036417Y66583D01*
X1036000Y66083D01*
X1035500Y65750D01*
X1034833Y65500D01*
X1033167D01*
G01X1038933D02*
Y70500D01*
X1041017D01*
X1041683Y70250D01*
X1042100Y69917D01*
X1042267Y69250D01*
X1042100Y68583D01*
X1041600Y68167D01*
X1041017Y67917D01*
X1038933D01*
G01X1041017D02*
X1042267Y65500D01*
G01X1045200Y70500D02*
X1047200D01*
G01X1046200D02*
Y65500D01*
G01X1045200D02*
X1047200D01*
G01X1050133Y70500D02*
Y65500D01*
X1053467D01*
G01X1055733Y70500D02*
Y65500D01*
X1059067D01*
G01X1066850D02*
Y70500D01*
G01X1070350D02*
Y65500D01*
G01Y68000D02*
X1066850D01*
G01X1074200Y65500D02*
X1073533Y65583D01*
X1072950Y65917D01*
X1072450Y66417D01*
X1072117Y67000D01*
X1071950Y67667D01*
Y68333D01*
X1072117Y69000D01*
X1072450Y69583D01*
X1072950Y70083D01*
X1073533Y70417D01*
X1074200Y70500D01*
X1074867Y70417D01*
X1075450Y70083D01*
X1075950Y69583D01*
X1076283Y69000D01*
X1076450Y68333D01*
Y67667D01*
X1076283Y67000D01*
X1075950Y66417D01*
X1075450Y65917D01*
X1074867Y65583D01*
X1074200Y65500D01*
G01X1078133Y70500D02*
Y65500D01*
X1081467D01*
G01X1087067D02*
X1083733D01*
Y70500D01*
X1087067D01*
G01X1085733Y68083D02*
X1083733D01*
G01X1094767Y65500D02*
Y70500D01*
X1096433D01*
X1097100Y70250D01*
X1097600Y69917D01*
X1098017Y69417D01*
X1098350Y68833D01*
X1098433Y68000D01*
X1098350Y67167D01*
X1098017Y66583D01*
X1097600Y66083D01*
X1097100Y65750D01*
X1096433Y65500D01*
X1094767D01*
G01X1103867D02*
X1100533D01*
Y70500D01*
X1103867D01*
G01X1102533Y68083D02*
X1100533D01*
G01X1106217Y65500D02*
Y70500D01*
X1109383D01*
G01X1108217Y68083D02*
X1106217D01*
G01X1112400Y70500D02*
X1114400D01*
G01X1113400D02*
Y65500D01*
G01X1112400D02*
X1114400D01*
G01X1117083D02*
Y70500D01*
X1120917Y65500D01*
Y70500D01*
G01X1126267Y65500D02*
X1122933D01*
Y70500D01*
X1126267D01*
G01X1124933Y68083D02*
X1122933D01*
G01X956000Y795980D02*
Y790980D01*
G01X954083Y795980D02*
X957917D01*
G01X959517Y794313D02*
X960517Y790980D01*
X961600Y794313D01*
X962683Y790980D01*
X963683Y794313D01*
G01X967200D02*
Y790980D01*
G01Y795647D02*
X967033Y795730D01*
Y795897D01*
X967200Y795980D01*
X967367Y795897D01*
Y795730D01*
X967200Y795647D01*
G01X971550Y791563D02*
X971967Y791230D01*
X972550Y790980D01*
X973050D01*
X973550Y791147D01*
X973883Y791397D01*
X974050Y791730D01*
X973967Y792230D01*
X973633Y792480D01*
X972133Y792980D01*
X971800Y793563D01*
X971967Y793980D01*
X972300Y794230D01*
X972800Y794313D01*
X973300Y794230D01*
X973800Y793980D01*
G01X978400Y795980D02*
Y790980D01*
G01X977233Y794313D02*
X979567D01*
G01X991100Y790980D02*
Y794313D01*
G01Y793730D02*
X990767Y794063D01*
X990267Y794230D01*
X989683Y794313D01*
X989100Y794147D01*
X988600Y793813D01*
X988267Y793313D01*
X988100Y792647D01*
X988267Y791980D01*
X988600Y791480D01*
X989100Y791147D01*
X989683Y790980D01*
X990267Y791063D01*
X990767Y791313D01*
X991100Y791647D01*
G01X993783Y790980D02*
Y794313D01*
G01Y793480D02*
X994117Y793897D01*
X994617Y794230D01*
X995283Y794313D01*
X995867Y794230D01*
X996367Y793897D01*
X996617Y793313D01*
Y790980D01*
G01X1002300Y795980D02*
Y790980D01*
G01Y791730D02*
X1001967Y791313D01*
X1001467Y791063D01*
X1000883Y790980D01*
X1000217Y791147D01*
X999717Y791563D01*
X999383Y792063D01*
X999300Y792647D01*
X999383Y793230D01*
X999717Y793730D01*
X1000217Y794147D01*
X1000883Y794313D01*
X1001467Y794230D01*
X1001883Y794063D01*
X1002300Y793730D01*
G01X1010500Y790980D02*
Y795980D01*
G01Y793480D02*
X1010917Y793980D01*
X1011417Y794230D01*
X1011917Y794313D01*
X1012667Y794147D01*
X1013167Y793813D01*
X1013500Y793230D01*
Y792563D01*
X1013333Y791897D01*
X1013000Y791397D01*
X1012417Y791063D01*
X1011917Y790980D01*
X1011417Y791063D01*
X1010917Y791313D01*
X1010500Y791730D01*
G01X1017600Y790980D02*
X1017100Y791063D01*
X1016600Y791397D01*
X1016267Y791980D01*
X1016100Y792647D01*
X1016267Y793313D01*
X1016600Y793897D01*
X1017100Y794230D01*
X1017600Y794313D01*
X1018100Y794230D01*
X1018600Y793897D01*
X1018933Y793313D01*
X1019017Y792647D01*
X1018933Y791980D01*
X1018600Y791397D01*
X1018100Y791063D01*
X1017600Y790980D01*
G01X1021117Y794313D02*
X1022117Y790980D01*
X1023200Y794313D01*
X1024283Y790980D01*
X1025283Y794313D01*
G01X957500Y811500D02*
X959167D01*
Y810000D01*
X958667Y809500D01*
X958083Y809167D01*
X957250Y809000D01*
X956417Y809167D01*
X955833Y809500D01*
X955333Y810000D01*
X955000Y810583D01*
X954833Y811250D01*
Y811833D01*
X955000Y812333D01*
X955333Y812917D01*
X955833Y813417D01*
X956333Y813750D01*
X957000Y814000D01*
X957583D01*
X958250Y813833D01*
X958750Y813500D01*
G01X961100Y808833D02*
X964100Y814000D01*
G01X966617Y809000D02*
Y814000D01*
X969783D01*
G01X968617Y811583D02*
X966617D01*
G01X977650Y809667D02*
X978317Y809250D01*
X979067Y809000D01*
X979733D01*
X980400Y809250D01*
X980900Y809667D01*
X981150Y810250D01*
X980983Y810833D01*
X980567Y811333D01*
X979817Y811667D01*
X978817Y811833D01*
X978233Y812167D01*
X977983Y812750D01*
X978150Y813333D01*
X978567Y813750D01*
X979150Y814000D01*
X979733D01*
X980317Y813833D01*
X980817Y813417D01*
G01X985000Y809000D02*
Y814000D01*
G01X990600Y809000D02*
X990100Y809083D01*
X989600Y809417D01*
X989267Y810000D01*
X989100Y810667D01*
X989267Y811333D01*
X989600Y811917D01*
X990100Y812250D01*
X990600Y812333D01*
X991100Y812250D01*
X991600Y811917D01*
X991933Y811333D01*
X992017Y810667D01*
X991933Y810000D01*
X991600Y809417D01*
X991100Y809083D01*
X990600Y809000D01*
G01X996200Y814000D02*
Y809000D01*
G01X995033Y812333D02*
X997367D01*
G01X955750Y826250D02*
X958417D01*
X958167Y826833D01*
X957750Y827167D01*
X957167Y827333D01*
X956583Y827250D01*
X956083Y827000D01*
X955750Y826417D01*
X955583Y825917D01*
Y825417D01*
X955750Y824917D01*
X956167Y824417D01*
X956667Y824083D01*
X957250Y824000D01*
X957833Y824167D01*
X958417Y824667D01*
G01X964100Y829000D02*
Y824000D01*
G01Y824750D02*
X963767Y824333D01*
X963267Y824083D01*
X962683Y824000D01*
X962017Y824167D01*
X961517Y824583D01*
X961183Y825083D01*
X961100Y825667D01*
X961183Y826250D01*
X961517Y826750D01*
X962017Y827167D01*
X962683Y827333D01*
X963267Y827250D01*
X963683Y827083D01*
X964100Y826750D01*
G01X967033Y822750D02*
X967617Y822417D01*
X968283Y822333D01*
X968867Y822417D01*
X969367Y822833D01*
X969700Y823417D01*
Y827333D01*
G01Y826667D02*
X969367Y827000D01*
X968867Y827250D01*
X968283Y827333D01*
X967617Y827167D01*
X967200Y826833D01*
X966867Y826250D01*
X966700Y825667D01*
X966783Y825167D01*
X967117Y824583D01*
X967617Y824167D01*
X968283Y824000D01*
X968783Y824083D01*
X969367Y824417D01*
X969700Y824750D01*
G01X972550Y826250D02*
X975217D01*
X974967Y826833D01*
X974550Y827167D01*
X973967Y827333D01*
X973383Y827250D01*
X972883Y827000D01*
X972550Y826417D01*
X972383Y825917D01*
Y825417D01*
X972550Y824917D01*
X972967Y824417D01*
X973467Y824083D01*
X974050Y824000D01*
X974633Y824167D01*
X975217Y824667D01*
G01X985000Y829000D02*
Y824000D01*
G01X983833Y827333D02*
X986167D01*
G01X990600Y824000D02*
X990100Y824083D01*
X989600Y824417D01*
X989267Y825000D01*
X989100Y825667D01*
X989267Y826333D01*
X989600Y826917D01*
X990100Y827250D01*
X990600Y827333D01*
X991100Y827250D01*
X991600Y826917D01*
X991933Y826333D01*
X992017Y825667D01*
X991933Y825000D01*
X991600Y824417D01*
X991100Y824083D01*
X990600Y824000D01*
G01X1000383D02*
Y829000D01*
G01Y826583D02*
X1000800Y827000D01*
X1001217Y827250D01*
X1001883Y827333D01*
X1002383Y827250D01*
X1002967Y826917D01*
X1003217Y826417D01*
Y824000D01*
G01X1007400D02*
X1006900Y824083D01*
X1006400Y824417D01*
X1006067Y825000D01*
X1005900Y825667D01*
X1006067Y826333D01*
X1006400Y826917D01*
X1006900Y827250D01*
X1007400Y827333D01*
X1007900Y827250D01*
X1008400Y826917D01*
X1008733Y826333D01*
X1008817Y825667D01*
X1008733Y825000D01*
X1008400Y824417D01*
X1007900Y824083D01*
X1007400Y824000D01*
G01X1013000D02*
Y829000D01*
G01X1017350Y826250D02*
X1020017D01*
X1019767Y826833D01*
X1019350Y827167D01*
X1018767Y827333D01*
X1018183Y827250D01*
X1017683Y827000D01*
X1017350Y826417D01*
X1017183Y825917D01*
Y825417D01*
X1017350Y824917D01*
X1017767Y824417D01*
X1018267Y824083D01*
X1018850Y824000D01*
X1019433Y824167D01*
X1020017Y824667D01*
G01X955750Y842750D02*
X958417D01*
X958167Y843333D01*
X957750Y843667D01*
X957167Y843833D01*
X956583Y843750D01*
X956083Y843500D01*
X955750Y842917D01*
X955583Y842417D01*
Y841917D01*
X955750Y841417D01*
X956167Y840917D01*
X956667Y840583D01*
X957250Y840500D01*
X957833Y840667D01*
X958417Y841167D01*
G01X964100Y845500D02*
Y840500D01*
G01Y841250D02*
X963767Y840833D01*
X963267Y840583D01*
X962683Y840500D01*
X962017Y840667D01*
X961517Y841083D01*
X961183Y841583D01*
X961100Y842167D01*
X961183Y842750D01*
X961517Y843250D01*
X962017Y843667D01*
X962683Y843833D01*
X963267Y843750D01*
X963683Y843583D01*
X964100Y843250D01*
G01X967033Y839250D02*
X967617Y838917D01*
X968283Y838833D01*
X968867Y838917D01*
X969367Y839333D01*
X969700Y839917D01*
Y843833D01*
G01Y843167D02*
X969367Y843500D01*
X968867Y843750D01*
X968283Y843833D01*
X967617Y843667D01*
X967200Y843333D01*
X966867Y842750D01*
X966700Y842167D01*
X966783Y841667D01*
X967117Y841083D01*
X967617Y840667D01*
X968283Y840500D01*
X968783Y840583D01*
X969367Y840917D01*
X969700Y841250D01*
G01X972550Y842750D02*
X975217D01*
X974967Y843333D01*
X974550Y843667D01*
X973967Y843833D01*
X973383Y843750D01*
X972883Y843500D01*
X972550Y842917D01*
X972383Y842417D01*
Y841917D01*
X972550Y841417D01*
X972967Y840917D01*
X973467Y840583D01*
X974050Y840500D01*
X974633Y840667D01*
X975217Y841167D01*
G01X985000Y845500D02*
Y840500D01*
G01X983833Y843833D02*
X986167D01*
G01X990600Y840500D02*
X990100Y840583D01*
X989600Y840917D01*
X989267Y841500D01*
X989100Y842167D01*
X989267Y842833D01*
X989600Y843417D01*
X990100Y843750D01*
X990600Y843833D01*
X991100Y843750D01*
X991600Y843417D01*
X991933Y842833D01*
X992017Y842167D01*
X991933Y841500D01*
X991600Y840917D01*
X991100Y840583D01*
X990600Y840500D01*
G01X1000550Y842750D02*
X1003217D01*
X1002967Y843333D01*
X1002550Y843667D01*
X1001967Y843833D01*
X1001383Y843750D01*
X1000883Y843500D01*
X1000550Y842917D01*
X1000383Y842417D01*
Y841917D01*
X1000550Y841417D01*
X1000967Y840917D01*
X1001467Y840583D01*
X1002050Y840500D01*
X1002633Y840667D01*
X1003217Y841167D01*
G01X1008900Y845500D02*
Y840500D01*
G01Y841250D02*
X1008567Y840833D01*
X1008067Y840583D01*
X1007483Y840500D01*
X1006817Y840667D01*
X1006317Y841083D01*
X1005983Y841583D01*
X1005900Y842167D01*
X1005983Y842750D01*
X1006317Y843250D01*
X1006817Y843667D01*
X1007483Y843833D01*
X1008067Y843750D01*
X1008483Y843583D01*
X1008900Y843250D01*
G01X1011833Y839250D02*
X1012417Y838917D01*
X1013083Y838833D01*
X1013667Y838917D01*
X1014167Y839333D01*
X1014500Y839917D01*
Y843833D01*
G01Y843167D02*
X1014167Y843500D01*
X1013667Y843750D01*
X1013083Y843833D01*
X1012417Y843667D01*
X1012000Y843333D01*
X1011667Y842750D01*
X1011500Y842167D01*
X1011583Y841667D01*
X1011917Y841083D01*
X1012417Y840667D01*
X1013083Y840500D01*
X1013583Y840583D01*
X1014167Y840917D01*
X1014500Y841250D01*
G01X1017350Y842750D02*
X1020017D01*
X1019767Y843333D01*
X1019350Y843667D01*
X1018767Y843833D01*
X1018183Y843750D01*
X1017683Y843500D01*
X1017350Y842917D01*
X1017183Y842417D01*
Y841917D01*
X1017350Y841417D01*
X1017767Y840917D01*
X1018267Y840583D01*
X1018850Y840500D01*
X1019433Y840667D01*
X1020017Y841167D01*
G01X948000Y850610D02*
Y782110D01*
G01X948500Y819500D02*
X1343000D01*
G01X948500Y834500D02*
X1343000D01*
G01X1026000Y336000D02*
Y86000D01*
G01X1033500Y370500D02*
Y375500D01*
G01Y373000D02*
X1033917Y373500D01*
X1034417Y373750D01*
X1034917Y373833D01*
X1035667Y373667D01*
X1036167Y373333D01*
X1036500Y372750D01*
Y372083D01*
X1036333Y371417D01*
X1036000Y370917D01*
X1035417Y370583D01*
X1034917Y370500D01*
X1034417Y370583D01*
X1033917Y370833D01*
X1033500Y371250D01*
G01X1039183Y373833D02*
Y371500D01*
X1039517Y370917D01*
X1040017Y370583D01*
X1040600Y370500D01*
X1041183Y370583D01*
X1041683Y370917D01*
X1042017Y371500D01*
G01Y370500D02*
Y373833D01*
G01X1044700Y370500D02*
Y375500D01*
G01Y373000D02*
X1045117Y373500D01*
X1045617Y373750D01*
X1046117Y373833D01*
X1046867Y373667D01*
X1047367Y373333D01*
X1047700Y372750D01*
Y372083D01*
X1047533Y371417D01*
X1047200Y370917D01*
X1046617Y370583D01*
X1046117Y370500D01*
X1045617Y370583D01*
X1045117Y370833D01*
X1044700Y371250D01*
G01X1050300Y370500D02*
Y375500D01*
G01Y373000D02*
X1050717Y373500D01*
X1051217Y373750D01*
X1051717Y373833D01*
X1052467Y373667D01*
X1052967Y373333D01*
X1053300Y372750D01*
Y372083D01*
X1053133Y371417D01*
X1052800Y370917D01*
X1052217Y370583D01*
X1051717Y370500D01*
X1051217Y370583D01*
X1050717Y370833D01*
X1050300Y371250D01*
G01X1057400Y370500D02*
Y375500D01*
G01X1061750Y372750D02*
X1064417D01*
X1064167Y373333D01*
X1063750Y373667D01*
X1063167Y373833D01*
X1062583Y373750D01*
X1062083Y373500D01*
X1061750Y372917D01*
X1061583Y372417D01*
Y371917D01*
X1061750Y371417D01*
X1062167Y370917D01*
X1062667Y370583D01*
X1063250Y370500D01*
X1063833Y370667D01*
X1064417Y371167D01*
G01X1074200Y373833D02*
Y370500D01*
G01Y375167D02*
X1074033Y375250D01*
Y375417D01*
X1074200Y375500D01*
X1074367Y375417D01*
Y375250D01*
X1074200Y375167D01*
G01X1078383Y370500D02*
Y373833D01*
G01Y373000D02*
X1078717Y373417D01*
X1079217Y373750D01*
X1079883Y373833D01*
X1080467Y373750D01*
X1080967Y373417D01*
X1081217Y372833D01*
Y370500D01*
G01X1084150Y371083D02*
X1084567Y370750D01*
X1085150Y370500D01*
X1085650D01*
X1086150Y370667D01*
X1086483Y370917D01*
X1086650Y371250D01*
X1086567Y371750D01*
X1086233Y372000D01*
X1084733Y372500D01*
X1084400Y373083D01*
X1084567Y373500D01*
X1084900Y373750D01*
X1085400Y373833D01*
X1085900Y373750D01*
X1086400Y373500D01*
G01X1091000Y373833D02*
Y370500D01*
G01Y375167D02*
X1090833Y375250D01*
Y375417D01*
X1091000Y375500D01*
X1091167Y375417D01*
Y375250D01*
X1091000Y375167D01*
G01X1098100Y375500D02*
Y370500D01*
G01Y371250D02*
X1097767Y370833D01*
X1097267Y370583D01*
X1096683Y370500D01*
X1096017Y370667D01*
X1095517Y371083D01*
X1095183Y371583D01*
X1095100Y372167D01*
X1095183Y372750D01*
X1095517Y373250D01*
X1096017Y373667D01*
X1096683Y373833D01*
X1097267Y373750D01*
X1097683Y373583D01*
X1098100Y373250D01*
G01X1100950Y372750D02*
X1103617D01*
X1103367Y373333D01*
X1102950Y373667D01*
X1102367Y373833D01*
X1101783Y373750D01*
X1101283Y373500D01*
X1100950Y372917D01*
X1100783Y372417D01*
Y371917D01*
X1100950Y371417D01*
X1101367Y370917D01*
X1101867Y370583D01*
X1102450Y370500D01*
X1103033Y370667D01*
X1103617Y371167D01*
G01X1113400Y375500D02*
Y370500D01*
G01X1112233Y373833D02*
X1114567D01*
G01X1117583Y370500D02*
Y375500D01*
G01Y373083D02*
X1118000Y373500D01*
X1118417Y373750D01*
X1119083Y373833D01*
X1119583Y373750D01*
X1120167Y373417D01*
X1120417Y372917D01*
Y370500D01*
G01X1123350Y372750D02*
X1126017D01*
X1125767Y373333D01*
X1125350Y373667D01*
X1124767Y373833D01*
X1124183Y373750D01*
X1123683Y373500D01*
X1123350Y372917D01*
X1123183Y372417D01*
Y371917D01*
X1123350Y371417D01*
X1123767Y370917D01*
X1124267Y370583D01*
X1124850Y370500D01*
X1125433Y370667D01*
X1126017Y371167D01*
G01X1134633Y370500D02*
Y373833D01*
G01Y373167D02*
X1135050Y373500D01*
X1135467Y373750D01*
X1136050Y373833D01*
X1136467Y373750D01*
X1136967Y373500D01*
G01X1140150Y372750D02*
X1142817D01*
X1142567Y373333D01*
X1142150Y373667D01*
X1141567Y373833D01*
X1140983Y373750D01*
X1140483Y373500D01*
X1140150Y372917D01*
X1139983Y372417D01*
Y371917D01*
X1140150Y371417D01*
X1140567Y370917D01*
X1141067Y370583D01*
X1141650Y370500D01*
X1142233Y370667D01*
X1142817Y371167D01*
G01X1145750Y371083D02*
X1146167Y370750D01*
X1146750Y370500D01*
X1147250D01*
X1147750Y370667D01*
X1148083Y370917D01*
X1148250Y371250D01*
X1148167Y371750D01*
X1147833Y372000D01*
X1146333Y372500D01*
X1146000Y373083D01*
X1146167Y373500D01*
X1146500Y373750D01*
X1147000Y373833D01*
X1147500Y373750D01*
X1148000Y373500D01*
G01X1152600Y373833D02*
Y370500D01*
G01Y375167D02*
X1152433Y375250D01*
Y375417D01*
X1152600Y375500D01*
X1152767Y375417D01*
Y375250D01*
X1152600Y375167D01*
G01X1156783Y370500D02*
Y373833D01*
G01Y373000D02*
X1157117Y373417D01*
X1157617Y373750D01*
X1158283Y373833D01*
X1158867Y373750D01*
X1159367Y373417D01*
X1159617Y372833D01*
Y370500D01*
G01X1163800Y370333D02*
X1163633Y370417D01*
Y370583D01*
X1163800Y370667D01*
X1163967Y370583D01*
Y370417D01*
X1163800Y370333D01*
G01X1021417Y383667D02*
X1021917Y384167D01*
X1022500Y384417D01*
X1023167Y384500D01*
X1024000Y384333D01*
X1024583Y383917D01*
X1024750Y383417D01*
X1024667Y382917D01*
X1024333Y382500D01*
X1022667Y381667D01*
X1021917Y381083D01*
X1021417Y380250D01*
X1021250Y379500D01*
X1024750D01*
G01X1028600Y379333D02*
X1028433Y379417D01*
Y379583D01*
X1028600Y379667D01*
X1028767Y379583D01*
Y379417D01*
X1028600Y379333D01*
G01X1032117Y384500D02*
X1034200Y379500D01*
X1036283Y384500D01*
G01X1039800Y382833D02*
Y379500D01*
G01Y384167D02*
X1039633Y384250D01*
Y384417D01*
X1039800Y384500D01*
X1039967Y384417D01*
Y384250D01*
X1039800Y384167D01*
G01X1046900Y379500D02*
Y382833D01*
G01Y382250D02*
X1046567Y382583D01*
X1046067Y382750D01*
X1045483Y382833D01*
X1044900Y382667D01*
X1044400Y382333D01*
X1044067Y381833D01*
X1043900Y381167D01*
X1044067Y380500D01*
X1044400Y380000D01*
X1044900Y379667D01*
X1045483Y379500D01*
X1046067Y379583D01*
X1046567Y379833D01*
X1046900Y380167D01*
G01X1055350Y380083D02*
X1055767Y379750D01*
X1056350Y379500D01*
X1056850D01*
X1057350Y379667D01*
X1057683Y379917D01*
X1057850Y380250D01*
X1057767Y380750D01*
X1057433Y381000D01*
X1055933Y381500D01*
X1055600Y382083D01*
X1055767Y382500D01*
X1056100Y382750D01*
X1056600Y382833D01*
X1057100Y382750D01*
X1057600Y382500D01*
G01X1060783Y379500D02*
Y384500D01*
G01Y382083D02*
X1061200Y382500D01*
X1061617Y382750D01*
X1062283Y382833D01*
X1062783Y382750D01*
X1063367Y382417D01*
X1063617Y381917D01*
Y379500D01*
G01X1067800D02*
X1067300Y379583D01*
X1066800Y379917D01*
X1066467Y380500D01*
X1066300Y381167D01*
X1066467Y381833D01*
X1066800Y382417D01*
X1067300Y382750D01*
X1067800Y382833D01*
X1068300Y382750D01*
X1068800Y382417D01*
X1069133Y381833D01*
X1069217Y381167D01*
X1069133Y380500D01*
X1068800Y379917D01*
X1068300Y379583D01*
X1067800Y379500D01*
G01X1071983Y382833D02*
Y380500D01*
X1072317Y379917D01*
X1072817Y379583D01*
X1073400Y379500D01*
X1073983Y379583D01*
X1074483Y379917D01*
X1074817Y380500D01*
G01Y379500D02*
Y382833D01*
G01X1079000Y379500D02*
Y384500D01*
G01X1086100D02*
Y379500D01*
G01Y380250D02*
X1085767Y379833D01*
X1085267Y379583D01*
X1084683Y379500D01*
X1084017Y379667D01*
X1083517Y380083D01*
X1083183Y380583D01*
X1083100Y381167D01*
X1083183Y381750D01*
X1083517Y382250D01*
X1084017Y382667D01*
X1084683Y382833D01*
X1085267Y382750D01*
X1085683Y382583D01*
X1086100Y382250D01*
G01X1094300Y379500D02*
Y384500D01*
G01Y382000D02*
X1094717Y382500D01*
X1095217Y382750D01*
X1095717Y382833D01*
X1096467Y382667D01*
X1096967Y382333D01*
X1097300Y381750D01*
Y381083D01*
X1097133Y380417D01*
X1096800Y379917D01*
X1096217Y379583D01*
X1095717Y379500D01*
X1095217Y379583D01*
X1094717Y379833D01*
X1094300Y380250D01*
G01X1100150Y381750D02*
X1102817D01*
X1102567Y382333D01*
X1102150Y382667D01*
X1101567Y382833D01*
X1100983Y382750D01*
X1100483Y382500D01*
X1100150Y381917D01*
X1099983Y381417D01*
Y380917D01*
X1100150Y380417D01*
X1100567Y379917D01*
X1101067Y379583D01*
X1101650Y379500D01*
X1102233Y379667D01*
X1102817Y380167D01*
G01X1111100Y377833D02*
Y382833D01*
G01Y382083D02*
X1111517Y382500D01*
X1111933Y382750D01*
X1112600Y382833D01*
X1113183Y382750D01*
X1113767Y382333D01*
X1114017Y381750D01*
X1114100Y381167D01*
X1114017Y380583D01*
X1113767Y380000D01*
X1113267Y379667D01*
X1112600Y379500D01*
X1112017Y379583D01*
X1111433Y379833D01*
X1111100Y380167D01*
G01X1118200Y379500D02*
Y384500D01*
G01X1122383Y382833D02*
Y380500D01*
X1122717Y379917D01*
X1123217Y379583D01*
X1123800Y379500D01*
X1124383Y379583D01*
X1124883Y379917D01*
X1125217Y380500D01*
G01Y379500D02*
Y382833D01*
G01X1128233Y378250D02*
X1128817Y377917D01*
X1129483Y377833D01*
X1130067Y377917D01*
X1130567Y378333D01*
X1130900Y378917D01*
Y382833D01*
G01Y382167D02*
X1130567Y382500D01*
X1130067Y382750D01*
X1129483Y382833D01*
X1128817Y382667D01*
X1128400Y382333D01*
X1128067Y381750D01*
X1127900Y381167D01*
X1127983Y380667D01*
X1128317Y380083D01*
X1128817Y379667D01*
X1129483Y379500D01*
X1129983Y379583D01*
X1130567Y379917D01*
X1130900Y380250D01*
G01X1133833Y378250D02*
X1134417Y377917D01*
X1135083Y377833D01*
X1135667Y377917D01*
X1136167Y378333D01*
X1136500Y378917D01*
Y382833D01*
G01Y382167D02*
X1136167Y382500D01*
X1135667Y382750D01*
X1135083Y382833D01*
X1134417Y382667D01*
X1134000Y382333D01*
X1133667Y381750D01*
X1133500Y381167D01*
X1133583Y380667D01*
X1133917Y380083D01*
X1134417Y379667D01*
X1135083Y379500D01*
X1135583Y379583D01*
X1136167Y379917D01*
X1136500Y380250D01*
G01X1139350Y381750D02*
X1142017D01*
X1141767Y382333D01*
X1141350Y382667D01*
X1140767Y382833D01*
X1140183Y382750D01*
X1139683Y382500D01*
X1139350Y381917D01*
X1139183Y381417D01*
Y380917D01*
X1139350Y380417D01*
X1139767Y379917D01*
X1140267Y379583D01*
X1140850Y379500D01*
X1141433Y379667D01*
X1142017Y380167D01*
G01X1147700Y384500D02*
Y379500D01*
G01Y380250D02*
X1147367Y379833D01*
X1146867Y379583D01*
X1146283Y379500D01*
X1145617Y379667D01*
X1145117Y380083D01*
X1144783Y380583D01*
X1144700Y381167D01*
X1144783Y381750D01*
X1145117Y382250D01*
X1145617Y382667D01*
X1146283Y382833D01*
X1146867Y382750D01*
X1147283Y382583D01*
X1147700Y382250D01*
G01X1155317Y382833D02*
X1156317Y379500D01*
X1157400Y382833D01*
X1158483Y379500D01*
X1159483Y382833D01*
G01X1163000D02*
Y379500D01*
G01Y384167D02*
X1162833Y384250D01*
Y384417D01*
X1163000Y384500D01*
X1163167Y384417D01*
Y384250D01*
X1163000Y384167D01*
G01X1168600Y384500D02*
Y379500D01*
G01X1167433Y382833D02*
X1169767D01*
G01X1172783Y379500D02*
Y384500D01*
G01Y382083D02*
X1173200Y382500D01*
X1173617Y382750D01*
X1174283Y382833D01*
X1174783Y382750D01*
X1175367Y382417D01*
X1175617Y381917D01*
Y379500D01*
G01X1183733D02*
X1187067Y381167D01*
X1183733Y382833D01*
G01X1189583Y380083D02*
X1190167Y379667D01*
X1190833Y379500D01*
X1191500Y379667D01*
X1192083Y380167D01*
X1192500Y380917D01*
X1192667Y381667D01*
Y382583D01*
X1192500Y383333D01*
X1192083Y384000D01*
X1191583Y384333D01*
X1191000Y384500D01*
X1190333Y384333D01*
X1189833Y384000D01*
X1189500Y383500D01*
X1189333Y382833D01*
X1189500Y382250D01*
X1189917Y381667D01*
X1190417Y381333D01*
X1191000Y381250D01*
X1191667Y381417D01*
X1192167Y381833D01*
X1192667Y382583D01*
G01X1196600Y384500D02*
X1195933Y384333D01*
X1195433Y383917D01*
X1195100Y383417D01*
X1194850Y382750D01*
X1194767Y382000D01*
X1194850Y381250D01*
X1195100Y380583D01*
X1195433Y380083D01*
X1195933Y379667D01*
X1196600Y379500D01*
X1197267Y379667D01*
X1197767Y380083D01*
X1198100Y380583D01*
X1198350Y381250D01*
X1198433Y382000D01*
X1198350Y382750D01*
X1198100Y383417D01*
X1197767Y383917D01*
X1197267Y384333D01*
X1196600Y384500D01*
G01X1200700Y379333D02*
X1203700Y384500D01*
G01X1200700D02*
X1200200Y384333D01*
X1199950Y384083D01*
X1199783Y383583D01*
X1199950Y383083D01*
X1200200Y382833D01*
X1200700Y382667D01*
X1201200Y382833D01*
X1201450Y383083D01*
X1201617Y383583D01*
X1201450Y384083D01*
X1201200Y384333D01*
X1200700Y384500D01*
G01X1203700Y381167D02*
X1203200Y381000D01*
X1202950Y380750D01*
X1202783Y380250D01*
X1202950Y379750D01*
X1203200Y379500D01*
X1203700Y379333D01*
X1204200Y379500D01*
X1204450Y379750D01*
X1204617Y380250D01*
X1204450Y380750D01*
X1204200Y381000D01*
X1203700Y381167D01*
G01X1212233Y379500D02*
Y382833D01*
G01Y382167D02*
X1212650Y382500D01*
X1213067Y382750D01*
X1213650Y382833D01*
X1214067Y382750D01*
X1214567Y382500D01*
G01X1217750Y381750D02*
X1220417D01*
X1220167Y382333D01*
X1219750Y382667D01*
X1219167Y382833D01*
X1218583Y382750D01*
X1218083Y382500D01*
X1217750Y381917D01*
X1217583Y381417D01*
Y380917D01*
X1217750Y380417D01*
X1218167Y379917D01*
X1218667Y379583D01*
X1219250Y379500D01*
X1219833Y379667D01*
X1220417Y380167D01*
G01X1223350Y380083D02*
X1223767Y379750D01*
X1224350Y379500D01*
X1224850D01*
X1225350Y379667D01*
X1225683Y379917D01*
X1225850Y380250D01*
X1225767Y380750D01*
X1225433Y381000D01*
X1223933Y381500D01*
X1223600Y382083D01*
X1223767Y382500D01*
X1224100Y382750D01*
X1224600Y382833D01*
X1225100Y382750D01*
X1225600Y382500D01*
G01X1230200Y382833D02*
Y379500D01*
G01Y384167D02*
X1230033Y384250D01*
Y384417D01*
X1230200Y384500D01*
X1230367Y384417D01*
Y384250D01*
X1230200Y384167D01*
G01X1234383Y379500D02*
Y382833D01*
G01Y382000D02*
X1234717Y382417D01*
X1235217Y382750D01*
X1235883Y382833D01*
X1236467Y382750D01*
X1236967Y382417D01*
X1237217Y381833D01*
Y379500D01*
G01X1246417Y378000D02*
X1247583Y379167D01*
Y380333D01*
X1246417D01*
Y379167D01*
X1247583D01*
G01Y381167D02*
Y382333D01*
X1246417D01*
Y381167D01*
X1247583D01*
G01X1250767Y379500D02*
Y384500D01*
X1252433D01*
X1253100Y384250D01*
X1253600Y383917D01*
X1254017Y383417D01*
X1254350Y382833D01*
X1254433Y382000D01*
X1254350Y381167D01*
X1254017Y380583D01*
X1253600Y380083D01*
X1253100Y379750D01*
X1252433Y379500D01*
X1250767D01*
G01X1258200D02*
X1257700Y379583D01*
X1257200Y379917D01*
X1256867Y380500D01*
X1256700Y381167D01*
X1256867Y381833D01*
X1257200Y382417D01*
X1257700Y382750D01*
X1258200Y382833D01*
X1258700Y382750D01*
X1259200Y382417D01*
X1259533Y381833D01*
X1259617Y381167D01*
X1259533Y380500D01*
X1259200Y379917D01*
X1258700Y379583D01*
X1258200Y379500D01*
G01X1267983D02*
Y382833D01*
G01Y382000D02*
X1268317Y382417D01*
X1268817Y382750D01*
X1269483Y382833D01*
X1270067Y382750D01*
X1270567Y382417D01*
X1270817Y381833D01*
Y379500D01*
G01X1275000D02*
X1274500Y379583D01*
X1274000Y379917D01*
X1273667Y380500D01*
X1273500Y381167D01*
X1273667Y381833D01*
X1274000Y382417D01*
X1274500Y382750D01*
X1275000Y382833D01*
X1275500Y382750D01*
X1276000Y382417D01*
X1276333Y381833D01*
X1276417Y381167D01*
X1276333Y380500D01*
X1276000Y379917D01*
X1275500Y379583D01*
X1275000Y379500D01*
G01X1280600Y384500D02*
Y379500D01*
G01X1279433Y382833D02*
X1281767D01*
G01X1293300Y379500D02*
Y382833D01*
G01Y382250D02*
X1292967Y382583D01*
X1292467Y382750D01*
X1291883Y382833D01*
X1291300Y382667D01*
X1290800Y382333D01*
X1290467Y381833D01*
X1290300Y381167D01*
X1290467Y380500D01*
X1290800Y380000D01*
X1291300Y379667D01*
X1291883Y379500D01*
X1292467Y379583D01*
X1292967Y379833D01*
X1293300Y380167D01*
G01X1297400Y379500D02*
Y384500D01*
G01X1303000Y379500D02*
Y384500D01*
G01X1308600Y379500D02*
X1308100Y379583D01*
X1307600Y379917D01*
X1307267Y380500D01*
X1307100Y381167D01*
X1307267Y381833D01*
X1307600Y382417D01*
X1308100Y382750D01*
X1308600Y382833D01*
X1309100Y382750D01*
X1309600Y382417D01*
X1309933Y381833D01*
X1310017Y381167D01*
X1309933Y380500D01*
X1309600Y379917D01*
X1309100Y379583D01*
X1308600Y379500D01*
G01X1312117Y382833D02*
X1313117Y379500D01*
X1314200Y382833D01*
X1315283Y379500D01*
X1316283Y382833D01*
G01X1033500Y413500D02*
Y418500D01*
G01Y416000D02*
X1033917Y416500D01*
X1034417Y416750D01*
X1034917Y416833D01*
X1035667Y416667D01*
X1036167Y416333D01*
X1036500Y415750D01*
Y415083D01*
X1036333Y414417D01*
X1036000Y413917D01*
X1035417Y413583D01*
X1034917Y413500D01*
X1034417Y413583D01*
X1033917Y413833D01*
X1033500Y414250D01*
G01X1039183Y416833D02*
Y414500D01*
X1039517Y413917D01*
X1040017Y413583D01*
X1040600Y413500D01*
X1041183Y413583D01*
X1041683Y413917D01*
X1042017Y414500D01*
G01Y413500D02*
Y416833D01*
G01X1044700Y413500D02*
Y418500D01*
G01Y416000D02*
X1045117Y416500D01*
X1045617Y416750D01*
X1046117Y416833D01*
X1046867Y416667D01*
X1047367Y416333D01*
X1047700Y415750D01*
Y415083D01*
X1047533Y414417D01*
X1047200Y413917D01*
X1046617Y413583D01*
X1046117Y413500D01*
X1045617Y413583D01*
X1045117Y413833D01*
X1044700Y414250D01*
G01X1050300Y413500D02*
Y418500D01*
G01Y416000D02*
X1050717Y416500D01*
X1051217Y416750D01*
X1051717Y416833D01*
X1052467Y416667D01*
X1052967Y416333D01*
X1053300Y415750D01*
Y415083D01*
X1053133Y414417D01*
X1052800Y413917D01*
X1052217Y413583D01*
X1051717Y413500D01*
X1051217Y413583D01*
X1050717Y413833D01*
X1050300Y414250D01*
G01X1057400Y413500D02*
Y418500D01*
G01X1061750Y415750D02*
X1064417D01*
X1064167Y416333D01*
X1063750Y416667D01*
X1063167Y416833D01*
X1062583Y416750D01*
X1062083Y416500D01*
X1061750Y415917D01*
X1061583Y415417D01*
Y414917D01*
X1061750Y414417D01*
X1062167Y413917D01*
X1062667Y413583D01*
X1063250Y413500D01*
X1063833Y413667D01*
X1064417Y414167D01*
G01X1074200Y416833D02*
Y413500D01*
G01Y418167D02*
X1074033Y418250D01*
Y418417D01*
X1074200Y418500D01*
X1074367Y418417D01*
Y418250D01*
X1074200Y418167D01*
G01X1078383Y413500D02*
Y416833D01*
G01Y416000D02*
X1078717Y416417D01*
X1079217Y416750D01*
X1079883Y416833D01*
X1080467Y416750D01*
X1080967Y416417D01*
X1081217Y415833D01*
Y413500D01*
G01X1084150Y414083D02*
X1084567Y413750D01*
X1085150Y413500D01*
X1085650D01*
X1086150Y413667D01*
X1086483Y413917D01*
X1086650Y414250D01*
X1086567Y414750D01*
X1086233Y415000D01*
X1084733Y415500D01*
X1084400Y416083D01*
X1084567Y416500D01*
X1084900Y416750D01*
X1085400Y416833D01*
X1085900Y416750D01*
X1086400Y416500D01*
G01X1091000Y416833D02*
Y413500D01*
G01Y418167D02*
X1090833Y418250D01*
Y418417D01*
X1091000Y418500D01*
X1091167Y418417D01*
Y418250D01*
X1091000Y418167D01*
G01X1098100Y418500D02*
Y413500D01*
G01Y414250D02*
X1097767Y413833D01*
X1097267Y413583D01*
X1096683Y413500D01*
X1096017Y413667D01*
X1095517Y414083D01*
X1095183Y414583D01*
X1095100Y415167D01*
X1095183Y415750D01*
X1095517Y416250D01*
X1096017Y416667D01*
X1096683Y416833D01*
X1097267Y416750D01*
X1097683Y416583D01*
X1098100Y416250D01*
G01X1100950Y415750D02*
X1103617D01*
X1103367Y416333D01*
X1102950Y416667D01*
X1102367Y416833D01*
X1101783Y416750D01*
X1101283Y416500D01*
X1100950Y415917D01*
X1100783Y415417D01*
Y414917D01*
X1100950Y414417D01*
X1101367Y413917D01*
X1101867Y413583D01*
X1102450Y413500D01*
X1103033Y413667D01*
X1103617Y414167D01*
G01X1113400Y418500D02*
Y413500D01*
G01X1112233Y416833D02*
X1114567D01*
G01X1117583Y413500D02*
Y418500D01*
G01Y416083D02*
X1118000Y416500D01*
X1118417Y416750D01*
X1119083Y416833D01*
X1119583Y416750D01*
X1120167Y416417D01*
X1120417Y415917D01*
Y413500D01*
G01X1123350Y415750D02*
X1126017D01*
X1125767Y416333D01*
X1125350Y416667D01*
X1124767Y416833D01*
X1124183Y416750D01*
X1123683Y416500D01*
X1123350Y415917D01*
X1123183Y415417D01*
Y414917D01*
X1123350Y414417D01*
X1123767Y413917D01*
X1124267Y413583D01*
X1124850Y413500D01*
X1125433Y413667D01*
X1126017Y414167D01*
G01X1134633Y413500D02*
Y416833D01*
G01Y416167D02*
X1135050Y416500D01*
X1135467Y416750D01*
X1136050Y416833D01*
X1136467Y416750D01*
X1136967Y416500D01*
G01X1140150Y415750D02*
X1142817D01*
X1142567Y416333D01*
X1142150Y416667D01*
X1141567Y416833D01*
X1140983Y416750D01*
X1140483Y416500D01*
X1140150Y415917D01*
X1139983Y415417D01*
Y414917D01*
X1140150Y414417D01*
X1140567Y413917D01*
X1141067Y413583D01*
X1141650Y413500D01*
X1142233Y413667D01*
X1142817Y414167D01*
G01X1145750Y414083D02*
X1146167Y413750D01*
X1146750Y413500D01*
X1147250D01*
X1147750Y413667D01*
X1148083Y413917D01*
X1148250Y414250D01*
X1148167Y414750D01*
X1147833Y415000D01*
X1146333Y415500D01*
X1146000Y416083D01*
X1146167Y416500D01*
X1146500Y416750D01*
X1147000Y416833D01*
X1147500Y416750D01*
X1148000Y416500D01*
G01X1152600Y416833D02*
Y413500D01*
G01Y418167D02*
X1152433Y418250D01*
Y418417D01*
X1152600Y418500D01*
X1152767Y418417D01*
Y418250D01*
X1152600Y418167D01*
G01X1156783Y413500D02*
Y416833D01*
G01Y416000D02*
X1157117Y416417D01*
X1157617Y416750D01*
X1158283Y416833D01*
X1158867Y416750D01*
X1159367Y416417D01*
X1159617Y415833D01*
Y413500D01*
G01X1163800Y413333D02*
X1163633Y413417D01*
Y413583D01*
X1163800Y413667D01*
X1163967Y413583D01*
Y413417D01*
X1163800Y413333D01*
G01X1023000Y390000D02*
Y395000D01*
X1022000Y394000D01*
G01Y390000D02*
X1024000D01*
G01X1028600Y389833D02*
X1028433Y389917D01*
Y390083D01*
X1028600Y390167D01*
X1028767Y390083D01*
Y389917D01*
X1028600Y389833D01*
G01X1032367Y390000D02*
Y395000D01*
X1034033D01*
X1034700Y394750D01*
X1035200Y394417D01*
X1035617Y393917D01*
X1035950Y393333D01*
X1036033Y392500D01*
X1035950Y391667D01*
X1035617Y391083D01*
X1035200Y390583D01*
X1034700Y390250D01*
X1034033Y390000D01*
X1032367D01*
G01X1039800Y393333D02*
Y390000D01*
G01Y394667D02*
X1039633Y394750D01*
Y394917D01*
X1039800Y395000D01*
X1039967Y394917D01*
Y394750D01*
X1039800Y394667D01*
G01X1042900Y390000D02*
Y393333D01*
G01Y392417D02*
X1043150Y392833D01*
X1043567Y393167D01*
X1044150Y393333D01*
X1044733Y393167D01*
X1045150Y392833D01*
X1045400Y392417D01*
Y390000D01*
G01Y392417D02*
X1045650Y392833D01*
X1046067Y393167D01*
X1046650Y393333D01*
X1047233Y393167D01*
X1047650Y392833D01*
X1047900Y392333D01*
Y390000D01*
G01X1049500Y388333D02*
Y393333D01*
G01Y392583D02*
X1049917Y393000D01*
X1050333Y393250D01*
X1051000Y393333D01*
X1051583Y393250D01*
X1052167Y392833D01*
X1052417Y392250D01*
X1052500Y391667D01*
X1052417Y391083D01*
X1052167Y390500D01*
X1051667Y390167D01*
X1051000Y390000D01*
X1050417Y390083D01*
X1049833Y390333D01*
X1049500Y390667D01*
G01X1056600Y390000D02*
Y395000D01*
G01X1060950Y392250D02*
X1063617D01*
X1063367Y392833D01*
X1062950Y393167D01*
X1062367Y393333D01*
X1061783Y393250D01*
X1061283Y393000D01*
X1060950Y392417D01*
X1060783Y391917D01*
Y391417D01*
X1060950Y390917D01*
X1061367Y390417D01*
X1061867Y390083D01*
X1062450Y390000D01*
X1063033Y390167D01*
X1063617Y390667D01*
G01X1075067Y390000D02*
X1071733Y391667D01*
X1075067Y393333D01*
G01X1084600Y390000D02*
Y395000D01*
X1083600Y394000D01*
G01Y390000D02*
X1085600D01*
G01X1093300D02*
Y393333D01*
G01Y392417D02*
X1093550Y392833D01*
X1093967Y393167D01*
X1094550Y393333D01*
X1095133Y393167D01*
X1095550Y392833D01*
X1095800Y392417D01*
Y390000D01*
G01Y392417D02*
X1096050Y392833D01*
X1096467Y393167D01*
X1097050Y393333D01*
X1097633Y393167D01*
X1098050Y392833D01*
X1098300Y392333D01*
Y390000D01*
G01X1101400Y393333D02*
Y390000D01*
G01Y394667D02*
X1101233Y394750D01*
Y394917D01*
X1101400Y395000D01*
X1101567Y394917D01*
Y394750D01*
X1101400Y394667D01*
G01X1107000Y390000D02*
Y395000D01*
G01X1117617Y388500D02*
X1118783Y389667D01*
Y390833D01*
X1117617D01*
Y389667D01*
X1118783D01*
G01Y391667D02*
Y392833D01*
X1117617D01*
Y391667D01*
X1118783D01*
G01X1016000Y604500D02*
Y366000D01*
G01X1023000Y424000D02*
Y429000D01*
X1022000Y428000D01*
G01Y424000D02*
X1024000D01*
G01X1028600Y423833D02*
X1028433Y423917D01*
Y424083D01*
X1028600Y424167D01*
X1028767Y424083D01*
Y423917D01*
X1028600Y423833D01*
G01X1032117Y429000D02*
X1034200Y424000D01*
X1036283Y429000D01*
G01X1039800Y427333D02*
Y424000D01*
G01Y428667D02*
X1039633Y428750D01*
Y428917D01*
X1039800Y429000D01*
X1039967Y428917D01*
Y428750D01*
X1039800Y428667D01*
G01X1046900Y424000D02*
Y427333D01*
G01Y426750D02*
X1046567Y427083D01*
X1046067Y427250D01*
X1045483Y427333D01*
X1044900Y427167D01*
X1044400Y426833D01*
X1044067Y426333D01*
X1043900Y425667D01*
X1044067Y425000D01*
X1044400Y424500D01*
X1044900Y424167D01*
X1045483Y424000D01*
X1046067Y424083D01*
X1046567Y424333D01*
X1046900Y424667D01*
G01X1055350Y424583D02*
X1055767Y424250D01*
X1056350Y424000D01*
X1056850D01*
X1057350Y424167D01*
X1057683Y424417D01*
X1057850Y424750D01*
X1057767Y425250D01*
X1057433Y425500D01*
X1055933Y426000D01*
X1055600Y426583D01*
X1055767Y427000D01*
X1056100Y427250D01*
X1056600Y427333D01*
X1057100Y427250D01*
X1057600Y427000D01*
G01X1060783Y424000D02*
Y429000D01*
G01Y426583D02*
X1061200Y427000D01*
X1061617Y427250D01*
X1062283Y427333D01*
X1062783Y427250D01*
X1063367Y426917D01*
X1063617Y426417D01*
Y424000D01*
G01X1067800D02*
X1067300Y424083D01*
X1066800Y424417D01*
X1066467Y425000D01*
X1066300Y425667D01*
X1066467Y426333D01*
X1066800Y426917D01*
X1067300Y427250D01*
X1067800Y427333D01*
X1068300Y427250D01*
X1068800Y426917D01*
X1069133Y426333D01*
X1069217Y425667D01*
X1069133Y425000D01*
X1068800Y424417D01*
X1068300Y424083D01*
X1067800Y424000D01*
G01X1071983Y427333D02*
Y425000D01*
X1072317Y424417D01*
X1072817Y424083D01*
X1073400Y424000D01*
X1073983Y424083D01*
X1074483Y424417D01*
X1074817Y425000D01*
G01Y424000D02*
Y427333D01*
G01X1079000Y424000D02*
Y429000D01*
G01X1086100D02*
Y424000D01*
G01Y424750D02*
X1085767Y424333D01*
X1085267Y424083D01*
X1084683Y424000D01*
X1084017Y424167D01*
X1083517Y424583D01*
X1083183Y425083D01*
X1083100Y425667D01*
X1083183Y426250D01*
X1083517Y426750D01*
X1084017Y427167D01*
X1084683Y427333D01*
X1085267Y427250D01*
X1085683Y427083D01*
X1086100Y426750D01*
G01X1094300Y424000D02*
Y429000D01*
G01Y426500D02*
X1094717Y427000D01*
X1095217Y427250D01*
X1095717Y427333D01*
X1096467Y427167D01*
X1096967Y426833D01*
X1097300Y426250D01*
Y425583D01*
X1097133Y424917D01*
X1096800Y424417D01*
X1096217Y424083D01*
X1095717Y424000D01*
X1095217Y424083D01*
X1094717Y424333D01*
X1094300Y424750D01*
G01X1100150Y426250D02*
X1102817D01*
X1102567Y426833D01*
X1102150Y427167D01*
X1101567Y427333D01*
X1100983Y427250D01*
X1100483Y427000D01*
X1100150Y426417D01*
X1099983Y425917D01*
Y425417D01*
X1100150Y424917D01*
X1100567Y424417D01*
X1101067Y424083D01*
X1101650Y424000D01*
X1102233Y424167D01*
X1102817Y424667D01*
G01X1111100Y422333D02*
Y427333D01*
G01Y426583D02*
X1111517Y427000D01*
X1111933Y427250D01*
X1112600Y427333D01*
X1113183Y427250D01*
X1113767Y426833D01*
X1114017Y426250D01*
X1114100Y425667D01*
X1114017Y425083D01*
X1113767Y424500D01*
X1113267Y424167D01*
X1112600Y424000D01*
X1112017Y424083D01*
X1111433Y424333D01*
X1111100Y424667D01*
G01X1118200Y424000D02*
Y429000D01*
G01X1122383Y427333D02*
Y425000D01*
X1122717Y424417D01*
X1123217Y424083D01*
X1123800Y424000D01*
X1124383Y424083D01*
X1124883Y424417D01*
X1125217Y425000D01*
G01Y424000D02*
Y427333D01*
G01X1128233Y422750D02*
X1128817Y422417D01*
X1129483Y422333D01*
X1130067Y422417D01*
X1130567Y422833D01*
X1130900Y423417D01*
Y427333D01*
G01Y426667D02*
X1130567Y427000D01*
X1130067Y427250D01*
X1129483Y427333D01*
X1128817Y427167D01*
X1128400Y426833D01*
X1128067Y426250D01*
X1127900Y425667D01*
X1127983Y425167D01*
X1128317Y424583D01*
X1128817Y424167D01*
X1129483Y424000D01*
X1129983Y424083D01*
X1130567Y424417D01*
X1130900Y424750D01*
G01X1133833Y422750D02*
X1134417Y422417D01*
X1135083Y422333D01*
X1135667Y422417D01*
X1136167Y422833D01*
X1136500Y423417D01*
Y427333D01*
G01Y426667D02*
X1136167Y427000D01*
X1135667Y427250D01*
X1135083Y427333D01*
X1134417Y427167D01*
X1134000Y426833D01*
X1133667Y426250D01*
X1133500Y425667D01*
X1133583Y425167D01*
X1133917Y424583D01*
X1134417Y424167D01*
X1135083Y424000D01*
X1135583Y424083D01*
X1136167Y424417D01*
X1136500Y424750D01*
G01X1139350Y426250D02*
X1142017D01*
X1141767Y426833D01*
X1141350Y427167D01*
X1140767Y427333D01*
X1140183Y427250D01*
X1139683Y427000D01*
X1139350Y426417D01*
X1139183Y425917D01*
Y425417D01*
X1139350Y424917D01*
X1139767Y424417D01*
X1140267Y424083D01*
X1140850Y424000D01*
X1141433Y424167D01*
X1142017Y424667D01*
G01X1147700Y429000D02*
Y424000D01*
G01Y424750D02*
X1147367Y424333D01*
X1146867Y424083D01*
X1146283Y424000D01*
X1145617Y424167D01*
X1145117Y424583D01*
X1144783Y425083D01*
X1144700Y425667D01*
X1144783Y426250D01*
X1145117Y426750D01*
X1145617Y427167D01*
X1146283Y427333D01*
X1146867Y427250D01*
X1147283Y427083D01*
X1147700Y426750D01*
G01X1155317Y427333D02*
X1156317Y424000D01*
X1157400Y427333D01*
X1158483Y424000D01*
X1159483Y427333D01*
G01X1163000D02*
Y424000D01*
G01Y428667D02*
X1162833Y428750D01*
Y428917D01*
X1163000Y429000D01*
X1163167Y428917D01*
Y428750D01*
X1163000Y428667D01*
G01X1168600Y429000D02*
Y424000D01*
G01X1167433Y427333D02*
X1169767D01*
G01X1172783Y424000D02*
Y429000D01*
G01Y426583D02*
X1173200Y427000D01*
X1173617Y427250D01*
X1174283Y427333D01*
X1174783Y427250D01*
X1175367Y426917D01*
X1175617Y426417D01*
Y424000D01*
G01X1183733D02*
X1187067Y425667D01*
X1183733Y427333D01*
G01X1189583Y424583D02*
X1190167Y424167D01*
X1190833Y424000D01*
X1191500Y424167D01*
X1192083Y424667D01*
X1192500Y425417D01*
X1192667Y426167D01*
Y427083D01*
X1192500Y427833D01*
X1192083Y428500D01*
X1191583Y428833D01*
X1191000Y429000D01*
X1190333Y428833D01*
X1189833Y428500D01*
X1189500Y428000D01*
X1189333Y427333D01*
X1189500Y426750D01*
X1189917Y426167D01*
X1190417Y425833D01*
X1191000Y425750D01*
X1191667Y425917D01*
X1192167Y426333D01*
X1192667Y427083D01*
G01X1196600Y429000D02*
X1195933Y428833D01*
X1195433Y428417D01*
X1195100Y427917D01*
X1194850Y427250D01*
X1194767Y426500D01*
X1194850Y425750D01*
X1195100Y425083D01*
X1195433Y424583D01*
X1195933Y424167D01*
X1196600Y424000D01*
X1197267Y424167D01*
X1197767Y424583D01*
X1198100Y425083D01*
X1198350Y425750D01*
X1198433Y426500D01*
X1198350Y427250D01*
X1198100Y427917D01*
X1197767Y428417D01*
X1197267Y428833D01*
X1196600Y429000D01*
G01X1200700Y423833D02*
X1203700Y429000D01*
G01X1200700D02*
X1200200Y428833D01*
X1199950Y428583D01*
X1199783Y428083D01*
X1199950Y427583D01*
X1200200Y427333D01*
X1200700Y427167D01*
X1201200Y427333D01*
X1201450Y427583D01*
X1201617Y428083D01*
X1201450Y428583D01*
X1201200Y428833D01*
X1200700Y429000D01*
G01X1203700Y425667D02*
X1203200Y425500D01*
X1202950Y425250D01*
X1202783Y424750D01*
X1202950Y424250D01*
X1203200Y424000D01*
X1203700Y423833D01*
X1204200Y424000D01*
X1204450Y424250D01*
X1204617Y424750D01*
X1204450Y425250D01*
X1204200Y425500D01*
X1203700Y425667D01*
G01X1212233Y424000D02*
Y427333D01*
G01Y426667D02*
X1212650Y427000D01*
X1213067Y427250D01*
X1213650Y427333D01*
X1214067Y427250D01*
X1214567Y427000D01*
G01X1217750Y426250D02*
X1220417D01*
X1220167Y426833D01*
X1219750Y427167D01*
X1219167Y427333D01*
X1218583Y427250D01*
X1218083Y427000D01*
X1217750Y426417D01*
X1217583Y425917D01*
Y425417D01*
X1217750Y424917D01*
X1218167Y424417D01*
X1218667Y424083D01*
X1219250Y424000D01*
X1219833Y424167D01*
X1220417Y424667D01*
G01X1223350Y424583D02*
X1223767Y424250D01*
X1224350Y424000D01*
X1224850D01*
X1225350Y424167D01*
X1225683Y424417D01*
X1225850Y424750D01*
X1225767Y425250D01*
X1225433Y425500D01*
X1223933Y426000D01*
X1223600Y426583D01*
X1223767Y427000D01*
X1224100Y427250D01*
X1224600Y427333D01*
X1225100Y427250D01*
X1225600Y427000D01*
G01X1230200Y427333D02*
Y424000D01*
G01Y428667D02*
X1230033Y428750D01*
Y428917D01*
X1230200Y429000D01*
X1230367Y428917D01*
Y428750D01*
X1230200Y428667D01*
G01X1234383Y424000D02*
Y427333D01*
G01Y426500D02*
X1234717Y426917D01*
X1235217Y427250D01*
X1235883Y427333D01*
X1236467Y427250D01*
X1236967Y426917D01*
X1237217Y426333D01*
Y424000D01*
G01X1246417Y422500D02*
X1247583Y423667D01*
Y424833D01*
X1246417D01*
Y423667D01*
X1247583D01*
G01Y425667D02*
Y426833D01*
X1246417D01*
Y425667D01*
X1247583D01*
G01X1250767Y424000D02*
Y429000D01*
X1252433D01*
X1253100Y428750D01*
X1253600Y428417D01*
X1254017Y427917D01*
X1254350Y427333D01*
X1254433Y426500D01*
X1254350Y425667D01*
X1254017Y425083D01*
X1253600Y424583D01*
X1253100Y424250D01*
X1252433Y424000D01*
X1250767D01*
G01X1258200D02*
X1257700Y424083D01*
X1257200Y424417D01*
X1256867Y425000D01*
X1256700Y425667D01*
X1256867Y426333D01*
X1257200Y426917D01*
X1257700Y427250D01*
X1258200Y427333D01*
X1258700Y427250D01*
X1259200Y426917D01*
X1259533Y426333D01*
X1259617Y425667D01*
X1259533Y425000D01*
X1259200Y424417D01*
X1258700Y424083D01*
X1258200Y424000D01*
G01X1267983D02*
Y427333D01*
G01Y426500D02*
X1268317Y426917D01*
X1268817Y427250D01*
X1269483Y427333D01*
X1270067Y427250D01*
X1270567Y426917D01*
X1270817Y426333D01*
Y424000D01*
G01X1275000D02*
X1274500Y424083D01*
X1274000Y424417D01*
X1273667Y425000D01*
X1273500Y425667D01*
X1273667Y426333D01*
X1274000Y426917D01*
X1274500Y427250D01*
X1275000Y427333D01*
X1275500Y427250D01*
X1276000Y426917D01*
X1276333Y426333D01*
X1276417Y425667D01*
X1276333Y425000D01*
X1276000Y424417D01*
X1275500Y424083D01*
X1275000Y424000D01*
G01X1280600Y429000D02*
Y424000D01*
G01X1279433Y427333D02*
X1281767D01*
G01X1293300Y424000D02*
Y427333D01*
G01Y426750D02*
X1292967Y427083D01*
X1292467Y427250D01*
X1291883Y427333D01*
X1291300Y427167D01*
X1290800Y426833D01*
X1290467Y426333D01*
X1290300Y425667D01*
X1290467Y425000D01*
X1290800Y424500D01*
X1291300Y424167D01*
X1291883Y424000D01*
X1292467Y424083D01*
X1292967Y424333D01*
X1293300Y424667D01*
G01X1297400Y424000D02*
Y429000D01*
G01X1303000Y424000D02*
Y429000D01*
G01X1308600Y424000D02*
X1308100Y424083D01*
X1307600Y424417D01*
X1307267Y425000D01*
X1307100Y425667D01*
X1307267Y426333D01*
X1307600Y426917D01*
X1308100Y427250D01*
X1308600Y427333D01*
X1309100Y427250D01*
X1309600Y426917D01*
X1309933Y426333D01*
X1310017Y425667D01*
X1309933Y425000D01*
X1309600Y424417D01*
X1309100Y424083D01*
X1308600Y424000D01*
G01X1312117Y427333D02*
X1313117Y424000D01*
X1314200Y427333D01*
X1315283Y424000D01*
X1316283Y427333D01*
G01X1025417Y445500D02*
X1027500Y440500D01*
X1029583Y445500D01*
G01X1033100Y443833D02*
Y440500D01*
G01Y445167D02*
X1032933Y445250D01*
Y445417D01*
X1033100Y445500D01*
X1033267Y445417D01*
Y445250D01*
X1033100Y445167D01*
G01X1040200Y440500D02*
Y443833D01*
G01Y443250D02*
X1039867Y443583D01*
X1039367Y443750D01*
X1038783Y443833D01*
X1038200Y443667D01*
X1037700Y443333D01*
X1037367Y442833D01*
X1037200Y442167D01*
X1037367Y441500D01*
X1037700Y441000D01*
X1038200Y440667D01*
X1038783Y440500D01*
X1039367Y440583D01*
X1039867Y440833D01*
X1040200Y441167D01*
G01X1048650Y441083D02*
X1049067Y440750D01*
X1049650Y440500D01*
X1050150D01*
X1050650Y440667D01*
X1050983Y440917D01*
X1051150Y441250D01*
X1051067Y441750D01*
X1050733Y442000D01*
X1049233Y442500D01*
X1048900Y443083D01*
X1049067Y443500D01*
X1049400Y443750D01*
X1049900Y443833D01*
X1050400Y443750D01*
X1050900Y443500D01*
G01X1054083Y440500D02*
Y445500D01*
G01Y443083D02*
X1054500Y443500D01*
X1054917Y443750D01*
X1055583Y443833D01*
X1056083Y443750D01*
X1056667Y443417D01*
X1056917Y442917D01*
Y440500D01*
G01X1061100D02*
X1060600Y440583D01*
X1060100Y440917D01*
X1059767Y441500D01*
X1059600Y442167D01*
X1059767Y442833D01*
X1060100Y443417D01*
X1060600Y443750D01*
X1061100Y443833D01*
X1061600Y443750D01*
X1062100Y443417D01*
X1062433Y442833D01*
X1062517Y442167D01*
X1062433Y441500D01*
X1062100Y440917D01*
X1061600Y440583D01*
X1061100Y440500D01*
G01X1065283Y443833D02*
Y441500D01*
X1065617Y440917D01*
X1066117Y440583D01*
X1066700Y440500D01*
X1067283Y440583D01*
X1067783Y440917D01*
X1068117Y441500D01*
G01Y440500D02*
Y443833D01*
G01X1072300Y440500D02*
Y445500D01*
G01X1079400D02*
Y440500D01*
G01Y441250D02*
X1079067Y440833D01*
X1078567Y440583D01*
X1077983Y440500D01*
X1077317Y440667D01*
X1076817Y441083D01*
X1076483Y441583D01*
X1076400Y442167D01*
X1076483Y442750D01*
X1076817Y443250D01*
X1077317Y443667D01*
X1077983Y443833D01*
X1078567Y443750D01*
X1078983Y443583D01*
X1079400Y443250D01*
G01X1087600Y440500D02*
Y445500D01*
G01Y443000D02*
X1088017Y443500D01*
X1088517Y443750D01*
X1089017Y443833D01*
X1089767Y443667D01*
X1090267Y443333D01*
X1090600Y442750D01*
Y442083D01*
X1090433Y441417D01*
X1090100Y440917D01*
X1089517Y440583D01*
X1089017Y440500D01*
X1088517Y440583D01*
X1088017Y440833D01*
X1087600Y441250D01*
G01X1093450Y442750D02*
X1096117D01*
X1095867Y443333D01*
X1095450Y443667D01*
X1094867Y443833D01*
X1094283Y443750D01*
X1093783Y443500D01*
X1093450Y442917D01*
X1093283Y442417D01*
Y441917D01*
X1093450Y441417D01*
X1093867Y440917D01*
X1094367Y440583D01*
X1094950Y440500D01*
X1095533Y440667D01*
X1096117Y441167D01*
G01X1104400Y438833D02*
Y443833D01*
G01Y443083D02*
X1104817Y443500D01*
X1105233Y443750D01*
X1105900Y443833D01*
X1106483Y443750D01*
X1107067Y443333D01*
X1107317Y442750D01*
X1107400Y442167D01*
X1107317Y441583D01*
X1107067Y441000D01*
X1106567Y440667D01*
X1105900Y440500D01*
X1105317Y440583D01*
X1104733Y440833D01*
X1104400Y441167D01*
G01X1111500Y440500D02*
Y445500D01*
G01X1115683Y443833D02*
Y441500D01*
X1116017Y440917D01*
X1116517Y440583D01*
X1117100Y440500D01*
X1117683Y440583D01*
X1118183Y440917D01*
X1118517Y441500D01*
G01Y440500D02*
Y443833D01*
G01X1121533Y439250D02*
X1122117Y438917D01*
X1122783Y438833D01*
X1123367Y438917D01*
X1123867Y439333D01*
X1124200Y439917D01*
Y443833D01*
G01Y443167D02*
X1123867Y443500D01*
X1123367Y443750D01*
X1122783Y443833D01*
X1122117Y443667D01*
X1121700Y443333D01*
X1121367Y442750D01*
X1121200Y442167D01*
X1121283Y441667D01*
X1121617Y441083D01*
X1122117Y440667D01*
X1122783Y440500D01*
X1123283Y440583D01*
X1123867Y440917D01*
X1124200Y441250D01*
G01X1127133Y439250D02*
X1127717Y438917D01*
X1128383Y438833D01*
X1128967Y438917D01*
X1129467Y439333D01*
X1129800Y439917D01*
Y443833D01*
G01Y443167D02*
X1129467Y443500D01*
X1128967Y443750D01*
X1128383Y443833D01*
X1127717Y443667D01*
X1127300Y443333D01*
X1126967Y442750D01*
X1126800Y442167D01*
X1126883Y441667D01*
X1127217Y441083D01*
X1127717Y440667D01*
X1128383Y440500D01*
X1128883Y440583D01*
X1129467Y440917D01*
X1129800Y441250D01*
G01X1132650Y442750D02*
X1135317D01*
X1135067Y443333D01*
X1134650Y443667D01*
X1134067Y443833D01*
X1133483Y443750D01*
X1132983Y443500D01*
X1132650Y442917D01*
X1132483Y442417D01*
Y441917D01*
X1132650Y441417D01*
X1133067Y440917D01*
X1133567Y440583D01*
X1134150Y440500D01*
X1134733Y440667D01*
X1135317Y441167D01*
G01X1141000Y445500D02*
Y440500D01*
G01Y441250D02*
X1140667Y440833D01*
X1140167Y440583D01*
X1139583Y440500D01*
X1138917Y440667D01*
X1138417Y441083D01*
X1138083Y441583D01*
X1138000Y442167D01*
X1138083Y442750D01*
X1138417Y443250D01*
X1138917Y443667D01*
X1139583Y443833D01*
X1140167Y443750D01*
X1140583Y443583D01*
X1141000Y443250D01*
G01X1148617Y443833D02*
X1149617Y440500D01*
X1150700Y443833D01*
X1151783Y440500D01*
X1152783Y443833D01*
G01X1156300D02*
Y440500D01*
G01Y445167D02*
X1156133Y445250D01*
Y445417D01*
X1156300Y445500D01*
X1156467Y445417D01*
Y445250D01*
X1156300Y445167D01*
G01X1161900Y445500D02*
Y440500D01*
G01X1160733Y443833D02*
X1163067D01*
G01X1166083Y440500D02*
Y445500D01*
G01Y443083D02*
X1166500Y443500D01*
X1166917Y443750D01*
X1167583Y443833D01*
X1168083Y443750D01*
X1168667Y443417D01*
X1168917Y442917D01*
Y440500D01*
G01X1177033D02*
X1180367Y442167D01*
X1177033Y443833D01*
G01X1182883Y441083D02*
X1183467Y440667D01*
X1184133Y440500D01*
X1184800Y440667D01*
X1185383Y441167D01*
X1185800Y441917D01*
X1185967Y442667D01*
Y443583D01*
X1185800Y444333D01*
X1185383Y445000D01*
X1184883Y445333D01*
X1184300Y445500D01*
X1183633Y445333D01*
X1183133Y445000D01*
X1182800Y444500D01*
X1182633Y443833D01*
X1182800Y443250D01*
X1183217Y442667D01*
X1183717Y442333D01*
X1184300Y442250D01*
X1184967Y442417D01*
X1185467Y442833D01*
X1185967Y443583D01*
G01X1189900Y445500D02*
X1189233Y445333D01*
X1188733Y444917D01*
X1188400Y444417D01*
X1188150Y443750D01*
X1188067Y443000D01*
X1188150Y442250D01*
X1188400Y441583D01*
X1188733Y441083D01*
X1189233Y440667D01*
X1189900Y440500D01*
X1190567Y440667D01*
X1191067Y441083D01*
X1191400Y441583D01*
X1191650Y442250D01*
X1191733Y443000D01*
X1191650Y443750D01*
X1191400Y444417D01*
X1191067Y444917D01*
X1190567Y445333D01*
X1189900Y445500D01*
G01X1194000Y440333D02*
X1197000Y445500D01*
G01X1194000D02*
X1193500Y445333D01*
X1193250Y445083D01*
X1193083Y444583D01*
X1193250Y444083D01*
X1193500Y443833D01*
X1194000Y443667D01*
X1194500Y443833D01*
X1194750Y444083D01*
X1194917Y444583D01*
X1194750Y445083D01*
X1194500Y445333D01*
X1194000Y445500D01*
G01X1197000Y442167D02*
X1196500Y442000D01*
X1196250Y441750D01*
X1196083Y441250D01*
X1196250Y440750D01*
X1196500Y440500D01*
X1197000Y440333D01*
X1197500Y440500D01*
X1197750Y440750D01*
X1197917Y441250D01*
X1197750Y441750D01*
X1197500Y442000D01*
X1197000Y442167D01*
G01X1205533Y440500D02*
Y443833D01*
G01Y443167D02*
X1205950Y443500D01*
X1206367Y443750D01*
X1206950Y443833D01*
X1207367Y443750D01*
X1207867Y443500D01*
G01X1211050Y442750D02*
X1213717D01*
X1213467Y443333D01*
X1213050Y443667D01*
X1212467Y443833D01*
X1211883Y443750D01*
X1211383Y443500D01*
X1211050Y442917D01*
X1210883Y442417D01*
Y441917D01*
X1211050Y441417D01*
X1211467Y440917D01*
X1211967Y440583D01*
X1212550Y440500D01*
X1213133Y440667D01*
X1213717Y441167D01*
G01X1216650Y441083D02*
X1217067Y440750D01*
X1217650Y440500D01*
X1218150D01*
X1218650Y440667D01*
X1218983Y440917D01*
X1219150Y441250D01*
X1219067Y441750D01*
X1218733Y442000D01*
X1217233Y442500D01*
X1216900Y443083D01*
X1217067Y443500D01*
X1217400Y443750D01*
X1217900Y443833D01*
X1218400Y443750D01*
X1218900Y443500D01*
G01X1223500Y443833D02*
Y440500D01*
G01Y445167D02*
X1223333Y445250D01*
Y445417D01*
X1223500Y445500D01*
X1223667Y445417D01*
Y445250D01*
X1223500Y445167D01*
G01X1227683Y440500D02*
Y443833D01*
G01Y443000D02*
X1228017Y443417D01*
X1228517Y443750D01*
X1229183Y443833D01*
X1229767Y443750D01*
X1230267Y443417D01*
X1230517Y442833D01*
Y440500D01*
G01X1023917Y466500D02*
X1026000Y461500D01*
X1028083Y466500D01*
G01X1031600Y464833D02*
Y461500D01*
G01Y466167D02*
X1031433Y466250D01*
Y466417D01*
X1031600Y466500D01*
X1031767Y466417D01*
Y466250D01*
X1031600Y466167D01*
G01X1038700Y461500D02*
Y464833D01*
G01Y464250D02*
X1038367Y464583D01*
X1037867Y464750D01*
X1037283Y464833D01*
X1036700Y464667D01*
X1036200Y464333D01*
X1035867Y463833D01*
X1035700Y463167D01*
X1035867Y462500D01*
X1036200Y462000D01*
X1036700Y461667D01*
X1037283Y461500D01*
X1037867Y461583D01*
X1038367Y461833D01*
X1038700Y462167D01*
G01X1047150Y462083D02*
X1047567Y461750D01*
X1048150Y461500D01*
X1048650D01*
X1049150Y461667D01*
X1049483Y461917D01*
X1049650Y462250D01*
X1049567Y462750D01*
X1049233Y463000D01*
X1047733Y463500D01*
X1047400Y464083D01*
X1047567Y464500D01*
X1047900Y464750D01*
X1048400Y464833D01*
X1048900Y464750D01*
X1049400Y464500D01*
G01X1052583Y461500D02*
Y466500D01*
G01Y464083D02*
X1053000Y464500D01*
X1053417Y464750D01*
X1054083Y464833D01*
X1054583Y464750D01*
X1055167Y464417D01*
X1055417Y463917D01*
Y461500D01*
G01X1059600D02*
X1059100Y461583D01*
X1058600Y461917D01*
X1058267Y462500D01*
X1058100Y463167D01*
X1058267Y463833D01*
X1058600Y464417D01*
X1059100Y464750D01*
X1059600Y464833D01*
X1060100Y464750D01*
X1060600Y464417D01*
X1060933Y463833D01*
X1061017Y463167D01*
X1060933Y462500D01*
X1060600Y461917D01*
X1060100Y461583D01*
X1059600Y461500D01*
G01X1063783Y464833D02*
Y462500D01*
X1064117Y461917D01*
X1064617Y461583D01*
X1065200Y461500D01*
X1065783Y461583D01*
X1066283Y461917D01*
X1066617Y462500D01*
G01Y461500D02*
Y464833D01*
G01X1070800Y461500D02*
Y466500D01*
G01X1077900D02*
Y461500D01*
G01Y462250D02*
X1077567Y461833D01*
X1077067Y461583D01*
X1076483Y461500D01*
X1075817Y461667D01*
X1075317Y462083D01*
X1074983Y462583D01*
X1074900Y463167D01*
X1074983Y463750D01*
X1075317Y464250D01*
X1075817Y464667D01*
X1076483Y464833D01*
X1077067Y464750D01*
X1077483Y464583D01*
X1077900Y464250D01*
G01X1086100Y461500D02*
Y466500D01*
G01Y464000D02*
X1086517Y464500D01*
X1087017Y464750D01*
X1087517Y464833D01*
X1088267Y464667D01*
X1088767Y464333D01*
X1089100Y463750D01*
Y463083D01*
X1088933Y462417D01*
X1088600Y461917D01*
X1088017Y461583D01*
X1087517Y461500D01*
X1087017Y461583D01*
X1086517Y461833D01*
X1086100Y462250D01*
G01X1091950Y463750D02*
X1094617D01*
X1094367Y464333D01*
X1093950Y464667D01*
X1093367Y464833D01*
X1092783Y464750D01*
X1092283Y464500D01*
X1091950Y463917D01*
X1091783Y463417D01*
Y462917D01*
X1091950Y462417D01*
X1092367Y461917D01*
X1092867Y461583D01*
X1093450Y461500D01*
X1094033Y461667D01*
X1094617Y462167D01*
G01X1102900Y459833D02*
Y464833D01*
G01Y464083D02*
X1103317Y464500D01*
X1103733Y464750D01*
X1104400Y464833D01*
X1104983Y464750D01*
X1105567Y464333D01*
X1105817Y463750D01*
X1105900Y463167D01*
X1105817Y462583D01*
X1105567Y462000D01*
X1105067Y461667D01*
X1104400Y461500D01*
X1103817Y461583D01*
X1103233Y461833D01*
X1102900Y462167D01*
G01X1110000Y461500D02*
Y466500D01*
G01X1114183Y464833D02*
Y462500D01*
X1114517Y461917D01*
X1115017Y461583D01*
X1115600Y461500D01*
X1116183Y461583D01*
X1116683Y461917D01*
X1117017Y462500D01*
G01Y461500D02*
Y464833D01*
G01X1120033Y460250D02*
X1120617Y459917D01*
X1121283Y459833D01*
X1121867Y459917D01*
X1122367Y460333D01*
X1122700Y460917D01*
Y464833D01*
G01Y464167D02*
X1122367Y464500D01*
X1121867Y464750D01*
X1121283Y464833D01*
X1120617Y464667D01*
X1120200Y464333D01*
X1119867Y463750D01*
X1119700Y463167D01*
X1119783Y462667D01*
X1120117Y462083D01*
X1120617Y461667D01*
X1121283Y461500D01*
X1121783Y461583D01*
X1122367Y461917D01*
X1122700Y462250D01*
G01X1125633Y460250D02*
X1126217Y459917D01*
X1126883Y459833D01*
X1127467Y459917D01*
X1127967Y460333D01*
X1128300Y460917D01*
Y464833D01*
G01Y464167D02*
X1127967Y464500D01*
X1127467Y464750D01*
X1126883Y464833D01*
X1126217Y464667D01*
X1125800Y464333D01*
X1125467Y463750D01*
X1125300Y463167D01*
X1125383Y462667D01*
X1125717Y462083D01*
X1126217Y461667D01*
X1126883Y461500D01*
X1127383Y461583D01*
X1127967Y461917D01*
X1128300Y462250D01*
G01X1131150Y463750D02*
X1133817D01*
X1133567Y464333D01*
X1133150Y464667D01*
X1132567Y464833D01*
X1131983Y464750D01*
X1131483Y464500D01*
X1131150Y463917D01*
X1130983Y463417D01*
Y462917D01*
X1131150Y462417D01*
X1131567Y461917D01*
X1132067Y461583D01*
X1132650Y461500D01*
X1133233Y461667D01*
X1133817Y462167D01*
G01X1139500Y466500D02*
Y461500D01*
G01Y462250D02*
X1139167Y461833D01*
X1138667Y461583D01*
X1138083Y461500D01*
X1137417Y461667D01*
X1136917Y462083D01*
X1136583Y462583D01*
X1136500Y463167D01*
X1136583Y463750D01*
X1136917Y464250D01*
X1137417Y464667D01*
X1138083Y464833D01*
X1138667Y464750D01*
X1139083Y464583D01*
X1139500Y464250D01*
G01X1150200Y461500D02*
Y466500D01*
X1147117Y462917D01*
X1151283D01*
G01X1154800Y466500D02*
X1154133Y466333D01*
X1153633Y465917D01*
X1153300Y465417D01*
X1153050Y464750D01*
X1152967Y464000D01*
X1153050Y463250D01*
X1153300Y462583D01*
X1153633Y462083D01*
X1154133Y461667D01*
X1154800Y461500D01*
X1155467Y461667D01*
X1155967Y462083D01*
X1156300Y462583D01*
X1156550Y463250D01*
X1156633Y464000D01*
X1156550Y464750D01*
X1156300Y465417D01*
X1155967Y465917D01*
X1155467Y466333D01*
X1154800Y466500D01*
G01X1158900Y461333D02*
X1161900Y466500D01*
G01X1158900D02*
X1158400Y466333D01*
X1158150Y466083D01*
X1157983Y465583D01*
X1158150Y465083D01*
X1158400Y464833D01*
X1158900Y464667D01*
X1159400Y464833D01*
X1159650Y465083D01*
X1159817Y465583D01*
X1159650Y466083D01*
X1159400Y466333D01*
X1158900Y466500D01*
G01X1161900Y463167D02*
X1161400Y463000D01*
X1161150Y462750D01*
X1160983Y462250D01*
X1161150Y461750D01*
X1161400Y461500D01*
X1161900Y461333D01*
X1162400Y461500D01*
X1162650Y461750D01*
X1162817Y462250D01*
X1162650Y462750D01*
X1162400Y463000D01*
X1161900Y463167D01*
G01X1169100D02*
X1169933Y464833D01*
X1170767D01*
X1172433Y461500D01*
X1173267D01*
X1174100Y463167D01*
G01X1182800Y461500D02*
Y466500D01*
X1181800Y465500D01*
G01Y461500D02*
X1183800D01*
G01X1188400Y466500D02*
X1187733Y466333D01*
X1187233Y465917D01*
X1186900Y465417D01*
X1186650Y464750D01*
X1186567Y464000D01*
X1186650Y463250D01*
X1186900Y462583D01*
X1187233Y462083D01*
X1187733Y461667D01*
X1188400Y461500D01*
X1189067Y461667D01*
X1189567Y462083D01*
X1189900Y462583D01*
X1190150Y463250D01*
X1190233Y464000D01*
X1190150Y464750D01*
X1189900Y465417D01*
X1189567Y465917D01*
X1189067Y466333D01*
X1188400Y466500D01*
G01X1194000D02*
X1193333Y466333D01*
X1192833Y465917D01*
X1192500Y465417D01*
X1192250Y464750D01*
X1192167Y464000D01*
X1192250Y463250D01*
X1192500Y462583D01*
X1192833Y462083D01*
X1193333Y461667D01*
X1194000Y461500D01*
X1194667Y461667D01*
X1195167Y462083D01*
X1195500Y462583D01*
X1195750Y463250D01*
X1195833Y464000D01*
X1195750Y464750D01*
X1195500Y465417D01*
X1195167Y465917D01*
X1194667Y466333D01*
X1194000Y466500D01*
G01X1198100Y461333D02*
X1201100Y466500D01*
G01X1198100D02*
X1197600Y466333D01*
X1197350Y466083D01*
X1197183Y465583D01*
X1197350Y465083D01*
X1197600Y464833D01*
X1198100Y464667D01*
X1198600Y464833D01*
X1198850Y465083D01*
X1199017Y465583D01*
X1198850Y466083D01*
X1198600Y466333D01*
X1198100Y466500D01*
G01X1201100Y463167D02*
X1200600Y463000D01*
X1200350Y462750D01*
X1200183Y462250D01*
X1200350Y461750D01*
X1200600Y461500D01*
X1201100Y461333D01*
X1201600Y461500D01*
X1201850Y461750D01*
X1202017Y462250D01*
X1201850Y462750D01*
X1201600Y463000D01*
X1201100Y463167D01*
G01X1209550Y462083D02*
X1209967Y461750D01*
X1210550Y461500D01*
X1211050D01*
X1211550Y461667D01*
X1211883Y461917D01*
X1212050Y462250D01*
X1211967Y462750D01*
X1211633Y463000D01*
X1210133Y463500D01*
X1209800Y464083D01*
X1209967Y464500D01*
X1210300Y464750D01*
X1210800Y464833D01*
X1211300Y464750D01*
X1211800Y464500D01*
G01X1216400Y461500D02*
X1215900Y461583D01*
X1215400Y461917D01*
X1215067Y462500D01*
X1214900Y463167D01*
X1215067Y463833D01*
X1215400Y464417D01*
X1215900Y464750D01*
X1216400Y464833D01*
X1216900Y464750D01*
X1217400Y464417D01*
X1217733Y463833D01*
X1217817Y463167D01*
X1217733Y462500D01*
X1217400Y461917D01*
X1216900Y461583D01*
X1216400Y461500D01*
G01X1222000D02*
Y466500D01*
G01X1229100D02*
Y461500D01*
G01Y462250D02*
X1228767Y461833D01*
X1228267Y461583D01*
X1227683Y461500D01*
X1227017Y461667D01*
X1226517Y462083D01*
X1226183Y462583D01*
X1226100Y463167D01*
X1226183Y463750D01*
X1226517Y464250D01*
X1227017Y464667D01*
X1227683Y464833D01*
X1228267Y464750D01*
X1228683Y464583D01*
X1229100Y464250D01*
G01X1231950Y463750D02*
X1234617D01*
X1234367Y464333D01*
X1233950Y464667D01*
X1233367Y464833D01*
X1232783Y464750D01*
X1232283Y464500D01*
X1231950Y463917D01*
X1231783Y463417D01*
Y462917D01*
X1231950Y462417D01*
X1232367Y461917D01*
X1232867Y461583D01*
X1233450Y461500D01*
X1234033Y461667D01*
X1234617Y462167D01*
G01X1237633Y461500D02*
Y464833D01*
G01Y464167D02*
X1238050Y464500D01*
X1238467Y464750D01*
X1239050Y464833D01*
X1239467Y464750D01*
X1239967Y464500D01*
G01X1247500Y461500D02*
Y464833D01*
G01Y463917D02*
X1247750Y464333D01*
X1248167Y464667D01*
X1248750Y464833D01*
X1249333Y464667D01*
X1249750Y464333D01*
X1250000Y463917D01*
Y461500D01*
G01Y463917D02*
X1250250Y464333D01*
X1250667Y464667D01*
X1251250Y464833D01*
X1251833Y464667D01*
X1252250Y464333D01*
X1252500Y463833D01*
Y461500D01*
G01X1257100D02*
Y464833D01*
G01Y464250D02*
X1256767Y464583D01*
X1256267Y464750D01*
X1255683Y464833D01*
X1255100Y464667D01*
X1254600Y464333D01*
X1254267Y463833D01*
X1254100Y463167D01*
X1254267Y462500D01*
X1254600Y462000D01*
X1255100Y461667D01*
X1255683Y461500D01*
X1256267Y461583D01*
X1256767Y461833D01*
X1257100Y462167D01*
G01X1259950Y462083D02*
X1260367Y461750D01*
X1260950Y461500D01*
X1261450D01*
X1261950Y461667D01*
X1262283Y461917D01*
X1262450Y462250D01*
X1262367Y462750D01*
X1262033Y463000D01*
X1260533Y463500D01*
X1260200Y464083D01*
X1260367Y464500D01*
X1260700Y464750D01*
X1261200Y464833D01*
X1261700Y464750D01*
X1262200Y464500D01*
G01X1265383Y461500D02*
Y466500D01*
G01X1268050Y464833D02*
X1265383Y462917D01*
G01X1266467Y463667D02*
X1268217Y461500D01*
G01X1046500Y485833D02*
X1048000Y482500D01*
X1049500Y485833D01*
G01X1053600D02*
Y482500D01*
G01Y487167D02*
X1053433Y487250D01*
Y487417D01*
X1053600Y487500D01*
X1053767Y487417D01*
Y487250D01*
X1053600Y487167D01*
G01X1060700Y482500D02*
Y485833D01*
G01Y485250D02*
X1060367Y485583D01*
X1059867Y485750D01*
X1059283Y485833D01*
X1058700Y485667D01*
X1058200Y485333D01*
X1057867Y484833D01*
X1057700Y484167D01*
X1057867Y483500D01*
X1058200Y483000D01*
X1058700Y482667D01*
X1059283Y482500D01*
X1059867Y482583D01*
X1060367Y482833D01*
X1060700Y483167D01*
G01X1069150Y483083D02*
X1069567Y482750D01*
X1070150Y482500D01*
X1070650D01*
X1071150Y482667D01*
X1071483Y482917D01*
X1071650Y483250D01*
X1071567Y483750D01*
X1071233Y484000D01*
X1069733Y484500D01*
X1069400Y485083D01*
X1069567Y485500D01*
X1069900Y485750D01*
X1070400Y485833D01*
X1070900Y485750D01*
X1071400Y485500D01*
G01X1074583Y482500D02*
Y487500D01*
G01Y485083D02*
X1075000Y485500D01*
X1075417Y485750D01*
X1076083Y485833D01*
X1076583Y485750D01*
X1077167Y485417D01*
X1077417Y484917D01*
Y482500D01*
G01X1083100D02*
Y485833D01*
G01Y485250D02*
X1082767Y485583D01*
X1082267Y485750D01*
X1081683Y485833D01*
X1081100Y485667D01*
X1080600Y485333D01*
X1080267Y484833D01*
X1080100Y484167D01*
X1080267Y483500D01*
X1080600Y483000D01*
X1081100Y482667D01*
X1081683Y482500D01*
X1082267Y482583D01*
X1082767Y482833D01*
X1083100Y483167D01*
G01X1087200Y482500D02*
Y487500D01*
G01X1092800Y482500D02*
Y487500D01*
G01X1102500Y482500D02*
Y487500D01*
G01Y485000D02*
X1102917Y485500D01*
X1103417Y485750D01*
X1103917Y485833D01*
X1104667Y485667D01*
X1105167Y485333D01*
X1105500Y484750D01*
Y484083D01*
X1105333Y483417D01*
X1105000Y482917D01*
X1104417Y482583D01*
X1103917Y482500D01*
X1103417Y482583D01*
X1102917Y482833D01*
X1102500Y483250D01*
G01X1108350Y484750D02*
X1111017D01*
X1110767Y485333D01*
X1110350Y485667D01*
X1109767Y485833D01*
X1109183Y485750D01*
X1108683Y485500D01*
X1108350Y484917D01*
X1108183Y484417D01*
Y483917D01*
X1108350Y483417D01*
X1108767Y482917D01*
X1109267Y482583D01*
X1109850Y482500D01*
X1110433Y482667D01*
X1111017Y483167D01*
G01X1118717Y485833D02*
X1119717Y482500D01*
X1120800Y485833D01*
X1121883Y482500D01*
X1122883Y485833D01*
G01X1126400D02*
Y482500D01*
G01Y487167D02*
X1126233Y487250D01*
Y487417D01*
X1126400Y487500D01*
X1126567Y487417D01*
Y487250D01*
X1126400Y487167D01*
G01X1132000Y487500D02*
Y482500D01*
G01X1130833Y485833D02*
X1133167D01*
G01X1136183Y482500D02*
Y487500D01*
G01Y485083D02*
X1136600Y485500D01*
X1137017Y485750D01*
X1137683Y485833D01*
X1138183Y485750D01*
X1138767Y485417D01*
X1139017Y484917D01*
Y482500D01*
G01X1150467D02*
X1147133Y484167D01*
X1150467Y485833D01*
G01X1160000Y482500D02*
X1160583Y482583D01*
X1161250Y482833D01*
X1161667Y483250D01*
X1161833Y483833D01*
X1161667Y484417D01*
X1161167Y484917D01*
X1160417Y485167D01*
X1159583D01*
X1159083Y485333D01*
X1158667Y485750D01*
X1158500Y486333D01*
X1158750Y486917D01*
X1159333Y487333D01*
X1160000Y487500D01*
X1160667Y487333D01*
X1161250Y486917D01*
X1161500Y486333D01*
X1161333Y485750D01*
X1160917Y485333D01*
X1160417Y485167D01*
X1159583D01*
X1158833Y484917D01*
X1158333Y484417D01*
X1158167Y483833D01*
X1158333Y483250D01*
X1158750Y482833D01*
X1159417Y482583D01*
X1160000Y482500D01*
G01X1165600Y487500D02*
X1164933Y487333D01*
X1164433Y486917D01*
X1164100Y486417D01*
X1163850Y485750D01*
X1163767Y485000D01*
X1163850Y484250D01*
X1164100Y483583D01*
X1164433Y483083D01*
X1164933Y482667D01*
X1165600Y482500D01*
X1166267Y482667D01*
X1166767Y483083D01*
X1167100Y483583D01*
X1167350Y484250D01*
X1167433Y485000D01*
X1167350Y485750D01*
X1167100Y486417D01*
X1166767Y486917D01*
X1166267Y487333D01*
X1165600Y487500D01*
G01X1175300Y482333D02*
X1178300Y487500D01*
G01X1175300D02*
X1174800Y487333D01*
X1174550Y487083D01*
X1174383Y486583D01*
X1174550Y486083D01*
X1174800Y485833D01*
X1175300Y485667D01*
X1175800Y485833D01*
X1176050Y486083D01*
X1176217Y486583D01*
X1176050Y487083D01*
X1175800Y487333D01*
X1175300Y487500D01*
G01X1178300Y484167D02*
X1177800Y484000D01*
X1177550Y483750D01*
X1177383Y483250D01*
X1177550Y482750D01*
X1177800Y482500D01*
X1178300Y482333D01*
X1178800Y482500D01*
X1179050Y482750D01*
X1179217Y483250D01*
X1179050Y483750D01*
X1178800Y484000D01*
X1178300Y484167D01*
G01X1186750Y483083D02*
X1187167Y482750D01*
X1187750Y482500D01*
X1188250D01*
X1188750Y482667D01*
X1189083Y482917D01*
X1189250Y483250D01*
X1189167Y483750D01*
X1188833Y484000D01*
X1187333Y484500D01*
X1187000Y485083D01*
X1187167Y485500D01*
X1187500Y485750D01*
X1188000Y485833D01*
X1188500Y485750D01*
X1189000Y485500D01*
G01X1193600Y482500D02*
X1193100Y482583D01*
X1192600Y482917D01*
X1192267Y483500D01*
X1192100Y484167D01*
X1192267Y484833D01*
X1192600Y485417D01*
X1193100Y485750D01*
X1193600Y485833D01*
X1194100Y485750D01*
X1194600Y485417D01*
X1194933Y484833D01*
X1195017Y484167D01*
X1194933Y483500D01*
X1194600Y482917D01*
X1194100Y482583D01*
X1193600Y482500D01*
G01X1199200D02*
Y487500D01*
G01X1206300D02*
Y482500D01*
G01Y483250D02*
X1205967Y482833D01*
X1205467Y482583D01*
X1204883Y482500D01*
X1204217Y482667D01*
X1203717Y483083D01*
X1203383Y483583D01*
X1203300Y484167D01*
X1203383Y484750D01*
X1203717Y485250D01*
X1204217Y485667D01*
X1204883Y485833D01*
X1205467Y485750D01*
X1205883Y485583D01*
X1206300Y485250D01*
G01X1209150Y484750D02*
X1211817D01*
X1211567Y485333D01*
X1211150Y485667D01*
X1210567Y485833D01*
X1209983Y485750D01*
X1209483Y485500D01*
X1209150Y484917D01*
X1208983Y484417D01*
Y483917D01*
X1209150Y483417D01*
X1209567Y482917D01*
X1210067Y482583D01*
X1210650Y482500D01*
X1211233Y482667D01*
X1211817Y483167D01*
G01X1214833Y482500D02*
Y485833D01*
G01Y485167D02*
X1215250Y485500D01*
X1215667Y485750D01*
X1216250Y485833D01*
X1216667Y485750D01*
X1217167Y485500D01*
G01X1224700Y482500D02*
Y485833D01*
G01Y484917D02*
X1224950Y485333D01*
X1225367Y485667D01*
X1225950Y485833D01*
X1226533Y485667D01*
X1226950Y485333D01*
X1227200Y484917D01*
Y482500D01*
G01Y484917D02*
X1227450Y485333D01*
X1227867Y485667D01*
X1228450Y485833D01*
X1229033Y485667D01*
X1229450Y485333D01*
X1229700Y484833D01*
Y482500D01*
G01X1234300D02*
Y485833D01*
G01Y485250D02*
X1233967Y485583D01*
X1233467Y485750D01*
X1232883Y485833D01*
X1232300Y485667D01*
X1231800Y485333D01*
X1231467Y484833D01*
X1231300Y484167D01*
X1231467Y483500D01*
X1231800Y483000D01*
X1232300Y482667D01*
X1232883Y482500D01*
X1233467Y482583D01*
X1233967Y482833D01*
X1234300Y483167D01*
G01X1237150Y483083D02*
X1237567Y482750D01*
X1238150Y482500D01*
X1238650D01*
X1239150Y482667D01*
X1239483Y482917D01*
X1239650Y483250D01*
X1239567Y483750D01*
X1239233Y484000D01*
X1237733Y484500D01*
X1237400Y485083D01*
X1237567Y485500D01*
X1237900Y485750D01*
X1238400Y485833D01*
X1238900Y485750D01*
X1239400Y485500D01*
G01X1242583Y482500D02*
Y487500D01*
G01X1245250Y485833D02*
X1242583Y483917D01*
G01X1243667Y484667D02*
X1245417Y482500D01*
G01X1035500Y491500D02*
Y496500D01*
G01Y494000D02*
X1035917Y494500D01*
X1036417Y494750D01*
X1036917Y494833D01*
X1037667Y494667D01*
X1038167Y494333D01*
X1038500Y493750D01*
Y493083D01*
X1038333Y492417D01*
X1038000Y491917D01*
X1037417Y491583D01*
X1036917Y491500D01*
X1036417Y491583D01*
X1035917Y491833D01*
X1035500Y492250D01*
G01X1042600Y491333D02*
X1042433Y491417D01*
Y491583D01*
X1042600Y491667D01*
X1042767Y491583D01*
Y491417D01*
X1042600Y491333D01*
G01X1048867Y494167D02*
X1049200Y494417D01*
X1049450Y494833D01*
X1049617Y495417D01*
X1049450Y495917D01*
X1049117Y496250D01*
X1048533Y496500D01*
X1046283D01*
Y491500D01*
X1049033D01*
X1049617Y491833D01*
X1049950Y492333D01*
X1050117Y492917D01*
X1049950Y493500D01*
X1049450Y494000D01*
X1048867Y494167D01*
X1046283D01*
G01X1053800Y491500D02*
X1053300Y491583D01*
X1052800Y491917D01*
X1052467Y492500D01*
X1052300Y493167D01*
X1052467Y493833D01*
X1052800Y494417D01*
X1053300Y494750D01*
X1053800Y494833D01*
X1054300Y494750D01*
X1054800Y494417D01*
X1055133Y493833D01*
X1055217Y493167D01*
X1055133Y492500D01*
X1054800Y491917D01*
X1054300Y491583D01*
X1053800Y491500D01*
G01X1060900D02*
Y494833D01*
G01Y494250D02*
X1060567Y494583D01*
X1060067Y494750D01*
X1059483Y494833D01*
X1058900Y494667D01*
X1058400Y494333D01*
X1058067Y493833D01*
X1057900Y493167D01*
X1058067Y492500D01*
X1058400Y492000D01*
X1058900Y491667D01*
X1059483Y491500D01*
X1060067Y491583D01*
X1060567Y491833D01*
X1060900Y492167D01*
G01X1063833Y491500D02*
Y494833D01*
G01Y494167D02*
X1064250Y494500D01*
X1064667Y494750D01*
X1065250Y494833D01*
X1065667Y494750D01*
X1066167Y494500D01*
G01X1072100Y496500D02*
Y491500D01*
G01Y492250D02*
X1071767Y491833D01*
X1071267Y491583D01*
X1070683Y491500D01*
X1070017Y491667D01*
X1069517Y492083D01*
X1069183Y492583D01*
X1069100Y493167D01*
X1069183Y493750D01*
X1069517Y494250D01*
X1070017Y494667D01*
X1070683Y494833D01*
X1071267Y494750D01*
X1071683Y494583D01*
X1072100Y494250D01*
G01X1081800Y496500D02*
Y491500D01*
G01X1080633Y494833D02*
X1082967D01*
G01X1085983Y491500D02*
Y496500D01*
G01Y494083D02*
X1086400Y494500D01*
X1086817Y494750D01*
X1087483Y494833D01*
X1087983Y494750D01*
X1088567Y494417D01*
X1088817Y493917D01*
Y491500D01*
G01X1093000Y494833D02*
Y491500D01*
G01Y496167D02*
X1092833Y496250D01*
Y496417D01*
X1093000Y496500D01*
X1093167Y496417D01*
Y496250D01*
X1093000Y496167D01*
G01X1099933Y494417D02*
X1099350Y494750D01*
X1098850Y494833D01*
X1098183Y494667D01*
X1097683Y494333D01*
X1097350Y493750D01*
X1097267Y493167D01*
X1097350Y492583D01*
X1097683Y492083D01*
X1098183Y491667D01*
X1098850Y491500D01*
X1099433Y491667D01*
X1099933Y492000D01*
G01X1102783Y491500D02*
Y496500D01*
G01X1105450Y494833D02*
X1102783Y492917D01*
G01X1103867Y493667D02*
X1105617Y491500D01*
G01X1108383D02*
Y494833D01*
G01Y494000D02*
X1108717Y494417D01*
X1109217Y494750D01*
X1109883Y494833D01*
X1110467Y494750D01*
X1110967Y494417D01*
X1111217Y493833D01*
Y491500D01*
G01X1114150Y493750D02*
X1116817D01*
X1116567Y494333D01*
X1116150Y494667D01*
X1115567Y494833D01*
X1114983Y494750D01*
X1114483Y494500D01*
X1114150Y493917D01*
X1113983Y493417D01*
Y492917D01*
X1114150Y492417D01*
X1114567Y491917D01*
X1115067Y491583D01*
X1115650Y491500D01*
X1116233Y491667D01*
X1116817Y492167D01*
G01X1119750Y492083D02*
X1120167Y491750D01*
X1120750Y491500D01*
X1121250D01*
X1121750Y491667D01*
X1122083Y491917D01*
X1122250Y492250D01*
X1122167Y492750D01*
X1121833Y493000D01*
X1120333Y493500D01*
X1120000Y494083D01*
X1120167Y494500D01*
X1120500Y494750D01*
X1121000Y494833D01*
X1121500Y494750D01*
X1122000Y494500D01*
G01X1125350Y492083D02*
X1125767Y491750D01*
X1126350Y491500D01*
X1126850D01*
X1127350Y491667D01*
X1127683Y491917D01*
X1127850Y492250D01*
X1127767Y492750D01*
X1127433Y493000D01*
X1125933Y493500D01*
X1125600Y494083D01*
X1125767Y494500D01*
X1126100Y494750D01*
X1126600Y494833D01*
X1127100Y494750D01*
X1127600Y494500D01*
G01X1139467Y491500D02*
X1136133Y493167D01*
X1139467Y494833D01*
G01X1149000Y496500D02*
X1148333Y496333D01*
X1147833Y495917D01*
X1147500Y495417D01*
X1147250Y494750D01*
X1147167Y494000D01*
X1147250Y493250D01*
X1147500Y492583D01*
X1147833Y492083D01*
X1148333Y491667D01*
X1149000Y491500D01*
X1149667Y491667D01*
X1150167Y492083D01*
X1150500Y492583D01*
X1150750Y493250D01*
X1150833Y494000D01*
X1150750Y494750D01*
X1150500Y495417D01*
X1150167Y495917D01*
X1149667Y496333D01*
X1149000Y496500D01*
G01X1154600Y491333D02*
X1154433Y491417D01*
Y491583D01*
X1154600Y491667D01*
X1154767Y491583D01*
Y491417D01*
X1154600Y491333D01*
G01X1158783Y492083D02*
X1159367Y491667D01*
X1160033Y491500D01*
X1160700Y491667D01*
X1161283Y492167D01*
X1161700Y492917D01*
X1161867Y493667D01*
Y494583D01*
X1161700Y495333D01*
X1161283Y496000D01*
X1160783Y496333D01*
X1160200Y496500D01*
X1159533Y496333D01*
X1159033Y496000D01*
X1158700Y495500D01*
X1158533Y494833D01*
X1158700Y494250D01*
X1159117Y493667D01*
X1159617Y493333D01*
X1160200Y493250D01*
X1160867Y493417D01*
X1161367Y493833D01*
X1161867Y494583D01*
G01X1163300Y491500D02*
Y494833D01*
G01Y493917D02*
X1163550Y494333D01*
X1163967Y494667D01*
X1164550Y494833D01*
X1165133Y494667D01*
X1165550Y494333D01*
X1165800Y493917D01*
Y491500D01*
G01Y493917D02*
X1166050Y494333D01*
X1166467Y494667D01*
X1167050Y494833D01*
X1167633Y494667D01*
X1168050Y494333D01*
X1168300Y493833D01*
Y491500D01*
G01X1168900D02*
Y494833D01*
G01Y493917D02*
X1169150Y494333D01*
X1169567Y494667D01*
X1170150Y494833D01*
X1170733Y494667D01*
X1171150Y494333D01*
X1171400Y493917D01*
Y491500D01*
G01Y493917D02*
X1171650Y494333D01*
X1172067Y494667D01*
X1172650Y494833D01*
X1173233Y494667D01*
X1173650Y494333D01*
X1173900Y493833D01*
Y491500D01*
G01X1177000Y491333D02*
X1176833Y491417D01*
Y491583D01*
X1177000Y491667D01*
X1177167Y491583D01*
Y491417D01*
X1177000Y491333D01*
G01Y493583D02*
X1176833Y493667D01*
Y493833D01*
X1177000Y493917D01*
X1177167Y493833D01*
Y493667D01*
X1177000Y493583D01*
G01X1045500Y504833D02*
X1047000Y501500D01*
X1048500Y504833D01*
G01X1052600D02*
Y501500D01*
G01Y506167D02*
X1052433Y506250D01*
Y506417D01*
X1052600Y506500D01*
X1052767Y506417D01*
Y506250D01*
X1052600Y506167D01*
G01X1059700Y501500D02*
Y504833D01*
G01Y504250D02*
X1059367Y504583D01*
X1058867Y504750D01*
X1058283Y504833D01*
X1057700Y504667D01*
X1057200Y504333D01*
X1056867Y503833D01*
X1056700Y503167D01*
X1056867Y502500D01*
X1057200Y502000D01*
X1057700Y501667D01*
X1058283Y501500D01*
X1058867Y501583D01*
X1059367Y501833D01*
X1059700Y502167D01*
G01X1068150Y502083D02*
X1068567Y501750D01*
X1069150Y501500D01*
X1069650D01*
X1070150Y501667D01*
X1070483Y501917D01*
X1070650Y502250D01*
X1070567Y502750D01*
X1070233Y503000D01*
X1068733Y503500D01*
X1068400Y504083D01*
X1068567Y504500D01*
X1068900Y504750D01*
X1069400Y504833D01*
X1069900Y504750D01*
X1070400Y504500D01*
G01X1073583Y501500D02*
Y506500D01*
G01Y504083D02*
X1074000Y504500D01*
X1074417Y504750D01*
X1075083Y504833D01*
X1075583Y504750D01*
X1076167Y504417D01*
X1076417Y503917D01*
Y501500D01*
G01X1082100D02*
Y504833D01*
G01Y504250D02*
X1081767Y504583D01*
X1081267Y504750D01*
X1080683Y504833D01*
X1080100Y504667D01*
X1079600Y504333D01*
X1079267Y503833D01*
X1079100Y503167D01*
X1079267Y502500D01*
X1079600Y502000D01*
X1080100Y501667D01*
X1080683Y501500D01*
X1081267Y501583D01*
X1081767Y501833D01*
X1082100Y502167D01*
G01X1086200Y501500D02*
Y506500D01*
G01X1091800Y501500D02*
Y506500D01*
G01X1101500Y501500D02*
Y506500D01*
G01Y504000D02*
X1101917Y504500D01*
X1102417Y504750D01*
X1102917Y504833D01*
X1103667Y504667D01*
X1104167Y504333D01*
X1104500Y503750D01*
Y503083D01*
X1104333Y502417D01*
X1104000Y501917D01*
X1103417Y501583D01*
X1102917Y501500D01*
X1102417Y501583D01*
X1101917Y501833D01*
X1101500Y502250D01*
G01X1107350Y503750D02*
X1110017D01*
X1109767Y504333D01*
X1109350Y504667D01*
X1108767Y504833D01*
X1108183Y504750D01*
X1107683Y504500D01*
X1107350Y503917D01*
X1107183Y503417D01*
Y502917D01*
X1107350Y502417D01*
X1107767Y501917D01*
X1108267Y501583D01*
X1108850Y501500D01*
X1109433Y501667D01*
X1110017Y502167D01*
G01X1118300Y499833D02*
Y504833D01*
G01Y504083D02*
X1118717Y504500D01*
X1119133Y504750D01*
X1119800Y504833D01*
X1120383Y504750D01*
X1120967Y504333D01*
X1121217Y503750D01*
X1121300Y503167D01*
X1121217Y502583D01*
X1120967Y502000D01*
X1120467Y501667D01*
X1119800Y501500D01*
X1119217Y501583D01*
X1118633Y501833D01*
X1118300Y502167D01*
G01X1125400Y501500D02*
Y506500D01*
G01X1129583Y504833D02*
Y502500D01*
X1129917Y501917D01*
X1130417Y501583D01*
X1131000Y501500D01*
X1131583Y501583D01*
X1132083Y501917D01*
X1132417Y502500D01*
G01Y501500D02*
Y504833D01*
G01X1135433Y500250D02*
X1136017Y499917D01*
X1136683Y499833D01*
X1137267Y499917D01*
X1137767Y500333D01*
X1138100Y500917D01*
Y504833D01*
G01Y504167D02*
X1137767Y504500D01*
X1137267Y504750D01*
X1136683Y504833D01*
X1136017Y504667D01*
X1135600Y504333D01*
X1135267Y503750D01*
X1135100Y503167D01*
X1135183Y502667D01*
X1135517Y502083D01*
X1136017Y501667D01*
X1136683Y501500D01*
X1137183Y501583D01*
X1137767Y501917D01*
X1138100Y502250D01*
G01X1141033Y500250D02*
X1141617Y499917D01*
X1142283Y499833D01*
X1142867Y499917D01*
X1143367Y500333D01*
X1143700Y500917D01*
Y504833D01*
G01Y504167D02*
X1143367Y504500D01*
X1142867Y504750D01*
X1142283Y504833D01*
X1141617Y504667D01*
X1141200Y504333D01*
X1140867Y503750D01*
X1140700Y503167D01*
X1140783Y502667D01*
X1141117Y502083D01*
X1141617Y501667D01*
X1142283Y501500D01*
X1142783Y501583D01*
X1143367Y501917D01*
X1143700Y502250D01*
G01X1146550Y503750D02*
X1149217D01*
X1148967Y504333D01*
X1148550Y504667D01*
X1147967Y504833D01*
X1147383Y504750D01*
X1146883Y504500D01*
X1146550Y503917D01*
X1146383Y503417D01*
Y502917D01*
X1146550Y502417D01*
X1146967Y501917D01*
X1147467Y501583D01*
X1148050Y501500D01*
X1148633Y501667D01*
X1149217Y502167D01*
G01X1154900Y506500D02*
Y501500D01*
G01Y502250D02*
X1154567Y501833D01*
X1154067Y501583D01*
X1153483Y501500D01*
X1152817Y501667D01*
X1152317Y502083D01*
X1151983Y502583D01*
X1151900Y503167D01*
X1151983Y503750D01*
X1152317Y504250D01*
X1152817Y504667D01*
X1153483Y504833D01*
X1154067Y504750D01*
X1154483Y504583D01*
X1154900Y504250D01*
G01X1162517Y504833D02*
X1163517Y501500D01*
X1164600Y504833D01*
X1165683Y501500D01*
X1166683Y504833D01*
G01X1170200D02*
Y501500D01*
G01Y506167D02*
X1170033Y506250D01*
Y506417D01*
X1170200Y506500D01*
X1170367Y506417D01*
Y506250D01*
X1170200Y506167D01*
G01X1175800Y506500D02*
Y501500D01*
G01X1174633Y504833D02*
X1176967D01*
G01X1179983Y501500D02*
Y506500D01*
G01Y504083D02*
X1180400Y504500D01*
X1180817Y504750D01*
X1181483Y504833D01*
X1181983Y504750D01*
X1182567Y504417D01*
X1182817Y503917D01*
Y501500D01*
G01X1194267D02*
X1190933Y503167D01*
X1194267Y504833D01*
G01X1201967Y502250D02*
X1202467Y501833D01*
X1203050Y501583D01*
X1203800Y501500D01*
X1204550Y501667D01*
X1205133Y502000D01*
X1205550Y502583D01*
X1205633Y503250D01*
X1205467Y503917D01*
X1205050Y504333D01*
X1204467Y504667D01*
X1203883Y504750D01*
X1203300Y504667D01*
X1202550Y504333D01*
X1202800Y506500D01*
X1205050D01*
G01X1209400D02*
X1208733Y506333D01*
X1208233Y505917D01*
X1207900Y505417D01*
X1207650Y504750D01*
X1207567Y504000D01*
X1207650Y503250D01*
X1207900Y502583D01*
X1208233Y502083D01*
X1208733Y501667D01*
X1209400Y501500D01*
X1210067Y501667D01*
X1210567Y502083D01*
X1210900Y502583D01*
X1211150Y503250D01*
X1211233Y504000D01*
X1211150Y504750D01*
X1210900Y505417D01*
X1210567Y505917D01*
X1210067Y506333D01*
X1209400Y506500D01*
G01X1219100Y501333D02*
X1222100Y506500D01*
G01X1219100D02*
X1218600Y506333D01*
X1218350Y506083D01*
X1218183Y505583D01*
X1218350Y505083D01*
X1218600Y504833D01*
X1219100Y504667D01*
X1219600Y504833D01*
X1219850Y505083D01*
X1220017Y505583D01*
X1219850Y506083D01*
X1219600Y506333D01*
X1219100Y506500D01*
G01X1222100Y503167D02*
X1221600Y503000D01*
X1221350Y502750D01*
X1221183Y502250D01*
X1221350Y501750D01*
X1221600Y501500D01*
X1222100Y501333D01*
X1222600Y501500D01*
X1222850Y501750D01*
X1223017Y502250D01*
X1222850Y502750D01*
X1222600Y503000D01*
X1222100Y503167D01*
G01X1230550Y502083D02*
X1230967Y501750D01*
X1231550Y501500D01*
X1232050D01*
X1232550Y501667D01*
X1232883Y501917D01*
X1233050Y502250D01*
X1232967Y502750D01*
X1232633Y503000D01*
X1231133Y503500D01*
X1230800Y504083D01*
X1230967Y504500D01*
X1231300Y504750D01*
X1231800Y504833D01*
X1232300Y504750D01*
X1232800Y504500D01*
G01X1237400Y501500D02*
X1236900Y501583D01*
X1236400Y501917D01*
X1236067Y502500D01*
X1235900Y503167D01*
X1236067Y503833D01*
X1236400Y504417D01*
X1236900Y504750D01*
X1237400Y504833D01*
X1237900Y504750D01*
X1238400Y504417D01*
X1238733Y503833D01*
X1238817Y503167D01*
X1238733Y502500D01*
X1238400Y501917D01*
X1237900Y501583D01*
X1237400Y501500D01*
G01X1243000D02*
Y506500D01*
G01X1250100D02*
Y501500D01*
G01Y502250D02*
X1249767Y501833D01*
X1249267Y501583D01*
X1248683Y501500D01*
X1248017Y501667D01*
X1247517Y502083D01*
X1247183Y502583D01*
X1247100Y503167D01*
X1247183Y503750D01*
X1247517Y504250D01*
X1248017Y504667D01*
X1248683Y504833D01*
X1249267Y504750D01*
X1249683Y504583D01*
X1250100Y504250D01*
G01X1252950Y503750D02*
X1255617D01*
X1255367Y504333D01*
X1254950Y504667D01*
X1254367Y504833D01*
X1253783Y504750D01*
X1253283Y504500D01*
X1252950Y503917D01*
X1252783Y503417D01*
Y502917D01*
X1252950Y502417D01*
X1253367Y501917D01*
X1253867Y501583D01*
X1254450Y501500D01*
X1255033Y501667D01*
X1255617Y502167D01*
G01X1258633Y501500D02*
Y504833D01*
G01Y504167D02*
X1259050Y504500D01*
X1259467Y504750D01*
X1260050Y504833D01*
X1260467Y504750D01*
X1260967Y504500D01*
G01X1268500Y501500D02*
Y504833D01*
G01Y503917D02*
X1268750Y504333D01*
X1269167Y504667D01*
X1269750Y504833D01*
X1270333Y504667D01*
X1270750Y504333D01*
X1271000Y503917D01*
Y501500D01*
G01Y503917D02*
X1271250Y504333D01*
X1271667Y504667D01*
X1272250Y504833D01*
X1272833Y504667D01*
X1273250Y504333D01*
X1273500Y503833D01*
Y501500D01*
G01X1278100D02*
Y504833D01*
G01Y504250D02*
X1277767Y504583D01*
X1277267Y504750D01*
X1276683Y504833D01*
X1276100Y504667D01*
X1275600Y504333D01*
X1275267Y503833D01*
X1275100Y503167D01*
X1275267Y502500D01*
X1275600Y502000D01*
X1276100Y501667D01*
X1276683Y501500D01*
X1277267Y501583D01*
X1277767Y501833D01*
X1278100Y502167D01*
G01X1280950Y502083D02*
X1281367Y501750D01*
X1281950Y501500D01*
X1282450D01*
X1282950Y501667D01*
X1283283Y501917D01*
X1283450Y502250D01*
X1283367Y502750D01*
X1283033Y503000D01*
X1281533Y503500D01*
X1281200Y504083D01*
X1281367Y504500D01*
X1281700Y504750D01*
X1282200Y504833D01*
X1282700Y504750D01*
X1283200Y504500D01*
G01X1286383Y501500D02*
Y506500D01*
G01X1289050Y504833D02*
X1286383Y502917D01*
G01X1287467Y503667D02*
X1289217Y501500D01*
G01X1293233Y500583D02*
X1293567Y501667D01*
G01X1038500Y510500D02*
Y513833D01*
G01Y513250D02*
X1038167Y513583D01*
X1037667Y513750D01*
X1037083Y513833D01*
X1036500Y513667D01*
X1036000Y513333D01*
X1035667Y512833D01*
X1035500Y512167D01*
X1035667Y511500D01*
X1036000Y511000D01*
X1036500Y510667D01*
X1037083Y510500D01*
X1037667Y510583D01*
X1038167Y510833D01*
X1038500Y511167D01*
G01X1042600Y510333D02*
X1042433Y510417D01*
Y510583D01*
X1042600Y510667D01*
X1042767Y510583D01*
Y510417D01*
X1042600Y510333D01*
G01X1048867Y513167D02*
X1049200Y513417D01*
X1049450Y513833D01*
X1049617Y514417D01*
X1049450Y514917D01*
X1049117Y515250D01*
X1048533Y515500D01*
X1046283D01*
Y510500D01*
X1049033D01*
X1049617Y510833D01*
X1049950Y511333D01*
X1050117Y511917D01*
X1049950Y512500D01*
X1049450Y513000D01*
X1048867Y513167D01*
X1046283D01*
G01X1053800Y510500D02*
X1053300Y510583D01*
X1052800Y510917D01*
X1052467Y511500D01*
X1052300Y512167D01*
X1052467Y512833D01*
X1052800Y513417D01*
X1053300Y513750D01*
X1053800Y513833D01*
X1054300Y513750D01*
X1054800Y513417D01*
X1055133Y512833D01*
X1055217Y512167D01*
X1055133Y511500D01*
X1054800Y510917D01*
X1054300Y510583D01*
X1053800Y510500D01*
G01X1060900D02*
Y513833D01*
G01Y513250D02*
X1060567Y513583D01*
X1060067Y513750D01*
X1059483Y513833D01*
X1058900Y513667D01*
X1058400Y513333D01*
X1058067Y512833D01*
X1057900Y512167D01*
X1058067Y511500D01*
X1058400Y511000D01*
X1058900Y510667D01*
X1059483Y510500D01*
X1060067Y510583D01*
X1060567Y510833D01*
X1060900Y511167D01*
G01X1063833Y510500D02*
Y513833D01*
G01Y513167D02*
X1064250Y513500D01*
X1064667Y513750D01*
X1065250Y513833D01*
X1065667Y513750D01*
X1066167Y513500D01*
G01X1072100Y515500D02*
Y510500D01*
G01Y511250D02*
X1071767Y510833D01*
X1071267Y510583D01*
X1070683Y510500D01*
X1070017Y510667D01*
X1069517Y511083D01*
X1069183Y511583D01*
X1069100Y512167D01*
X1069183Y512750D01*
X1069517Y513250D01*
X1070017Y513667D01*
X1070683Y513833D01*
X1071267Y513750D01*
X1071683Y513583D01*
X1072100Y513250D01*
G01X1081800Y515500D02*
Y510500D01*
G01X1080633Y513833D02*
X1082967D01*
G01X1085983Y510500D02*
Y515500D01*
G01Y513083D02*
X1086400Y513500D01*
X1086817Y513750D01*
X1087483Y513833D01*
X1087983Y513750D01*
X1088567Y513417D01*
X1088817Y512917D01*
Y510500D01*
G01X1093000Y513833D02*
Y510500D01*
G01Y515167D02*
X1092833Y515250D01*
Y515417D01*
X1093000Y515500D01*
X1093167Y515417D01*
Y515250D01*
X1093000Y515167D01*
G01X1099933Y513417D02*
X1099350Y513750D01*
X1098850Y513833D01*
X1098183Y513667D01*
X1097683Y513333D01*
X1097350Y512750D01*
X1097267Y512167D01*
X1097350Y511583D01*
X1097683Y511083D01*
X1098183Y510667D01*
X1098850Y510500D01*
X1099433Y510667D01*
X1099933Y511000D01*
G01X1102783Y510500D02*
Y515500D01*
G01X1105450Y513833D02*
X1102783Y511917D01*
G01X1103867Y512667D02*
X1105617Y510500D01*
G01X1108383D02*
Y513833D01*
G01Y513000D02*
X1108717Y513417D01*
X1109217Y513750D01*
X1109883Y513833D01*
X1110467Y513750D01*
X1110967Y513417D01*
X1111217Y512833D01*
Y510500D01*
G01X1114150Y512750D02*
X1116817D01*
X1116567Y513333D01*
X1116150Y513667D01*
X1115567Y513833D01*
X1114983Y513750D01*
X1114483Y513500D01*
X1114150Y512917D01*
X1113983Y512417D01*
Y511917D01*
X1114150Y511417D01*
X1114567Y510917D01*
X1115067Y510583D01*
X1115650Y510500D01*
X1116233Y510667D01*
X1116817Y511167D01*
G01X1119750Y511083D02*
X1120167Y510750D01*
X1120750Y510500D01*
X1121250D01*
X1121750Y510667D01*
X1122083Y510917D01*
X1122250Y511250D01*
X1122167Y511750D01*
X1121833Y512000D01*
X1120333Y512500D01*
X1120000Y513083D01*
X1120167Y513500D01*
X1120500Y513750D01*
X1121000Y513833D01*
X1121500Y513750D01*
X1122000Y513500D01*
G01X1125350Y511083D02*
X1125767Y510750D01*
X1126350Y510500D01*
X1126850D01*
X1127350Y510667D01*
X1127683Y510917D01*
X1127850Y511250D01*
X1127767Y511750D01*
X1127433Y512000D01*
X1125933Y512500D01*
X1125600Y513083D01*
X1125767Y513500D01*
X1126100Y513750D01*
X1126600Y513833D01*
X1127100Y513750D01*
X1127600Y513500D01*
G01X1130533Y510500D02*
X1133867Y512167D01*
X1130533Y513833D01*
G01X1136717Y511417D02*
X1138883D01*
G01Y512917D02*
X1136717D01*
G01X1149000Y515500D02*
X1148333Y515333D01*
X1147833Y514917D01*
X1147500Y514417D01*
X1147250Y513750D01*
X1147167Y513000D01*
X1147250Y512250D01*
X1147500Y511583D01*
X1147833Y511083D01*
X1148333Y510667D01*
X1149000Y510500D01*
X1149667Y510667D01*
X1150167Y511083D01*
X1150500Y511583D01*
X1150750Y512250D01*
X1150833Y513000D01*
X1150750Y513750D01*
X1150500Y514417D01*
X1150167Y514917D01*
X1149667Y515333D01*
X1149000Y515500D01*
G01X1154600Y510333D02*
X1154433Y510417D01*
Y510583D01*
X1154600Y510667D01*
X1154767Y510583D01*
Y510417D01*
X1154600Y510333D01*
G01X1158783Y511083D02*
X1159367Y510667D01*
X1160033Y510500D01*
X1160700Y510667D01*
X1161283Y511167D01*
X1161700Y511917D01*
X1161867Y512667D01*
Y513583D01*
X1161700Y514333D01*
X1161283Y515000D01*
X1160783Y515333D01*
X1160200Y515500D01*
X1159533Y515333D01*
X1159033Y515000D01*
X1158700Y514500D01*
X1158533Y513833D01*
X1158700Y513250D01*
X1159117Y512667D01*
X1159617Y512333D01*
X1160200Y512250D01*
X1160867Y512417D01*
X1161367Y512833D01*
X1161867Y513583D01*
G01X1163300Y510500D02*
Y513833D01*
G01Y512917D02*
X1163550Y513333D01*
X1163967Y513667D01*
X1164550Y513833D01*
X1165133Y513667D01*
X1165550Y513333D01*
X1165800Y512917D01*
Y510500D01*
G01Y512917D02*
X1166050Y513333D01*
X1166467Y513667D01*
X1167050Y513833D01*
X1167633Y513667D01*
X1168050Y513333D01*
X1168300Y512833D01*
Y510500D01*
G01X1171400Y510333D02*
X1171233Y510417D01*
Y510583D01*
X1171400Y510667D01*
X1171567Y510583D01*
Y510417D01*
X1171400Y510333D01*
G01Y512583D02*
X1171233Y512667D01*
Y512833D01*
X1171400Y512917D01*
X1171567Y512833D01*
Y512667D01*
X1171400Y512583D01*
G01X1034250Y520500D02*
Y525500D01*
G01X1037750D02*
Y520500D01*
G01Y523000D02*
X1034250D01*
G01X1043100Y520500D02*
Y523833D01*
G01Y523250D02*
X1042767Y523583D01*
X1042267Y523750D01*
X1041683Y523833D01*
X1041100Y523667D01*
X1040600Y523333D01*
X1040267Y522833D01*
X1040100Y522167D01*
X1040267Y521500D01*
X1040600Y521000D01*
X1041100Y520667D01*
X1041683Y520500D01*
X1042267Y520583D01*
X1042767Y520833D01*
X1043100Y521167D01*
G01X1047200Y520500D02*
Y525500D01*
G01X1052300Y520500D02*
Y524750D01*
X1052467Y525167D01*
X1052800Y525417D01*
X1053300Y525500D01*
X1053800Y525333D01*
X1054050Y524917D01*
G01X1053050Y523500D02*
X1051383D01*
G01X1057317Y522167D02*
X1059483D01*
G01X1062500Y518833D02*
Y523833D01*
G01Y523083D02*
X1062917Y523500D01*
X1063333Y523750D01*
X1064000Y523833D01*
X1064583Y523750D01*
X1065167Y523333D01*
X1065417Y522750D01*
X1065500Y522167D01*
X1065417Y521583D01*
X1065167Y521000D01*
X1064667Y520667D01*
X1064000Y520500D01*
X1063417Y520583D01*
X1062833Y520833D01*
X1062500Y521167D01*
G01X1069600Y520500D02*
Y525500D01*
G01X1073783Y523833D02*
Y521500D01*
X1074117Y520917D01*
X1074617Y520583D01*
X1075200Y520500D01*
X1075783Y520583D01*
X1076283Y520917D01*
X1076617Y521500D01*
G01Y520500D02*
Y523833D01*
G01X1079633Y519250D02*
X1080217Y518917D01*
X1080883Y518833D01*
X1081467Y518917D01*
X1081967Y519333D01*
X1082300Y519917D01*
Y523833D01*
G01Y523167D02*
X1081967Y523500D01*
X1081467Y523750D01*
X1080883Y523833D01*
X1080217Y523667D01*
X1079800Y523333D01*
X1079467Y522750D01*
X1079300Y522167D01*
X1079383Y521667D01*
X1079717Y521083D01*
X1080217Y520667D01*
X1080883Y520500D01*
X1081383Y520583D01*
X1081967Y520917D01*
X1082300Y521250D01*
G01X1085233Y519250D02*
X1085817Y518917D01*
X1086483Y518833D01*
X1087067Y518917D01*
X1087567Y519333D01*
X1087900Y519917D01*
Y523833D01*
G01Y523167D02*
X1087567Y523500D01*
X1087067Y523750D01*
X1086483Y523833D01*
X1085817Y523667D01*
X1085400Y523333D01*
X1085067Y522750D01*
X1084900Y522167D01*
X1084983Y521667D01*
X1085317Y521083D01*
X1085817Y520667D01*
X1086483Y520500D01*
X1086983Y520583D01*
X1087567Y520917D01*
X1087900Y521250D01*
G01X1092000Y523833D02*
Y520500D01*
G01Y525167D02*
X1091833Y525250D01*
Y525417D01*
X1092000Y525500D01*
X1092167Y525417D01*
Y525250D01*
X1092000Y525167D01*
G01X1096183Y520500D02*
Y523833D01*
G01Y523000D02*
X1096517Y523417D01*
X1097017Y523750D01*
X1097683Y523833D01*
X1098267Y523750D01*
X1098767Y523417D01*
X1099017Y522833D01*
Y520500D01*
G01X1102033Y519250D02*
X1102617Y518917D01*
X1103283Y518833D01*
X1103867Y518917D01*
X1104367Y519333D01*
X1104700Y519917D01*
Y523833D01*
G01Y523167D02*
X1104367Y523500D01*
X1103867Y523750D01*
X1103283Y523833D01*
X1102617Y523667D01*
X1102200Y523333D01*
X1101867Y522750D01*
X1101700Y522167D01*
X1101783Y521667D01*
X1102117Y521083D01*
X1102617Y520667D01*
X1103283Y520500D01*
X1103783Y520583D01*
X1104367Y520917D01*
X1104700Y521250D01*
G01X1114400Y520333D02*
X1114233Y520417D01*
Y520583D01*
X1114400Y520667D01*
X1114567Y520583D01*
Y520417D01*
X1114400Y520333D01*
G01Y522583D02*
X1114233Y522667D01*
Y522833D01*
X1114400Y522917D01*
X1114567Y522833D01*
Y522667D01*
X1114400Y522583D01*
G01X1125600Y525500D02*
Y520500D01*
G01X1124433Y523833D02*
X1126767D01*
G01X1129783Y520500D02*
Y525500D01*
G01Y523083D02*
X1130200Y523500D01*
X1130617Y523750D01*
X1131283Y523833D01*
X1131783Y523750D01*
X1132367Y523417D01*
X1132617Y522917D01*
Y520500D01*
G01X1135550Y522750D02*
X1138217D01*
X1137967Y523333D01*
X1137550Y523667D01*
X1136967Y523833D01*
X1136383Y523750D01*
X1135883Y523500D01*
X1135550Y522917D01*
X1135383Y522417D01*
Y521917D01*
X1135550Y521417D01*
X1135967Y520917D01*
X1136467Y520583D01*
X1137050Y520500D01*
X1137633Y520667D01*
X1138217Y521167D01*
G01X1146500Y518833D02*
Y523833D01*
G01Y523083D02*
X1146917Y523500D01*
X1147333Y523750D01*
X1148000Y523833D01*
X1148583Y523750D01*
X1149167Y523333D01*
X1149417Y522750D01*
X1149500Y522167D01*
X1149417Y521583D01*
X1149167Y521000D01*
X1148667Y520667D01*
X1148000Y520500D01*
X1147417Y520583D01*
X1146833Y520833D01*
X1146500Y521167D01*
G01X1153600Y520500D02*
Y525500D01*
G01X1157783Y523833D02*
Y521500D01*
X1158117Y520917D01*
X1158617Y520583D01*
X1159200Y520500D01*
X1159783Y520583D01*
X1160283Y520917D01*
X1160617Y521500D01*
G01Y520500D02*
Y523833D01*
G01X1163633Y519250D02*
X1164217Y518917D01*
X1164883Y518833D01*
X1165467Y518917D01*
X1165967Y519333D01*
X1166300Y519917D01*
Y523833D01*
G01Y523167D02*
X1165967Y523500D01*
X1165467Y523750D01*
X1164883Y523833D01*
X1164217Y523667D01*
X1163800Y523333D01*
X1163467Y522750D01*
X1163300Y522167D01*
X1163383Y521667D01*
X1163717Y521083D01*
X1164217Y520667D01*
X1164883Y520500D01*
X1165383Y520583D01*
X1165967Y520917D01*
X1166300Y521250D01*
G01X1169233Y519250D02*
X1169817Y518917D01*
X1170483Y518833D01*
X1171067Y518917D01*
X1171567Y519333D01*
X1171900Y519917D01*
Y523833D01*
G01Y523167D02*
X1171567Y523500D01*
X1171067Y523750D01*
X1170483Y523833D01*
X1169817Y523667D01*
X1169400Y523333D01*
X1169067Y522750D01*
X1168900Y522167D01*
X1168983Y521667D01*
X1169317Y521083D01*
X1169817Y520667D01*
X1170483Y520500D01*
X1170983Y520583D01*
X1171567Y520917D01*
X1171900Y521250D01*
G01X1176000Y523833D02*
Y520500D01*
G01Y525167D02*
X1175833Y525250D01*
Y525417D01*
X1176000Y525500D01*
X1176167Y525417D01*
Y525250D01*
X1176000Y525167D01*
G01X1180183Y520500D02*
Y523833D01*
G01Y523000D02*
X1180517Y523417D01*
X1181017Y523750D01*
X1181683Y523833D01*
X1182267Y523750D01*
X1182767Y523417D01*
X1183017Y522833D01*
Y520500D01*
G01X1186033Y519250D02*
X1186617Y518917D01*
X1187283Y518833D01*
X1187867Y518917D01*
X1188367Y519333D01*
X1188700Y519917D01*
Y523833D01*
G01Y523167D02*
X1188367Y523500D01*
X1187867Y523750D01*
X1187283Y523833D01*
X1186617Y523667D01*
X1186200Y523333D01*
X1185867Y522750D01*
X1185700Y522167D01*
X1185783Y521667D01*
X1186117Y521083D01*
X1186617Y520667D01*
X1187283Y520500D01*
X1187783Y520583D01*
X1188367Y520917D01*
X1188700Y521250D01*
G01X1197233Y520500D02*
Y523833D01*
G01Y523167D02*
X1197650Y523500D01*
X1198067Y523750D01*
X1198650Y523833D01*
X1199067Y523750D01*
X1199567Y523500D01*
G01X1205500Y520500D02*
Y523833D01*
G01Y523250D02*
X1205167Y523583D01*
X1204667Y523750D01*
X1204083Y523833D01*
X1203500Y523667D01*
X1203000Y523333D01*
X1202667Y522833D01*
X1202500Y522167D01*
X1202667Y521500D01*
X1203000Y521000D01*
X1203500Y520667D01*
X1204083Y520500D01*
X1204667Y520583D01*
X1205167Y520833D01*
X1205500Y521167D01*
G01X1209600Y525500D02*
Y520500D01*
G01X1208433Y523833D02*
X1210767D01*
G01X1215200D02*
Y520500D01*
G01Y525167D02*
X1215033Y525250D01*
Y525417D01*
X1215200Y525500D01*
X1215367Y525417D01*
Y525250D01*
X1215200Y525167D01*
G01X1220800Y520500D02*
X1220300Y520583D01*
X1219800Y520917D01*
X1219467Y521500D01*
X1219300Y522167D01*
X1219467Y522833D01*
X1219800Y523417D01*
X1220300Y523750D01*
X1220800Y523833D01*
X1221300Y523750D01*
X1221800Y523417D01*
X1222133Y522833D01*
X1222217Y522167D01*
X1222133Y521500D01*
X1221800Y520917D01*
X1221300Y520583D01*
X1220800Y520500D01*
G01X1230500Y518833D02*
Y523833D01*
G01Y523083D02*
X1230917Y523500D01*
X1231333Y523750D01*
X1232000Y523833D01*
X1232583Y523750D01*
X1233167Y523333D01*
X1233417Y522750D01*
X1233500Y522167D01*
X1233417Y521583D01*
X1233167Y521000D01*
X1232667Y520667D01*
X1232000Y520500D01*
X1231417Y520583D01*
X1230833Y520833D01*
X1230500Y521167D01*
G01X1236350Y522750D02*
X1239017D01*
X1238767Y523333D01*
X1238350Y523667D01*
X1237767Y523833D01*
X1237183Y523750D01*
X1236683Y523500D01*
X1236350Y522917D01*
X1236183Y522417D01*
Y521917D01*
X1236350Y521417D01*
X1236767Y520917D01*
X1237267Y520583D01*
X1237850Y520500D01*
X1238433Y520667D01*
X1239017Y521167D01*
G01X1242033Y520500D02*
Y523833D01*
G01Y523167D02*
X1242450Y523500D01*
X1242867Y523750D01*
X1243450Y523833D01*
X1243867Y523750D01*
X1244367Y523500D01*
G01X1253900Y520500D02*
Y524750D01*
X1254067Y525167D01*
X1254400Y525417D01*
X1254900Y525500D01*
X1255400Y525333D01*
X1255650Y524917D01*
G01X1254650Y523500D02*
X1252983D01*
G01X1260000Y520500D02*
X1259500Y520583D01*
X1259000Y520917D01*
X1258667Y521500D01*
X1258500Y522167D01*
X1258667Y522833D01*
X1259000Y523417D01*
X1259500Y523750D01*
X1260000Y523833D01*
X1260500Y523750D01*
X1261000Y523417D01*
X1261333Y522833D01*
X1261417Y522167D01*
X1261333Y521500D01*
X1261000Y520917D01*
X1260500Y520583D01*
X1260000Y520500D01*
G01X1265600D02*
Y525500D01*
G01X1271200Y520500D02*
Y525500D01*
G01X1276800Y520500D02*
X1276300Y520583D01*
X1275800Y520917D01*
X1275467Y521500D01*
X1275300Y522167D01*
X1275467Y522833D01*
X1275800Y523417D01*
X1276300Y523750D01*
X1276800Y523833D01*
X1277300Y523750D01*
X1277800Y523417D01*
X1278133Y522833D01*
X1278217Y522167D01*
X1278133Y521500D01*
X1277800Y520917D01*
X1277300Y520583D01*
X1276800Y520500D01*
G01X1280317Y523833D02*
X1281317Y520500D01*
X1282400Y523833D01*
X1283483Y520500D01*
X1284483Y523833D01*
G01X1288000D02*
Y520500D01*
G01Y525167D02*
X1287833Y525250D01*
Y525417D01*
X1288000Y525500D01*
X1288167Y525417D01*
Y525250D01*
X1288000Y525167D01*
G01X1292183Y520500D02*
Y523833D01*
G01Y523000D02*
X1292517Y523417D01*
X1293017Y523750D01*
X1293683Y523833D01*
X1294267Y523750D01*
X1294767Y523417D01*
X1295017Y522833D01*
Y520500D01*
G01X1298033Y519250D02*
X1298617Y518917D01*
X1299283Y518833D01*
X1299867Y518917D01*
X1300367Y519333D01*
X1300700Y519917D01*
Y523833D01*
G01Y523167D02*
X1300367Y523500D01*
X1299867Y523750D01*
X1299283Y523833D01*
X1298617Y523667D01*
X1298200Y523333D01*
X1297867Y522750D01*
X1297700Y522167D01*
X1297783Y521667D01*
X1298117Y521083D01*
X1298617Y520667D01*
X1299283Y520500D01*
X1299783Y520583D01*
X1300367Y520917D01*
X1300700Y521250D01*
G01X1304800Y520333D02*
X1304633Y520417D01*
Y520583D01*
X1304800Y520667D01*
X1304967Y520583D01*
Y520417D01*
X1304800Y520333D01*
G01Y522583D02*
X1304633Y522667D01*
Y522833D01*
X1304800Y522917D01*
X1304967Y522833D01*
Y522667D01*
X1304800Y522583D01*
G01X1033500Y529500D02*
Y534500D01*
G01Y532000D02*
X1033917Y532500D01*
X1034417Y532750D01*
X1034917Y532833D01*
X1035667Y532667D01*
X1036167Y532333D01*
X1036500Y531750D01*
Y531083D01*
X1036333Y530417D01*
X1036000Y529917D01*
X1035417Y529583D01*
X1034917Y529500D01*
X1034417Y529583D01*
X1033917Y529833D01*
X1033500Y530250D01*
G01X1039350Y531750D02*
X1042017D01*
X1041767Y532333D01*
X1041350Y532667D01*
X1040767Y532833D01*
X1040183Y532750D01*
X1039683Y532500D01*
X1039350Y531917D01*
X1039183Y531417D01*
Y530917D01*
X1039350Y530417D01*
X1039767Y529917D01*
X1040267Y529583D01*
X1040850Y529500D01*
X1041433Y529667D01*
X1042017Y530167D01*
G01X1051300Y529500D02*
Y533750D01*
X1051467Y534167D01*
X1051800Y534417D01*
X1052300Y534500D01*
X1052800Y534333D01*
X1053050Y533917D01*
G01X1052050Y532500D02*
X1050383D01*
G01X1056233Y529500D02*
Y532833D01*
G01Y532167D02*
X1056650Y532500D01*
X1057067Y532750D01*
X1057650Y532833D01*
X1058067Y532750D01*
X1058567Y532500D01*
G01X1061750Y531750D02*
X1064417D01*
X1064167Y532333D01*
X1063750Y532667D01*
X1063167Y532833D01*
X1062583Y532750D01*
X1062083Y532500D01*
X1061750Y531917D01*
X1061583Y531417D01*
Y530917D01*
X1061750Y530417D01*
X1062167Y529917D01*
X1062667Y529583D01*
X1063250Y529500D01*
X1063833Y529667D01*
X1064417Y530167D01*
G01X1067350Y531750D02*
X1070017D01*
X1069767Y532333D01*
X1069350Y532667D01*
X1068767Y532833D01*
X1068183Y532750D01*
X1067683Y532500D01*
X1067350Y531917D01*
X1067183Y531417D01*
Y530917D01*
X1067350Y530417D01*
X1067767Y529917D01*
X1068267Y529583D01*
X1068850Y529500D01*
X1069433Y529667D01*
X1070017Y530167D01*
G01X1079300Y529500D02*
Y533750D01*
X1079467Y534167D01*
X1079800Y534417D01*
X1080300Y534500D01*
X1080800Y534333D01*
X1081050Y533917D01*
G01X1080050Y532500D02*
X1078383D01*
G01X1084233Y529500D02*
Y532833D01*
G01Y532167D02*
X1084650Y532500D01*
X1085067Y532750D01*
X1085650Y532833D01*
X1086067Y532750D01*
X1086567Y532500D01*
G01X1091000Y529500D02*
X1090500Y529583D01*
X1090000Y529917D01*
X1089667Y530500D01*
X1089500Y531167D01*
X1089667Y531833D01*
X1090000Y532417D01*
X1090500Y532750D01*
X1091000Y532833D01*
X1091500Y532750D01*
X1092000Y532417D01*
X1092333Y531833D01*
X1092417Y531167D01*
X1092333Y530500D01*
X1092000Y529917D01*
X1091500Y529583D01*
X1091000Y529500D01*
G01X1094100D02*
Y532833D01*
G01Y531917D02*
X1094350Y532333D01*
X1094767Y532667D01*
X1095350Y532833D01*
X1095933Y532667D01*
X1096350Y532333D01*
X1096600Y531917D01*
Y529500D01*
G01Y531917D02*
X1096850Y532333D01*
X1097267Y532667D01*
X1097850Y532833D01*
X1098433Y532667D01*
X1098850Y532333D01*
X1099100Y531833D01*
Y529500D01*
G01X1106550Y530083D02*
X1106967Y529750D01*
X1107550Y529500D01*
X1108050D01*
X1108550Y529667D01*
X1108883Y529917D01*
X1109050Y530250D01*
X1108967Y530750D01*
X1108633Y531000D01*
X1107133Y531500D01*
X1106800Y532083D01*
X1106967Y532500D01*
X1107300Y532750D01*
X1107800Y532833D01*
X1108300Y532750D01*
X1108800Y532500D01*
G01X1113400Y529500D02*
X1112900Y529583D01*
X1112400Y529917D01*
X1112067Y530500D01*
X1111900Y531167D01*
X1112067Y531833D01*
X1112400Y532417D01*
X1112900Y532750D01*
X1113400Y532833D01*
X1113900Y532750D01*
X1114400Y532417D01*
X1114733Y531833D01*
X1114817Y531167D01*
X1114733Y530500D01*
X1114400Y529917D01*
X1113900Y529583D01*
X1113400Y529500D01*
G01X1119000D02*
Y534500D01*
G01X1126100D02*
Y529500D01*
G01Y530250D02*
X1125767Y529833D01*
X1125267Y529583D01*
X1124683Y529500D01*
X1124017Y529667D01*
X1123517Y530083D01*
X1123183Y530583D01*
X1123100Y531167D01*
X1123183Y531750D01*
X1123517Y532250D01*
X1124017Y532667D01*
X1124683Y532833D01*
X1125267Y532750D01*
X1125683Y532583D01*
X1126100Y532250D01*
G01X1128950Y531750D02*
X1131617D01*
X1131367Y532333D01*
X1130950Y532667D01*
X1130367Y532833D01*
X1129783Y532750D01*
X1129283Y532500D01*
X1128950Y531917D01*
X1128783Y531417D01*
Y530917D01*
X1128950Y530417D01*
X1129367Y529917D01*
X1129867Y529583D01*
X1130450Y529500D01*
X1131033Y529667D01*
X1131617Y530167D01*
G01X1134633Y529500D02*
Y532833D01*
G01Y532167D02*
X1135050Y532500D01*
X1135467Y532750D01*
X1136050Y532833D01*
X1136467Y532750D01*
X1136967Y532500D01*
G01X1144500Y529500D02*
Y532833D01*
G01Y531917D02*
X1144750Y532333D01*
X1145167Y532667D01*
X1145750Y532833D01*
X1146333Y532667D01*
X1146750Y532333D01*
X1147000Y531917D01*
Y529500D01*
G01Y531917D02*
X1147250Y532333D01*
X1147667Y532667D01*
X1148250Y532833D01*
X1148833Y532667D01*
X1149250Y532333D01*
X1149500Y531833D01*
Y529500D01*
G01X1154100D02*
Y532833D01*
G01Y532250D02*
X1153767Y532583D01*
X1153267Y532750D01*
X1152683Y532833D01*
X1152100Y532667D01*
X1151600Y532333D01*
X1151267Y531833D01*
X1151100Y531167D01*
X1151267Y530500D01*
X1151600Y530000D01*
X1152100Y529667D01*
X1152683Y529500D01*
X1153267Y529583D01*
X1153767Y529833D01*
X1154100Y530167D01*
G01X1156950Y530083D02*
X1157367Y529750D01*
X1157950Y529500D01*
X1158450D01*
X1158950Y529667D01*
X1159283Y529917D01*
X1159450Y530250D01*
X1159367Y530750D01*
X1159033Y531000D01*
X1157533Y531500D01*
X1157200Y532083D01*
X1157367Y532500D01*
X1157700Y532750D01*
X1158200Y532833D01*
X1158700Y532750D01*
X1159200Y532500D01*
G01X1162383Y529500D02*
Y534500D01*
G01X1165050Y532833D02*
X1162383Y530917D01*
G01X1163467Y531667D02*
X1165217Y529500D01*
G01X1169400Y529333D02*
X1169233Y529417D01*
Y529583D01*
X1169400Y529667D01*
X1169567Y529583D01*
Y529417D01*
X1169400Y529333D01*
G01X1020417Y542667D02*
X1020917Y543167D01*
X1021500Y543417D01*
X1022167Y543500D01*
X1023000Y543333D01*
X1023583Y542917D01*
X1023750Y542417D01*
X1023667Y541917D01*
X1023333Y541500D01*
X1021667Y540667D01*
X1020917Y540083D01*
X1020417Y539250D01*
X1020250Y538500D01*
X1023750D01*
G01X1027600Y538333D02*
X1027433Y538417D01*
Y538583D01*
X1027600Y538667D01*
X1027767Y538583D01*
Y538417D01*
X1027600Y538333D01*
G01X1033200Y543500D02*
Y538500D01*
G01X1031283Y543500D02*
X1035117D01*
G01X1037383Y538500D02*
Y543500D01*
G01Y541083D02*
X1037800Y541500D01*
X1038217Y541750D01*
X1038883Y541833D01*
X1039383Y541750D01*
X1039967Y541417D01*
X1040217Y540917D01*
Y538500D01*
G01X1043150Y540750D02*
X1045817D01*
X1045567Y541333D01*
X1045150Y541667D01*
X1044567Y541833D01*
X1043983Y541750D01*
X1043483Y541500D01*
X1043150Y540917D01*
X1042983Y540417D01*
Y539917D01*
X1043150Y539417D01*
X1043567Y538917D01*
X1044067Y538583D01*
X1044650Y538500D01*
X1045233Y538667D01*
X1045817Y539167D01*
G01X1054350Y539083D02*
X1054767Y538750D01*
X1055350Y538500D01*
X1055850D01*
X1056350Y538667D01*
X1056683Y538917D01*
X1056850Y539250D01*
X1056767Y539750D01*
X1056433Y540000D01*
X1054933Y540500D01*
X1054600Y541083D01*
X1054767Y541500D01*
X1055100Y541750D01*
X1055600Y541833D01*
X1056100Y541750D01*
X1056600Y541500D01*
G01X1061200Y541833D02*
Y538500D01*
G01Y543167D02*
X1061033Y543250D01*
Y543417D01*
X1061200Y543500D01*
X1061367Y543417D01*
Y543250D01*
X1061200Y543167D01*
G01X1068300Y543500D02*
Y538500D01*
G01Y539250D02*
X1067967Y538833D01*
X1067467Y538583D01*
X1066883Y538500D01*
X1066217Y538667D01*
X1065717Y539083D01*
X1065383Y539583D01*
X1065300Y540167D01*
X1065383Y540750D01*
X1065717Y541250D01*
X1066217Y541667D01*
X1066883Y541833D01*
X1067467Y541750D01*
X1067883Y541583D01*
X1068300Y541250D01*
G01X1071150Y540750D02*
X1073817D01*
X1073567Y541333D01*
X1073150Y541667D01*
X1072567Y541833D01*
X1071983Y541750D01*
X1071483Y541500D01*
X1071150Y540917D01*
X1070983Y540417D01*
Y539917D01*
X1071150Y539417D01*
X1071567Y538917D01*
X1072067Y538583D01*
X1072650Y538500D01*
X1073233Y538667D01*
X1073817Y539167D01*
G01X1081517Y541833D02*
X1082517Y538500D01*
X1083600Y541833D01*
X1084683Y538500D01*
X1085683Y541833D01*
G01X1089200D02*
Y538500D01*
G01Y543167D02*
X1089033Y543250D01*
Y543417D01*
X1089200Y543500D01*
X1089367Y543417D01*
Y543250D01*
X1089200Y543167D01*
G01X1094800Y543500D02*
Y538500D01*
G01X1093633Y541833D02*
X1095967D01*
G01X1098983Y538500D02*
Y543500D01*
G01Y541083D02*
X1099400Y541500D01*
X1099817Y541750D01*
X1100483Y541833D01*
X1100983Y541750D01*
X1101567Y541417D01*
X1101817Y540917D01*
Y538500D01*
G01X1110350Y539083D02*
X1110767Y538750D01*
X1111350Y538500D01*
X1111850D01*
X1112350Y538667D01*
X1112683Y538917D01*
X1112850Y539250D01*
X1112767Y539750D01*
X1112433Y540000D01*
X1110933Y540500D01*
X1110600Y541083D01*
X1110767Y541500D01*
X1111100Y541750D01*
X1111600Y541833D01*
X1112100Y541750D01*
X1112600Y541500D01*
G01X1117200Y538500D02*
X1116700Y538583D01*
X1116200Y538917D01*
X1115867Y539500D01*
X1115700Y540167D01*
X1115867Y540833D01*
X1116200Y541417D01*
X1116700Y541750D01*
X1117200Y541833D01*
X1117700Y541750D01*
X1118200Y541417D01*
X1118533Y540833D01*
X1118617Y540167D01*
X1118533Y539500D01*
X1118200Y538917D01*
X1117700Y538583D01*
X1117200Y538500D01*
G01X1122800D02*
Y543500D01*
G01X1129900D02*
Y538500D01*
G01Y539250D02*
X1129567Y538833D01*
X1129067Y538583D01*
X1128483Y538500D01*
X1127817Y538667D01*
X1127317Y539083D01*
X1126983Y539583D01*
X1126900Y540167D01*
X1126983Y540750D01*
X1127317Y541250D01*
X1127817Y541667D01*
X1128483Y541833D01*
X1129067Y541750D01*
X1129483Y541583D01*
X1129900Y541250D01*
G01X1132750Y540750D02*
X1135417D01*
X1135167Y541333D01*
X1134750Y541667D01*
X1134167Y541833D01*
X1133583Y541750D01*
X1133083Y541500D01*
X1132750Y540917D01*
X1132583Y540417D01*
Y539917D01*
X1132750Y539417D01*
X1133167Y538917D01*
X1133667Y538583D01*
X1134250Y538500D01*
X1134833Y538667D01*
X1135417Y539167D01*
G01X1138433Y538500D02*
Y541833D01*
G01Y541167D02*
X1138850Y541500D01*
X1139267Y541750D01*
X1139850Y541833D01*
X1140267Y541750D01*
X1140767Y541500D01*
G01X1148300Y538500D02*
Y541833D01*
G01Y540917D02*
X1148550Y541333D01*
X1148967Y541667D01*
X1149550Y541833D01*
X1150133Y541667D01*
X1150550Y541333D01*
X1150800Y540917D01*
Y538500D01*
G01Y540917D02*
X1151050Y541333D01*
X1151467Y541667D01*
X1152050Y541833D01*
X1152633Y541667D01*
X1153050Y541333D01*
X1153300Y540833D01*
Y538500D01*
G01X1157900D02*
Y541833D01*
G01Y541250D02*
X1157567Y541583D01*
X1157067Y541750D01*
X1156483Y541833D01*
X1155900Y541667D01*
X1155400Y541333D01*
X1155067Y540833D01*
X1154900Y540167D01*
X1155067Y539500D01*
X1155400Y539000D01*
X1155900Y538667D01*
X1156483Y538500D01*
X1157067Y538583D01*
X1157567Y538833D01*
X1157900Y539167D01*
G01X1160750Y539083D02*
X1161167Y538750D01*
X1161750Y538500D01*
X1162250D01*
X1162750Y538667D01*
X1163083Y538917D01*
X1163250Y539250D01*
X1163167Y539750D01*
X1162833Y540000D01*
X1161333Y540500D01*
X1161000Y541083D01*
X1161167Y541500D01*
X1161500Y541750D01*
X1162000Y541833D01*
X1162500Y541750D01*
X1163000Y541500D01*
G01X1166183Y538500D02*
Y543500D01*
G01X1168850Y541833D02*
X1166183Y539917D01*
G01X1167267Y540667D02*
X1169017Y538500D01*
G01X1177300Y536833D02*
Y541833D01*
G01Y541083D02*
X1177717Y541500D01*
X1178133Y541750D01*
X1178800Y541833D01*
X1179383Y541750D01*
X1179967Y541333D01*
X1180217Y540750D01*
X1180300Y540167D01*
X1180217Y539583D01*
X1179967Y539000D01*
X1179467Y538667D01*
X1178800Y538500D01*
X1178217Y538583D01*
X1177633Y538833D01*
X1177300Y539167D01*
G01X1185900Y538500D02*
Y541833D01*
G01Y541250D02*
X1185567Y541583D01*
X1185067Y541750D01*
X1184483Y541833D01*
X1183900Y541667D01*
X1183400Y541333D01*
X1183067Y540833D01*
X1182900Y540167D01*
X1183067Y539500D01*
X1183400Y539000D01*
X1183900Y538667D01*
X1184483Y538500D01*
X1185067Y538583D01*
X1185567Y538833D01*
X1185900Y539167D01*
G01X1191500Y543500D02*
Y538500D01*
G01Y539250D02*
X1191167Y538833D01*
X1190667Y538583D01*
X1190083Y538500D01*
X1189417Y538667D01*
X1188917Y539083D01*
X1188583Y539583D01*
X1188500Y540167D01*
X1188583Y540750D01*
X1188917Y541250D01*
X1189417Y541667D01*
X1190083Y541833D01*
X1190667Y541750D01*
X1191083Y541583D01*
X1191500Y541250D01*
G01X1195433Y537583D02*
X1195767Y538667D01*
G01X1206800Y543500D02*
Y538500D01*
G01X1205633Y541833D02*
X1207967D01*
G01X1210983Y538500D02*
Y543500D01*
G01Y541083D02*
X1211400Y541500D01*
X1211817Y541750D01*
X1212483Y541833D01*
X1212983Y541750D01*
X1213567Y541417D01*
X1213817Y540917D01*
Y538500D01*
G01X1216750Y540750D02*
X1219417D01*
X1219167Y541333D01*
X1218750Y541667D01*
X1218167Y541833D01*
X1217583Y541750D01*
X1217083Y541500D01*
X1216750Y540917D01*
X1216583Y540417D01*
Y539917D01*
X1216750Y539417D01*
X1217167Y538917D01*
X1217667Y538583D01*
X1218250Y538500D01*
X1218833Y538667D01*
X1219417Y539167D01*
G01X1230700Y538500D02*
Y541833D01*
G01Y541250D02*
X1230367Y541583D01*
X1229867Y541750D01*
X1229283Y541833D01*
X1228700Y541667D01*
X1228200Y541333D01*
X1227867Y540833D01*
X1227700Y540167D01*
X1227867Y539500D01*
X1228200Y539000D01*
X1228700Y538667D01*
X1229283Y538500D01*
X1229867Y538583D01*
X1230367Y538833D01*
X1230700Y539167D01*
G01X1233383Y538500D02*
Y541833D01*
G01Y541000D02*
X1233717Y541417D01*
X1234217Y541750D01*
X1234883Y541833D01*
X1235467Y541750D01*
X1235967Y541417D01*
X1236217Y540833D01*
Y538500D01*
G01X1238983D02*
Y541833D01*
G01Y541000D02*
X1239317Y541417D01*
X1239817Y541750D01*
X1240483Y541833D01*
X1241067Y541750D01*
X1241567Y541417D01*
X1241817Y540833D01*
Y538500D01*
G01X1244583Y541833D02*
Y539500D01*
X1244917Y538917D01*
X1245417Y538583D01*
X1246000Y538500D01*
X1246583Y538583D01*
X1247083Y538917D01*
X1247417Y539500D01*
G01Y538500D02*
Y541833D01*
G01X1253100Y538500D02*
Y541833D01*
G01Y541250D02*
X1252767Y541583D01*
X1252267Y541750D01*
X1251683Y541833D01*
X1251100Y541667D01*
X1250600Y541333D01*
X1250267Y540833D01*
X1250100Y540167D01*
X1250267Y539500D01*
X1250600Y539000D01*
X1251100Y538667D01*
X1251683Y538500D01*
X1252267Y538583D01*
X1252767Y538833D01*
X1253100Y539167D01*
G01X1257200Y538500D02*
Y543500D01*
G01X1267233Y538500D02*
Y541833D01*
G01Y541167D02*
X1267650Y541500D01*
X1268067Y541750D01*
X1268650Y541833D01*
X1269067Y541750D01*
X1269567Y541500D01*
G01X1274000Y541833D02*
Y538500D01*
G01Y543167D02*
X1273833Y543250D01*
Y543417D01*
X1274000Y543500D01*
X1274167Y543417D01*
Y543250D01*
X1274000Y543167D01*
G01X1278183Y538500D02*
Y541833D01*
G01Y541000D02*
X1278517Y541417D01*
X1279017Y541750D01*
X1279683Y541833D01*
X1280267Y541750D01*
X1280767Y541417D01*
X1281017Y540833D01*
Y538500D01*
G01X1284033Y537250D02*
X1284617Y536917D01*
X1285283Y536833D01*
X1285867Y536917D01*
X1286367Y537333D01*
X1286700Y537917D01*
Y541833D01*
G01Y541167D02*
X1286367Y541500D01*
X1285867Y541750D01*
X1285283Y541833D01*
X1284617Y541667D01*
X1284200Y541333D01*
X1283867Y540750D01*
X1283700Y540167D01*
X1283783Y539667D01*
X1284117Y539083D01*
X1284617Y538667D01*
X1285283Y538500D01*
X1285783Y538583D01*
X1286367Y538917D01*
X1286700Y539250D01*
G01X1295150Y539083D02*
X1295567Y538750D01*
X1296150Y538500D01*
X1296650D01*
X1297150Y538667D01*
X1297483Y538917D01*
X1297650Y539250D01*
X1297567Y539750D01*
X1297233Y540000D01*
X1295733Y540500D01*
X1295400Y541083D01*
X1295567Y541500D01*
X1295900Y541750D01*
X1296400Y541833D01*
X1296900Y541750D01*
X1297400Y541500D01*
G01X1300583Y538500D02*
Y543500D01*
G01Y541083D02*
X1301000Y541500D01*
X1301417Y541750D01*
X1302083Y541833D01*
X1302583Y541750D01*
X1303167Y541417D01*
X1303417Y540917D01*
Y538500D01*
G01X1307600D02*
X1307100Y538583D01*
X1306600Y538917D01*
X1306267Y539500D01*
X1306100Y540167D01*
X1306267Y540833D01*
X1306600Y541417D01*
X1307100Y541750D01*
X1307600Y541833D01*
X1308100Y541750D01*
X1308600Y541417D01*
X1308933Y540833D01*
X1309017Y540167D01*
X1308933Y539500D01*
X1308600Y538917D01*
X1308100Y538583D01*
X1307600Y538500D01*
G01X1311783Y541833D02*
Y539500D01*
X1312117Y538917D01*
X1312617Y538583D01*
X1313200Y538500D01*
X1313783Y538583D01*
X1314283Y538917D01*
X1314617Y539500D01*
G01Y538500D02*
Y541833D01*
G01X1318800Y538500D02*
Y543500D01*
G01X1325900D02*
Y538500D01*
G01Y539250D02*
X1325567Y538833D01*
X1325067Y538583D01*
X1324483Y538500D01*
X1323817Y538667D01*
X1323317Y539083D01*
X1322983Y539583D01*
X1322900Y540167D01*
X1322983Y540750D01*
X1323317Y541250D01*
X1323817Y541667D01*
X1324483Y541833D01*
X1325067Y541750D01*
X1325483Y541583D01*
X1325900Y541250D01*
G01X1032500Y552500D02*
Y557500D01*
G01Y555000D02*
X1032917Y555500D01*
X1033417Y555750D01*
X1033917Y555833D01*
X1034667Y555667D01*
X1035167Y555333D01*
X1035500Y554750D01*
Y554083D01*
X1035333Y553417D01*
X1035000Y552917D01*
X1034417Y552583D01*
X1033917Y552500D01*
X1033417Y552583D01*
X1032917Y552833D01*
X1032500Y553250D01*
G01X1038350Y554750D02*
X1041017D01*
X1040767Y555333D01*
X1040350Y555667D01*
X1039767Y555833D01*
X1039183Y555750D01*
X1038683Y555500D01*
X1038350Y554917D01*
X1038183Y554417D01*
Y553917D01*
X1038350Y553417D01*
X1038767Y552917D01*
X1039267Y552583D01*
X1039850Y552500D01*
X1040433Y552667D01*
X1041017Y553167D01*
G01X1050800Y557500D02*
Y552500D01*
G01X1049633Y555833D02*
X1051967D01*
G01X1055150Y554750D02*
X1057817D01*
X1057567Y555333D01*
X1057150Y555667D01*
X1056567Y555833D01*
X1055983Y555750D01*
X1055483Y555500D01*
X1055150Y554917D01*
X1054983Y554417D01*
Y553917D01*
X1055150Y553417D01*
X1055567Y552917D01*
X1056067Y552583D01*
X1056650Y552500D01*
X1057233Y552667D01*
X1057817Y553167D01*
G01X1060583Y552500D02*
Y555833D01*
G01Y555000D02*
X1060917Y555417D01*
X1061417Y555750D01*
X1062083Y555833D01*
X1062667Y555750D01*
X1063167Y555417D01*
X1063417Y554833D01*
Y552500D01*
G01X1067600Y557500D02*
Y552500D01*
G01X1066433Y555833D02*
X1068767D01*
G01X1071950Y554750D02*
X1074617D01*
X1074367Y555333D01*
X1073950Y555667D01*
X1073367Y555833D01*
X1072783Y555750D01*
X1072283Y555500D01*
X1071950Y554917D01*
X1071783Y554417D01*
Y553917D01*
X1071950Y553417D01*
X1072367Y552917D01*
X1072867Y552583D01*
X1073450Y552500D01*
X1074033Y552667D01*
X1074617Y553167D01*
G01X1080300Y557500D02*
Y552500D01*
G01Y553250D02*
X1079967Y552833D01*
X1079467Y552583D01*
X1078883Y552500D01*
X1078217Y552667D01*
X1077717Y553083D01*
X1077383Y553583D01*
X1077300Y554167D01*
X1077383Y554750D01*
X1077717Y555250D01*
X1078217Y555667D01*
X1078883Y555833D01*
X1079467Y555750D01*
X1079883Y555583D01*
X1080300Y555250D01*
G01X1087917Y555833D02*
X1088917Y552500D01*
X1090000Y555833D01*
X1091083Y552500D01*
X1092083Y555833D01*
G01X1095600D02*
Y552500D01*
G01Y557167D02*
X1095433Y557250D01*
Y557417D01*
X1095600Y557500D01*
X1095767Y557417D01*
Y557250D01*
X1095600Y557167D01*
G01X1101200Y557500D02*
Y552500D01*
G01X1100033Y555833D02*
X1102367D01*
G01X1105383Y552500D02*
Y557500D01*
G01Y555083D02*
X1105800Y555500D01*
X1106217Y555750D01*
X1106883Y555833D01*
X1107383Y555750D01*
X1107967Y555417D01*
X1108217Y554917D01*
Y552500D01*
G01X1116750Y553083D02*
X1117167Y552750D01*
X1117750Y552500D01*
X1118250D01*
X1118750Y552667D01*
X1119083Y552917D01*
X1119250Y553250D01*
X1119167Y553750D01*
X1118833Y554000D01*
X1117333Y554500D01*
X1117000Y555083D01*
X1117167Y555500D01*
X1117500Y555750D01*
X1118000Y555833D01*
X1118500Y555750D01*
X1119000Y555500D01*
G01X1123600Y552500D02*
X1123100Y552583D01*
X1122600Y552917D01*
X1122267Y553500D01*
X1122100Y554167D01*
X1122267Y554833D01*
X1122600Y555417D01*
X1123100Y555750D01*
X1123600Y555833D01*
X1124100Y555750D01*
X1124600Y555417D01*
X1124933Y554833D01*
X1125017Y554167D01*
X1124933Y553500D01*
X1124600Y552917D01*
X1124100Y552583D01*
X1123600Y552500D01*
G01X1129200D02*
Y557500D01*
G01X1136300D02*
Y552500D01*
G01Y553250D02*
X1135967Y552833D01*
X1135467Y552583D01*
X1134883Y552500D01*
X1134217Y552667D01*
X1133717Y553083D01*
X1133383Y553583D01*
X1133300Y554167D01*
X1133383Y554750D01*
X1133717Y555250D01*
X1134217Y555667D01*
X1134883Y555833D01*
X1135467Y555750D01*
X1135883Y555583D01*
X1136300Y555250D01*
G01X1139150Y554750D02*
X1141817D01*
X1141567Y555333D01*
X1141150Y555667D01*
X1140567Y555833D01*
X1139983Y555750D01*
X1139483Y555500D01*
X1139150Y554917D01*
X1138983Y554417D01*
Y553917D01*
X1139150Y553417D01*
X1139567Y552917D01*
X1140067Y552583D01*
X1140650Y552500D01*
X1141233Y552667D01*
X1141817Y553167D01*
G01X1144833Y552500D02*
Y555833D01*
G01Y555167D02*
X1145250Y555500D01*
X1145667Y555750D01*
X1146250Y555833D01*
X1146667Y555750D01*
X1147167Y555500D01*
G01X1154700Y552500D02*
Y555833D01*
G01Y554917D02*
X1154950Y555333D01*
X1155367Y555667D01*
X1155950Y555833D01*
X1156533Y555667D01*
X1156950Y555333D01*
X1157200Y554917D01*
Y552500D01*
G01Y554917D02*
X1157450Y555333D01*
X1157867Y555667D01*
X1158450Y555833D01*
X1159033Y555667D01*
X1159450Y555333D01*
X1159700Y554833D01*
Y552500D01*
G01X1164300D02*
Y555833D01*
G01Y555250D02*
X1163967Y555583D01*
X1163467Y555750D01*
X1162883Y555833D01*
X1162300Y555667D01*
X1161800Y555333D01*
X1161467Y554833D01*
X1161300Y554167D01*
X1161467Y553500D01*
X1161800Y553000D01*
X1162300Y552667D01*
X1162883Y552500D01*
X1163467Y552583D01*
X1163967Y552833D01*
X1164300Y553167D01*
G01X1167150Y553083D02*
X1167567Y552750D01*
X1168150Y552500D01*
X1168650D01*
X1169150Y552667D01*
X1169483Y552917D01*
X1169650Y553250D01*
X1169567Y553750D01*
X1169233Y554000D01*
X1167733Y554500D01*
X1167400Y555083D01*
X1167567Y555500D01*
X1167900Y555750D01*
X1168400Y555833D01*
X1168900Y555750D01*
X1169400Y555500D01*
G01X1172583Y552500D02*
Y557500D01*
G01X1175250Y555833D02*
X1172583Y553917D01*
G01X1173667Y554667D02*
X1175417Y552500D01*
G01X1179600Y552333D02*
X1179433Y552417D01*
Y552583D01*
X1179600Y552667D01*
X1179767Y552583D01*
Y552417D01*
X1179600Y552333D01*
G01X1034000Y566500D02*
Y561500D01*
G01X1032833Y564833D02*
X1035167D01*
G01X1039600Y561500D02*
X1039100Y561583D01*
X1038600Y561917D01*
X1038267Y562500D01*
X1038100Y563167D01*
X1038267Y563833D01*
X1038600Y564417D01*
X1039100Y564750D01*
X1039600Y564833D01*
X1040100Y564750D01*
X1040600Y564417D01*
X1040933Y563833D01*
X1041017Y563167D01*
X1040933Y562500D01*
X1040600Y561917D01*
X1040100Y561583D01*
X1039600Y561500D01*
G01X1049300D02*
Y566500D01*
G01Y564000D02*
X1049717Y564500D01*
X1050217Y564750D01*
X1050717Y564833D01*
X1051467Y564667D01*
X1051967Y564333D01*
X1052300Y563750D01*
Y563083D01*
X1052133Y562417D01*
X1051800Y561917D01*
X1051217Y561583D01*
X1050717Y561500D01*
X1050217Y561583D01*
X1049717Y561833D01*
X1049300Y562250D01*
G01X1055150Y563750D02*
X1057817D01*
X1057567Y564333D01*
X1057150Y564667D01*
X1056567Y564833D01*
X1055983Y564750D01*
X1055483Y564500D01*
X1055150Y563917D01*
X1054983Y563417D01*
Y562917D01*
X1055150Y562417D01*
X1055567Y561917D01*
X1056067Y561583D01*
X1056650Y561500D01*
X1057233Y561667D01*
X1057817Y562167D01*
G01X1068933Y564417D02*
X1068350Y564750D01*
X1067850Y564833D01*
X1067183Y564667D01*
X1066683Y564333D01*
X1066350Y563750D01*
X1066267Y563167D01*
X1066350Y562583D01*
X1066683Y562083D01*
X1067183Y561667D01*
X1067850Y561500D01*
X1068433Y561667D01*
X1068933Y562000D01*
G01X1073200Y561500D02*
X1072700Y561583D01*
X1072200Y561917D01*
X1071867Y562500D01*
X1071700Y563167D01*
X1071867Y563833D01*
X1072200Y564417D01*
X1072700Y564750D01*
X1073200Y564833D01*
X1073700Y564750D01*
X1074200Y564417D01*
X1074533Y563833D01*
X1074617Y563167D01*
X1074533Y562500D01*
X1074200Y561917D01*
X1073700Y561583D01*
X1073200Y561500D01*
G01X1077300Y564833D02*
X1078800Y561500D01*
X1080300Y564833D01*
G01X1083150Y563750D02*
X1085817D01*
X1085567Y564333D01*
X1085150Y564667D01*
X1084567Y564833D01*
X1083983Y564750D01*
X1083483Y564500D01*
X1083150Y563917D01*
X1082983Y563417D01*
Y562917D01*
X1083150Y562417D01*
X1083567Y561917D01*
X1084067Y561583D01*
X1084650Y561500D01*
X1085233Y561667D01*
X1085817Y562167D01*
G01X1088833Y561500D02*
Y564833D01*
G01Y564167D02*
X1089250Y564500D01*
X1089667Y564750D01*
X1090250Y564833D01*
X1090667Y564750D01*
X1091167Y564500D01*
G01X1094350Y563750D02*
X1097017D01*
X1096767Y564333D01*
X1096350Y564667D01*
X1095767Y564833D01*
X1095183Y564750D01*
X1094683Y564500D01*
X1094350Y563917D01*
X1094183Y563417D01*
Y562917D01*
X1094350Y562417D01*
X1094767Y561917D01*
X1095267Y561583D01*
X1095850Y561500D01*
X1096433Y561667D01*
X1097017Y562167D01*
G01X1102700Y566500D02*
Y561500D01*
G01Y562250D02*
X1102367Y561833D01*
X1101867Y561583D01*
X1101283Y561500D01*
X1100617Y561667D01*
X1100117Y562083D01*
X1099783Y562583D01*
X1099700Y563167D01*
X1099783Y563750D01*
X1100117Y564250D01*
X1100617Y564667D01*
X1101283Y564833D01*
X1101867Y564750D01*
X1102283Y564583D01*
X1102700Y564250D01*
G01X1110900Y561500D02*
Y566500D01*
G01Y564000D02*
X1111317Y564500D01*
X1111817Y564750D01*
X1112317Y564833D01*
X1113067Y564667D01*
X1113567Y564333D01*
X1113900Y563750D01*
Y563083D01*
X1113733Y562417D01*
X1113400Y561917D01*
X1112817Y561583D01*
X1112317Y561500D01*
X1111817Y561583D01*
X1111317Y561833D01*
X1110900Y562250D01*
G01X1116250Y560000D02*
X1116750Y559833D01*
X1117417Y560000D01*
X1117833Y560333D01*
X1118167Y560750D01*
X1118667Y562083D01*
X1119750Y564833D01*
G01X1117083D02*
X1118667Y562083D01*
G01X1127950D02*
X1128367Y561750D01*
X1128950Y561500D01*
X1129450D01*
X1129950Y561667D01*
X1130283Y561917D01*
X1130450Y562250D01*
X1130367Y562750D01*
X1130033Y563000D01*
X1128533Y563500D01*
X1128200Y564083D01*
X1128367Y564500D01*
X1128700Y564750D01*
X1129200Y564833D01*
X1129700Y564750D01*
X1130200Y564500D01*
G01X1134800Y561500D02*
X1134300Y561583D01*
X1133800Y561917D01*
X1133467Y562500D01*
X1133300Y563167D01*
X1133467Y563833D01*
X1133800Y564417D01*
X1134300Y564750D01*
X1134800Y564833D01*
X1135300Y564750D01*
X1135800Y564417D01*
X1136133Y563833D01*
X1136217Y563167D01*
X1136133Y562500D01*
X1135800Y561917D01*
X1135300Y561583D01*
X1134800Y561500D01*
G01X1140400D02*
Y566500D01*
G01X1147500D02*
Y561500D01*
G01Y562250D02*
X1147167Y561833D01*
X1146667Y561583D01*
X1146083Y561500D01*
X1145417Y561667D01*
X1144917Y562083D01*
X1144583Y562583D01*
X1144500Y563167D01*
X1144583Y563750D01*
X1144917Y564250D01*
X1145417Y564667D01*
X1146083Y564833D01*
X1146667Y564750D01*
X1147083Y564583D01*
X1147500Y564250D01*
G01X1150350Y563750D02*
X1153017D01*
X1152767Y564333D01*
X1152350Y564667D01*
X1151767Y564833D01*
X1151183Y564750D01*
X1150683Y564500D01*
X1150350Y563917D01*
X1150183Y563417D01*
Y562917D01*
X1150350Y562417D01*
X1150767Y561917D01*
X1151267Y561583D01*
X1151850Y561500D01*
X1152433Y561667D01*
X1153017Y562167D01*
G01X1156033Y561500D02*
Y564833D01*
G01Y564167D02*
X1156450Y564500D01*
X1156867Y564750D01*
X1157450Y564833D01*
X1157867Y564750D01*
X1158367Y564500D01*
G01X1165900Y561500D02*
Y564833D01*
G01Y563917D02*
X1166150Y564333D01*
X1166567Y564667D01*
X1167150Y564833D01*
X1167733Y564667D01*
X1168150Y564333D01*
X1168400Y563917D01*
Y561500D01*
G01Y563917D02*
X1168650Y564333D01*
X1169067Y564667D01*
X1169650Y564833D01*
X1170233Y564667D01*
X1170650Y564333D01*
X1170900Y563833D01*
Y561500D01*
G01X1175500D02*
Y564833D01*
G01Y564250D02*
X1175167Y564583D01*
X1174667Y564750D01*
X1174083Y564833D01*
X1173500Y564667D01*
X1173000Y564333D01*
X1172667Y563833D01*
X1172500Y563167D01*
X1172667Y562500D01*
X1173000Y562000D01*
X1173500Y561667D01*
X1174083Y561500D01*
X1174667Y561583D01*
X1175167Y561833D01*
X1175500Y562167D01*
G01X1178350Y562083D02*
X1178767Y561750D01*
X1179350Y561500D01*
X1179850D01*
X1180350Y561667D01*
X1180683Y561917D01*
X1180850Y562250D01*
X1180767Y562750D01*
X1180433Y563000D01*
X1178933Y563500D01*
X1178600Y564083D01*
X1178767Y564500D01*
X1179100Y564750D01*
X1179600Y564833D01*
X1180100Y564750D01*
X1180600Y564500D01*
G01X1183783Y561500D02*
Y566500D01*
G01X1186450Y564833D02*
X1183783Y562917D01*
G01X1184867Y563667D02*
X1186617Y561500D01*
G01X1197900D02*
Y564833D01*
G01Y564250D02*
X1197567Y564583D01*
X1197067Y564750D01*
X1196483Y564833D01*
X1195900Y564667D01*
X1195400Y564333D01*
X1195067Y563833D01*
X1194900Y563167D01*
X1195067Y562500D01*
X1195400Y562000D01*
X1195900Y561667D01*
X1196483Y561500D01*
X1197067Y561583D01*
X1197567Y561833D01*
X1197900Y562167D01*
G01X1200583Y561500D02*
Y564833D01*
G01Y564000D02*
X1200917Y564417D01*
X1201417Y564750D01*
X1202083Y564833D01*
X1202667Y564750D01*
X1203167Y564417D01*
X1203417Y563833D01*
Y561500D01*
G01X1209100Y566500D02*
Y561500D01*
G01Y562250D02*
X1208767Y561833D01*
X1208267Y561583D01*
X1207683Y561500D01*
X1207017Y561667D01*
X1206517Y562083D01*
X1206183Y562583D01*
X1206100Y563167D01*
X1206183Y563750D01*
X1206517Y564250D01*
X1207017Y564667D01*
X1207683Y564833D01*
X1208267Y564750D01*
X1208683Y564583D01*
X1209100Y564250D01*
G01X1217383Y561500D02*
Y566500D01*
G01Y564083D02*
X1217800Y564500D01*
X1218217Y564750D01*
X1218883Y564833D01*
X1219383Y564750D01*
X1219967Y564417D01*
X1220217Y563917D01*
Y561500D01*
G01X1224400D02*
X1223900Y561583D01*
X1223400Y561917D01*
X1223067Y562500D01*
X1222900Y563167D01*
X1223067Y563833D01*
X1223400Y564417D01*
X1223900Y564750D01*
X1224400Y564833D01*
X1224900Y564750D01*
X1225400Y564417D01*
X1225733Y563833D01*
X1225817Y563167D01*
X1225733Y562500D01*
X1225400Y561917D01*
X1224900Y561583D01*
X1224400Y561500D01*
G01X1230000D02*
Y566500D01*
G01X1234350Y563750D02*
X1237017D01*
X1236767Y564333D01*
X1236350Y564667D01*
X1235767Y564833D01*
X1235183Y564750D01*
X1234683Y564500D01*
X1234350Y563917D01*
X1234183Y563417D01*
Y562917D01*
X1234350Y562417D01*
X1234767Y561917D01*
X1235267Y561583D01*
X1235850Y561500D01*
X1236433Y561667D01*
X1237017Y562167D01*
G01X1248300Y561500D02*
Y564833D01*
G01Y564250D02*
X1247967Y564583D01*
X1247467Y564750D01*
X1246883Y564833D01*
X1246300Y564667D01*
X1245800Y564333D01*
X1245467Y563833D01*
X1245300Y563167D01*
X1245467Y562500D01*
X1245800Y562000D01*
X1246300Y561667D01*
X1246883Y561500D01*
X1247467Y561583D01*
X1247967Y561833D01*
X1248300Y562167D01*
G01X1252400Y561500D02*
Y566500D01*
G01X1256750Y562083D02*
X1257167Y561750D01*
X1257750Y561500D01*
X1258250D01*
X1258750Y561667D01*
X1259083Y561917D01*
X1259250Y562250D01*
X1259167Y562750D01*
X1258833Y563000D01*
X1257333Y563500D01*
X1257000Y564083D01*
X1257167Y564500D01*
X1257500Y564750D01*
X1258000Y564833D01*
X1258500Y564750D01*
X1259000Y564500D01*
G01X1263600Y561500D02*
X1263100Y561583D01*
X1262600Y561917D01*
X1262267Y562500D01*
X1262100Y563167D01*
X1262267Y563833D01*
X1262600Y564417D01*
X1263100Y564750D01*
X1263600Y564833D01*
X1264100Y564750D01*
X1264600Y564417D01*
X1264933Y563833D01*
X1265017Y563167D01*
X1264933Y562500D01*
X1264600Y561917D01*
X1264100Y561583D01*
X1263600Y561500D01*
G01X1273383D02*
Y564833D01*
G01Y564000D02*
X1273717Y564417D01*
X1274217Y564750D01*
X1274883Y564833D01*
X1275467Y564750D01*
X1275967Y564417D01*
X1276217Y563833D01*
Y561500D01*
G01X1279150Y563750D02*
X1281817D01*
X1281567Y564333D01*
X1281150Y564667D01*
X1280567Y564833D01*
X1279983Y564750D01*
X1279483Y564500D01*
X1279150Y563917D01*
X1278983Y563417D01*
Y562917D01*
X1279150Y562417D01*
X1279567Y561917D01*
X1280067Y561583D01*
X1280650Y561500D01*
X1281233Y561667D01*
X1281817Y562167D01*
G01X1284750Y563750D02*
X1287417D01*
X1287167Y564333D01*
X1286750Y564667D01*
X1286167Y564833D01*
X1285583Y564750D01*
X1285083Y564500D01*
X1284750Y563917D01*
X1284583Y563417D01*
Y562917D01*
X1284750Y562417D01*
X1285167Y561917D01*
X1285667Y561583D01*
X1286250Y561500D01*
X1286833Y561667D01*
X1287417Y562167D01*
G01X1293100Y566500D02*
Y561500D01*
G01Y562250D02*
X1292767Y561833D01*
X1292267Y561583D01*
X1291683Y561500D01*
X1291017Y561667D01*
X1290517Y562083D01*
X1290183Y562583D01*
X1290100Y563167D01*
X1290183Y563750D01*
X1290517Y564250D01*
X1291017Y564667D01*
X1291683Y564833D01*
X1292267Y564750D01*
X1292683Y564583D01*
X1293100Y564250D01*
G01X1302800Y566500D02*
Y561500D01*
G01X1301633Y564833D02*
X1303967D01*
G01X1308400Y561500D02*
X1307900Y561583D01*
X1307400Y561917D01*
X1307067Y562500D01*
X1306900Y563167D01*
X1307067Y563833D01*
X1307400Y564417D01*
X1307900Y564750D01*
X1308400Y564833D01*
X1308900Y564750D01*
X1309400Y564417D01*
X1309733Y563833D01*
X1309817Y563167D01*
X1309733Y562500D01*
X1309400Y561917D01*
X1308900Y561583D01*
X1308400Y561500D01*
G01X1022000Y569500D02*
Y574500D01*
X1021000Y573500D01*
G01Y569500D02*
X1023000D01*
G01X1027600Y569333D02*
X1027433Y569417D01*
Y569583D01*
X1027600Y569667D01*
X1027767Y569583D01*
Y569417D01*
X1027600Y569333D01*
G01X1033200Y574500D02*
Y569500D01*
G01X1031283Y574500D02*
X1035117D01*
G01X1037383Y569500D02*
Y574500D01*
G01Y572083D02*
X1037800Y572500D01*
X1038217Y572750D01*
X1038883Y572833D01*
X1039383Y572750D01*
X1039967Y572417D01*
X1040217Y571917D01*
Y569500D01*
G01X1043150Y571750D02*
X1045817D01*
X1045567Y572333D01*
X1045150Y572667D01*
X1044567Y572833D01*
X1043983Y572750D01*
X1043483Y572500D01*
X1043150Y571917D01*
X1042983Y571417D01*
Y570917D01*
X1043150Y570417D01*
X1043567Y569917D01*
X1044067Y569583D01*
X1044650Y569500D01*
X1045233Y569667D01*
X1045817Y570167D01*
G01X1054350Y570083D02*
X1054767Y569750D01*
X1055350Y569500D01*
X1055850D01*
X1056350Y569667D01*
X1056683Y569917D01*
X1056850Y570250D01*
X1056767Y570750D01*
X1056433Y571000D01*
X1054933Y571500D01*
X1054600Y572083D01*
X1054767Y572500D01*
X1055100Y572750D01*
X1055600Y572833D01*
X1056100Y572750D01*
X1056600Y572500D01*
G01X1061200Y572833D02*
Y569500D01*
G01Y574167D02*
X1061033Y574250D01*
Y574417D01*
X1061200Y574500D01*
X1061367Y574417D01*
Y574250D01*
X1061200Y574167D01*
G01X1068300Y574500D02*
Y569500D01*
G01Y570250D02*
X1067967Y569833D01*
X1067467Y569583D01*
X1066883Y569500D01*
X1066217Y569667D01*
X1065717Y570083D01*
X1065383Y570583D01*
X1065300Y571167D01*
X1065383Y571750D01*
X1065717Y572250D01*
X1066217Y572667D01*
X1066883Y572833D01*
X1067467Y572750D01*
X1067883Y572583D01*
X1068300Y572250D01*
G01X1071150Y571750D02*
X1073817D01*
X1073567Y572333D01*
X1073150Y572667D01*
X1072567Y572833D01*
X1071983Y572750D01*
X1071483Y572500D01*
X1071150Y571917D01*
X1070983Y571417D01*
Y570917D01*
X1071150Y570417D01*
X1071567Y569917D01*
X1072067Y569583D01*
X1072650Y569500D01*
X1073233Y569667D01*
X1073817Y570167D01*
G01X1081517Y572833D02*
X1082517Y569500D01*
X1083600Y572833D01*
X1084683Y569500D01*
X1085683Y572833D01*
G01X1089200D02*
Y569500D01*
G01Y574167D02*
X1089033Y574250D01*
Y574417D01*
X1089200Y574500D01*
X1089367Y574417D01*
Y574250D01*
X1089200Y574167D01*
G01X1094800Y574500D02*
Y569500D01*
G01X1093633Y572833D02*
X1095967D01*
G01X1098983Y569500D02*
Y574500D01*
G01Y572083D02*
X1099400Y572500D01*
X1099817Y572750D01*
X1100483Y572833D01*
X1100983Y572750D01*
X1101567Y572417D01*
X1101817Y571917D01*
Y569500D01*
G01X1106000D02*
X1105500Y569583D01*
X1105000Y569917D01*
X1104667Y570500D01*
X1104500Y571167D01*
X1104667Y571833D01*
X1105000Y572417D01*
X1105500Y572750D01*
X1106000Y572833D01*
X1106500Y572750D01*
X1107000Y572417D01*
X1107333Y571833D01*
X1107417Y571167D01*
X1107333Y570500D01*
X1107000Y569917D01*
X1106500Y569583D01*
X1106000Y569500D01*
G01X1110183Y572833D02*
Y570500D01*
X1110517Y569917D01*
X1111017Y569583D01*
X1111600Y569500D01*
X1112183Y569583D01*
X1112683Y569917D01*
X1113017Y570500D01*
G01Y569500D02*
Y572833D01*
G01X1117200Y574500D02*
Y569500D01*
G01X1116033Y572833D02*
X1118367D01*
G01X1127150Y570083D02*
X1127567Y569750D01*
X1128150Y569500D01*
X1128650D01*
X1129150Y569667D01*
X1129483Y569917D01*
X1129650Y570250D01*
X1129567Y570750D01*
X1129233Y571000D01*
X1127733Y571500D01*
X1127400Y572083D01*
X1127567Y572500D01*
X1127900Y572750D01*
X1128400Y572833D01*
X1128900Y572750D01*
X1129400Y572500D01*
G01X1134000Y569500D02*
X1133500Y569583D01*
X1133000Y569917D01*
X1132667Y570500D01*
X1132500Y571167D01*
X1132667Y571833D01*
X1133000Y572417D01*
X1133500Y572750D01*
X1134000Y572833D01*
X1134500Y572750D01*
X1135000Y572417D01*
X1135333Y571833D01*
X1135417Y571167D01*
X1135333Y570500D01*
X1135000Y569917D01*
X1134500Y569583D01*
X1134000Y569500D01*
G01X1139600D02*
Y574500D01*
G01X1146700D02*
Y569500D01*
G01Y570250D02*
X1146367Y569833D01*
X1145867Y569583D01*
X1145283Y569500D01*
X1144617Y569667D01*
X1144117Y570083D01*
X1143783Y570583D01*
X1143700Y571167D01*
X1143783Y571750D01*
X1144117Y572250D01*
X1144617Y572667D01*
X1145283Y572833D01*
X1145867Y572750D01*
X1146283Y572583D01*
X1146700Y572250D01*
G01X1149550Y571750D02*
X1152217D01*
X1151967Y572333D01*
X1151550Y572667D01*
X1150967Y572833D01*
X1150383Y572750D01*
X1149883Y572500D01*
X1149550Y571917D01*
X1149383Y571417D01*
Y570917D01*
X1149550Y570417D01*
X1149967Y569917D01*
X1150467Y569583D01*
X1151050Y569500D01*
X1151633Y569667D01*
X1152217Y570167D01*
G01X1155233Y569500D02*
Y572833D01*
G01Y572167D02*
X1155650Y572500D01*
X1156067Y572750D01*
X1156650Y572833D01*
X1157067Y572750D01*
X1157567Y572500D01*
G01X1165100Y569500D02*
Y572833D01*
G01Y571917D02*
X1165350Y572333D01*
X1165767Y572667D01*
X1166350Y572833D01*
X1166933Y572667D01*
X1167350Y572333D01*
X1167600Y571917D01*
Y569500D01*
G01Y571917D02*
X1167850Y572333D01*
X1168267Y572667D01*
X1168850Y572833D01*
X1169433Y572667D01*
X1169850Y572333D01*
X1170100Y571833D01*
Y569500D01*
G01X1174700D02*
Y572833D01*
G01Y572250D02*
X1174367Y572583D01*
X1173867Y572750D01*
X1173283Y572833D01*
X1172700Y572667D01*
X1172200Y572333D01*
X1171867Y571833D01*
X1171700Y571167D01*
X1171867Y570500D01*
X1172200Y570000D01*
X1172700Y569667D01*
X1173283Y569500D01*
X1173867Y569583D01*
X1174367Y569833D01*
X1174700Y570167D01*
G01X1177550Y570083D02*
X1177967Y569750D01*
X1178550Y569500D01*
X1179050D01*
X1179550Y569667D01*
X1179883Y569917D01*
X1180050Y570250D01*
X1179967Y570750D01*
X1179633Y571000D01*
X1178133Y571500D01*
X1177800Y572083D01*
X1177967Y572500D01*
X1178300Y572750D01*
X1178800Y572833D01*
X1179300Y572750D01*
X1179800Y572500D01*
G01X1182983Y569500D02*
Y574500D01*
G01X1185650Y572833D02*
X1182983Y570917D01*
G01X1184067Y571667D02*
X1185817Y569500D01*
G01X1194100Y567833D02*
Y572833D01*
G01Y572083D02*
X1194517Y572500D01*
X1194933Y572750D01*
X1195600Y572833D01*
X1196183Y572750D01*
X1196767Y572333D01*
X1197017Y571750D01*
X1197100Y571167D01*
X1197017Y570583D01*
X1196767Y570000D01*
X1196267Y569667D01*
X1195600Y569500D01*
X1195017Y569583D01*
X1194433Y569833D01*
X1194100Y570167D01*
G01X1202700Y569500D02*
Y572833D01*
G01Y572250D02*
X1202367Y572583D01*
X1201867Y572750D01*
X1201283Y572833D01*
X1200700Y572667D01*
X1200200Y572333D01*
X1199867Y571833D01*
X1199700Y571167D01*
X1199867Y570500D01*
X1200200Y570000D01*
X1200700Y569667D01*
X1201283Y569500D01*
X1201867Y569583D01*
X1202367Y569833D01*
X1202700Y570167D01*
G01X1208300Y574500D02*
Y569500D01*
G01Y570250D02*
X1207967Y569833D01*
X1207467Y569583D01*
X1206883Y569500D01*
X1206217Y569667D01*
X1205717Y570083D01*
X1205383Y570583D01*
X1205300Y571167D01*
X1205383Y571750D01*
X1205717Y572250D01*
X1206217Y572667D01*
X1206883Y572833D01*
X1207467Y572750D01*
X1207883Y572583D01*
X1208300Y572250D01*
G01X1217833Y568583D02*
X1218167Y569667D01*
G01X1230700Y569500D02*
Y572833D01*
G01Y572250D02*
X1230367Y572583D01*
X1229867Y572750D01*
X1229283Y572833D01*
X1228700Y572667D01*
X1228200Y572333D01*
X1227867Y571833D01*
X1227700Y571167D01*
X1227867Y570500D01*
X1228200Y570000D01*
X1228700Y569667D01*
X1229283Y569500D01*
X1229867Y569583D01*
X1230367Y569833D01*
X1230700Y570167D01*
G01X1233383Y569500D02*
Y572833D01*
G01Y572000D02*
X1233717Y572417D01*
X1234217Y572750D01*
X1234883Y572833D01*
X1235467Y572750D01*
X1235967Y572417D01*
X1236217Y571833D01*
Y569500D01*
G01X1238983D02*
Y572833D01*
G01Y572000D02*
X1239317Y572417D01*
X1239817Y572750D01*
X1240483Y572833D01*
X1241067Y572750D01*
X1241567Y572417D01*
X1241817Y571833D01*
Y569500D01*
G01X1244583Y572833D02*
Y570500D01*
X1244917Y569917D01*
X1245417Y569583D01*
X1246000Y569500D01*
X1246583Y569583D01*
X1247083Y569917D01*
X1247417Y570500D01*
G01Y569500D02*
Y572833D01*
G01X1253100Y569500D02*
Y572833D01*
G01Y572250D02*
X1252767Y572583D01*
X1252267Y572750D01*
X1251683Y572833D01*
X1251100Y572667D01*
X1250600Y572333D01*
X1250267Y571833D01*
X1250100Y571167D01*
X1250267Y570500D01*
X1250600Y570000D01*
X1251100Y569667D01*
X1251683Y569500D01*
X1252267Y569583D01*
X1252767Y569833D01*
X1253100Y570167D01*
G01X1257200Y569500D02*
Y574500D01*
G01X1267233Y569500D02*
Y572833D01*
G01Y572167D02*
X1267650Y572500D01*
X1268067Y572750D01*
X1268650Y572833D01*
X1269067Y572750D01*
X1269567Y572500D01*
G01X1274000Y572833D02*
Y569500D01*
G01Y574167D02*
X1273833Y574250D01*
Y574417D01*
X1274000Y574500D01*
X1274167Y574417D01*
Y574250D01*
X1274000Y574167D01*
G01X1278183Y569500D02*
Y572833D01*
G01Y572000D02*
X1278517Y572417D01*
X1279017Y572750D01*
X1279683Y572833D01*
X1280267Y572750D01*
X1280767Y572417D01*
X1281017Y571833D01*
Y569500D01*
G01X1284033Y568250D02*
X1284617Y567917D01*
X1285283Y567833D01*
X1285867Y567917D01*
X1286367Y568333D01*
X1286700Y568917D01*
Y572833D01*
G01Y572167D02*
X1286367Y572500D01*
X1285867Y572750D01*
X1285283Y572833D01*
X1284617Y572667D01*
X1284200Y572333D01*
X1283867Y571750D01*
X1283700Y571167D01*
X1283783Y570667D01*
X1284117Y570083D01*
X1284617Y569667D01*
X1285283Y569500D01*
X1285783Y569583D01*
X1286367Y569917D01*
X1286700Y570250D01*
G01X1294983Y569500D02*
Y572833D01*
G01Y572000D02*
X1295317Y572417D01*
X1295817Y572750D01*
X1296483Y572833D01*
X1297067Y572750D01*
X1297567Y572417D01*
X1297817Y571833D01*
Y569500D01*
G01X1300750Y571750D02*
X1303417D01*
X1303167Y572333D01*
X1302750Y572667D01*
X1302167Y572833D01*
X1301583Y572750D01*
X1301083Y572500D01*
X1300750Y571917D01*
X1300583Y571417D01*
Y570917D01*
X1300750Y570417D01*
X1301167Y569917D01*
X1301667Y569583D01*
X1302250Y569500D01*
X1302833Y569667D01*
X1303417Y570167D01*
G01X1306350Y571750D02*
X1309017D01*
X1308767Y572333D01*
X1308350Y572667D01*
X1307767Y572833D01*
X1307183Y572750D01*
X1306683Y572500D01*
X1306350Y571917D01*
X1306183Y571417D01*
Y570917D01*
X1306350Y570417D01*
X1306767Y569917D01*
X1307267Y569583D01*
X1307850Y569500D01*
X1308433Y569667D01*
X1309017Y570167D01*
G01X1314700Y574500D02*
Y569500D01*
G01Y570250D02*
X1314367Y569833D01*
X1313867Y569583D01*
X1313283Y569500D01*
X1312617Y569667D01*
X1312117Y570083D01*
X1311783Y570583D01*
X1311700Y571167D01*
X1311783Y571750D01*
X1312117Y572250D01*
X1312617Y572667D01*
X1313283Y572833D01*
X1313867Y572750D01*
X1314283Y572583D01*
X1314700Y572250D01*
G01X1012083Y730500D02*
Y733833D01*
G01Y733000D02*
X1012417Y733417D01*
X1012917Y733750D01*
X1013583Y733833D01*
X1014167Y733750D01*
X1014667Y733417D01*
X1014917Y732833D01*
Y730500D01*
G01X1019100D02*
X1018600Y730583D01*
X1018100Y730917D01*
X1017767Y731500D01*
X1017600Y732167D01*
X1017767Y732833D01*
X1018100Y733417D01*
X1018600Y733750D01*
X1019100Y733833D01*
X1019600Y733750D01*
X1020100Y733417D01*
X1020433Y732833D01*
X1020517Y732167D01*
X1020433Y731500D01*
X1020100Y730917D01*
X1019600Y730583D01*
X1019100Y730500D01*
G01X1028800Y728833D02*
Y733833D01*
G01Y733083D02*
X1029217Y733500D01*
X1029633Y733750D01*
X1030300Y733833D01*
X1030883Y733750D01*
X1031467Y733333D01*
X1031717Y732750D01*
X1031800Y732167D01*
X1031717Y731583D01*
X1031467Y731000D01*
X1030967Y730667D01*
X1030300Y730500D01*
X1029717Y730583D01*
X1029133Y730833D01*
X1028800Y731167D01*
G01X1035900Y730500D02*
Y735500D01*
G01X1040083Y733833D02*
Y731500D01*
X1040417Y730917D01*
X1040917Y730583D01*
X1041500Y730500D01*
X1042083Y730583D01*
X1042583Y730917D01*
X1042917Y731500D01*
G01Y730500D02*
Y733833D01*
G01X1045933Y729250D02*
X1046517Y728917D01*
X1047183Y728833D01*
X1047767Y728917D01*
X1048267Y729333D01*
X1048600Y729917D01*
Y733833D01*
G01Y733167D02*
X1048267Y733500D01*
X1047767Y733750D01*
X1047183Y733833D01*
X1046517Y733667D01*
X1046100Y733333D01*
X1045767Y732750D01*
X1045600Y732167D01*
X1045683Y731667D01*
X1046017Y731083D01*
X1046517Y730667D01*
X1047183Y730500D01*
X1047683Y730583D01*
X1048267Y730917D01*
X1048600Y731250D01*
G01X1051533Y729250D02*
X1052117Y728917D01*
X1052783Y728833D01*
X1053367Y728917D01*
X1053867Y729333D01*
X1054200Y729917D01*
Y733833D01*
G01Y733167D02*
X1053867Y733500D01*
X1053367Y733750D01*
X1052783Y733833D01*
X1052117Y733667D01*
X1051700Y733333D01*
X1051367Y732750D01*
X1051200Y732167D01*
X1051283Y731667D01*
X1051617Y731083D01*
X1052117Y730667D01*
X1052783Y730500D01*
X1053283Y730583D01*
X1053867Y730917D01*
X1054200Y731250D01*
G01X1058300Y733833D02*
Y730500D01*
G01Y735167D02*
X1058133Y735250D01*
Y735417D01*
X1058300Y735500D01*
X1058467Y735417D01*
Y735250D01*
X1058300Y735167D01*
G01X1062483Y730500D02*
Y733833D01*
G01Y733000D02*
X1062817Y733417D01*
X1063317Y733750D01*
X1063983Y733833D01*
X1064567Y733750D01*
X1065067Y733417D01*
X1065317Y732833D01*
Y730500D01*
G01X1068333Y729250D02*
X1068917Y728917D01*
X1069583Y728833D01*
X1070167Y728917D01*
X1070667Y729333D01*
X1071000Y729917D01*
Y733833D01*
G01Y733167D02*
X1070667Y733500D01*
X1070167Y733750D01*
X1069583Y733833D01*
X1068917Y733667D01*
X1068500Y733333D01*
X1068167Y732750D01*
X1068000Y732167D01*
X1068083Y731667D01*
X1068417Y731083D01*
X1068917Y730667D01*
X1069583Y730500D01*
X1070083Y730583D01*
X1070667Y730917D01*
X1071000Y731250D01*
G01X1087667Y124000D02*
Y129000D01*
X1089333D01*
X1090000Y128750D01*
X1090500Y128417D01*
X1090917Y127917D01*
X1091250Y127333D01*
X1091333Y126500D01*
X1091250Y125667D01*
X1090917Y125083D01*
X1090500Y124583D01*
X1090000Y124250D01*
X1089333Y124000D01*
X1087667D01*
G01X1093933D02*
Y127333D01*
G01Y126667D02*
X1094350Y127000D01*
X1094767Y127250D01*
X1095350Y127333D01*
X1095767Y127250D01*
X1096267Y127000D01*
G01X1100700Y127333D02*
Y124000D01*
G01Y128667D02*
X1100533Y128750D01*
Y128917D01*
X1100700Y129000D01*
X1100867Y128917D01*
Y128750D01*
X1100700Y128667D01*
G01X1106300Y124000D02*
Y129000D01*
G01X1111900Y124000D02*
Y129000D01*
G01X1121517Y124000D02*
Y129000D01*
X1124683D01*
G01X1123517Y126583D02*
X1121517D01*
G01X1127533Y124000D02*
Y127333D01*
G01Y126667D02*
X1127950Y127000D01*
X1128367Y127250D01*
X1128950Y127333D01*
X1129367Y127250D01*
X1129867Y127000D01*
G01X1134300Y124000D02*
X1133800Y124083D01*
X1133300Y124417D01*
X1132967Y125000D01*
X1132800Y125667D01*
X1132967Y126333D01*
X1133300Y126917D01*
X1133800Y127250D01*
X1134300Y127333D01*
X1134800Y127250D01*
X1135300Y126917D01*
X1135633Y126333D01*
X1135717Y125667D01*
X1135633Y125000D01*
X1135300Y124417D01*
X1134800Y124083D01*
X1134300Y124000D01*
G01X1137400D02*
Y127333D01*
G01Y126417D02*
X1137650Y126833D01*
X1138067Y127167D01*
X1138650Y127333D01*
X1139233Y127167D01*
X1139650Y126833D01*
X1139900Y126417D01*
Y124000D01*
G01Y126417D02*
X1140150Y126833D01*
X1140567Y127167D01*
X1141150Y127333D01*
X1141733Y127167D01*
X1142150Y126833D01*
X1142400Y126333D01*
Y124000D01*
G01X1167483Y122333D02*
X1166650Y123167D01*
X1166233Y124000D01*
Y127333D01*
X1166650Y128167D01*
X1167483Y129000D01*
G01X1174167Y126667D02*
X1174500Y126917D01*
X1174750Y127333D01*
X1174917Y127917D01*
X1174750Y128417D01*
X1174417Y128750D01*
X1173833Y129000D01*
X1171583D01*
Y124000D01*
X1174333D01*
X1174917Y124333D01*
X1175250Y124833D01*
X1175417Y125417D01*
X1175250Y126000D01*
X1174750Y126500D01*
X1174167Y126667D01*
X1171583D01*
G01X1179100Y124000D02*
X1178433Y124083D01*
X1177850Y124417D01*
X1177350Y124917D01*
X1177017Y125500D01*
X1176850Y126167D01*
Y126833D01*
X1177017Y127500D01*
X1177350Y128083D01*
X1177850Y128583D01*
X1178433Y128917D01*
X1179100Y129000D01*
X1179767Y128917D01*
X1180350Y128583D01*
X1180850Y128083D01*
X1181183Y127500D01*
X1181350Y126833D01*
Y126167D01*
X1181183Y125500D01*
X1180850Y124917D01*
X1180350Y124417D01*
X1179767Y124083D01*
X1179100Y124000D01*
G01X1184700Y129000D02*
Y124000D01*
G01X1182783Y129000D02*
X1186617D01*
G01X1190300D02*
Y124000D01*
G01X1188383Y129000D02*
X1192217D01*
G01X1195900Y124000D02*
X1195233Y124083D01*
X1194650Y124417D01*
X1194150Y124917D01*
X1193817Y125500D01*
X1193650Y126167D01*
Y126833D01*
X1193817Y127500D01*
X1194150Y128083D01*
X1194650Y128583D01*
X1195233Y128917D01*
X1195900Y129000D01*
X1196567Y128917D01*
X1197150Y128583D01*
X1197650Y128083D01*
X1197983Y127500D01*
X1198150Y126833D01*
Y126167D01*
X1197983Y125500D01*
X1197650Y124917D01*
X1197150Y124417D01*
X1196567Y124083D01*
X1195900Y124000D01*
G01X1199333D02*
Y129000D01*
X1201500Y124833D01*
X1203667Y129000D01*
Y124000D01*
G01X1207517Y122333D02*
X1208350Y123167D01*
X1208767Y124000D01*
Y127333D01*
X1208350Y128167D01*
X1207517Y129000D01*
G01X1218300D02*
Y124000D01*
G01X1217133Y127333D02*
X1219467D01*
G01X1223900Y124000D02*
X1223400Y124083D01*
X1222900Y124417D01*
X1222567Y125000D01*
X1222400Y125667D01*
X1222567Y126333D01*
X1222900Y126917D01*
X1223400Y127250D01*
X1223900Y127333D01*
X1224400Y127250D01*
X1224900Y126917D01*
X1225233Y126333D01*
X1225317Y125667D01*
X1225233Y125000D01*
X1224900Y124417D01*
X1224400Y124083D01*
X1223900Y124000D01*
G01X1233433Y129000D02*
Y124000D01*
X1236767D01*
G01X1239450Y127333D02*
X1241950Y124000D01*
G01Y127333D02*
X1239450Y124000D01*
G01X1089493Y104700D02*
Y99700D01*
X1092827D01*
G01X1095510Y103033D02*
X1098010Y99700D01*
G01Y103033D02*
X1095510Y99700D01*
G01X1102360Y99533D02*
X1102193Y99617D01*
Y99783D01*
X1102360Y99867D01*
X1102527Y99783D01*
Y99617D01*
X1102360Y99533D01*
G01Y101783D02*
X1102193Y101867D01*
Y102033D01*
X1102360Y102117D01*
X1102527Y102033D01*
Y101867D01*
X1102360Y101783D01*
G01X1111060Y99700D02*
Y103033D01*
G01Y102117D02*
X1111310Y102533D01*
X1111727Y102867D01*
X1112310Y103033D01*
X1112893Y102867D01*
X1113310Y102533D01*
X1113560Y102117D01*
Y99700D01*
G01Y102117D02*
X1113810Y102533D01*
X1114227Y102867D01*
X1114810Y103033D01*
X1115393Y102867D01*
X1115810Y102533D01*
X1116060Y102033D01*
Y99700D01*
G01X1117743Y103033D02*
Y100700D01*
X1118077Y100117D01*
X1118577Y99783D01*
X1119160Y99700D01*
X1119743Y99783D01*
X1120243Y100117D01*
X1120577Y100700D01*
G01Y99700D02*
Y103033D01*
G01X1123510Y100283D02*
X1123927Y99950D01*
X1124510Y99700D01*
X1125010D01*
X1125510Y99867D01*
X1125843Y100117D01*
X1126010Y100450D01*
X1125927Y100950D01*
X1125593Y101200D01*
X1124093Y101700D01*
X1123760Y102283D01*
X1123927Y102700D01*
X1124260Y102950D01*
X1124760Y103033D01*
X1125260Y102950D01*
X1125760Y102700D01*
G01X1130360Y104700D02*
Y99700D01*
G01X1129193Y103033D02*
X1131527D01*
G01X1140060Y99700D02*
Y104700D01*
G01Y102200D02*
X1140477Y102700D01*
X1140977Y102950D01*
X1141477Y103033D01*
X1142227Y102867D01*
X1142727Y102533D01*
X1143060Y101950D01*
Y101283D01*
X1142893Y100617D01*
X1142560Y100117D01*
X1141977Y99783D01*
X1141477Y99700D01*
X1140977Y99783D01*
X1140477Y100033D01*
X1140060Y100450D01*
G01X1145910Y101950D02*
X1148577D01*
X1148327Y102533D01*
X1147910Y102867D01*
X1147327Y103033D01*
X1146743Y102950D01*
X1146243Y102700D01*
X1145910Y102117D01*
X1145743Y101617D01*
Y101117D01*
X1145910Y100617D01*
X1146327Y100117D01*
X1146827Y99783D01*
X1147410Y99700D01*
X1147993Y99867D01*
X1148577Y100367D01*
G01X1156860Y99700D02*
Y104700D01*
G01Y102200D02*
X1157277Y102700D01*
X1157777Y102950D01*
X1158277Y103033D01*
X1159027Y102867D01*
X1159527Y102533D01*
X1159860Y101950D01*
Y101283D01*
X1159693Y100617D01*
X1159360Y100117D01*
X1158777Y99783D01*
X1158277Y99700D01*
X1157777Y99783D01*
X1157277Y100033D01*
X1156860Y100450D01*
G01X1162793Y99700D02*
Y103033D01*
G01Y102367D02*
X1163210Y102700D01*
X1163627Y102950D01*
X1164210Y103033D01*
X1164627Y102950D01*
X1165127Y102700D01*
G01X1169560Y99700D02*
X1169060Y99783D01*
X1168560Y100117D01*
X1168227Y100700D01*
X1168060Y101367D01*
X1168227Y102033D01*
X1168560Y102617D01*
X1169060Y102950D01*
X1169560Y103033D01*
X1170060Y102950D01*
X1170560Y102617D01*
X1170893Y102033D01*
X1170977Y101367D01*
X1170893Y100700D01*
X1170560Y100117D01*
X1170060Y99783D01*
X1169560Y99700D01*
G01X1173743D02*
Y104700D01*
G01X1176410Y103033D02*
X1173743Y101117D01*
G01X1174827Y101867D02*
X1176577Y99700D01*
G01X1179510Y101950D02*
X1182177D01*
X1181927Y102533D01*
X1181510Y102867D01*
X1180927Y103033D01*
X1180343Y102950D01*
X1179843Y102700D01*
X1179510Y102117D01*
X1179343Y101617D01*
Y101117D01*
X1179510Y100617D01*
X1179927Y100117D01*
X1180427Y99783D01*
X1181010Y99700D01*
X1181593Y99867D01*
X1182177Y100367D01*
G01X1184943Y99700D02*
Y103033D01*
G01Y102200D02*
X1185277Y102617D01*
X1185777Y102950D01*
X1186443Y103033D01*
X1187027Y102950D01*
X1187527Y102617D01*
X1187777Y102033D01*
Y99700D01*
G01X1197560D02*
Y104700D01*
G01X1204660Y99700D02*
Y103033D01*
G01Y102450D02*
X1204327Y102783D01*
X1203827Y102950D01*
X1203243Y103033D01*
X1202660Y102867D01*
X1202160Y102533D01*
X1201827Y102033D01*
X1201660Y101367D01*
X1201827Y100700D01*
X1202160Y100200D01*
X1202660Y99867D01*
X1203243Y99700D01*
X1203827Y99783D01*
X1204327Y100033D01*
X1204660Y100367D01*
G01X1207010Y98200D02*
X1207510Y98033D01*
X1208177Y98200D01*
X1208593Y98533D01*
X1208927Y98950D01*
X1209427Y100283D01*
X1210510Y103033D01*
G01X1207843D02*
X1209427Y100283D01*
G01X1213110Y101950D02*
X1215777D01*
X1215527Y102533D01*
X1215110Y102867D01*
X1214527Y103033D01*
X1213943Y102950D01*
X1213443Y102700D01*
X1213110Y102117D01*
X1212943Y101617D01*
Y101117D01*
X1213110Y100617D01*
X1213527Y100117D01*
X1214027Y99783D01*
X1214610Y99700D01*
X1215193Y99867D01*
X1215777Y100367D01*
G01X1218793Y99700D02*
Y103033D01*
G01Y102367D02*
X1219210Y102700D01*
X1219627Y102950D01*
X1220210Y103033D01*
X1220627Y102950D01*
X1221127Y102700D01*
G01X1088893Y117200D02*
Y112200D01*
X1092227D01*
G01X1094743D02*
Y115533D01*
G01Y114700D02*
X1095077Y115117D01*
X1095577Y115450D01*
X1096243Y115533D01*
X1096827Y115450D01*
X1097327Y115117D01*
X1097577Y114533D01*
Y112200D01*
G01X1101760Y112033D02*
X1101593Y112117D01*
Y112283D01*
X1101760Y112367D01*
X1101927Y112283D01*
Y112117D01*
X1101760Y112033D01*
G01Y114283D02*
X1101593Y114367D01*
Y114533D01*
X1101760Y114617D01*
X1101927Y114533D01*
Y114367D01*
X1101760Y114283D01*
G01X1114293Y115117D02*
X1113710Y115450D01*
X1113210Y115533D01*
X1112543Y115367D01*
X1112043Y115033D01*
X1111710Y114450D01*
X1111627Y113867D01*
X1111710Y113283D01*
X1112043Y112783D01*
X1112543Y112367D01*
X1113210Y112200D01*
X1113793Y112367D01*
X1114293Y112700D01*
G01X1120060Y112200D02*
Y115533D01*
G01Y114950D02*
X1119727Y115283D01*
X1119227Y115450D01*
X1118643Y115533D01*
X1118060Y115367D01*
X1117560Y115033D01*
X1117227Y114533D01*
X1117060Y113867D01*
X1117227Y113200D01*
X1117560Y112700D01*
X1118060Y112367D01*
X1118643Y112200D01*
X1119227Y112283D01*
X1119727Y112533D01*
X1120060Y112867D01*
G01X1122743Y112200D02*
Y115533D01*
G01Y114700D02*
X1123077Y115117D01*
X1123577Y115450D01*
X1124243Y115533D01*
X1124827Y115450D01*
X1125327Y115117D01*
X1125577Y114533D01*
Y112200D01*
G01X1129760Y115533D02*
X1130593Y116575D01*
Y117200D01*
X1129968D01*
Y116575D01*
X1130593D01*
G01X1135360Y117200D02*
Y112200D01*
G01X1134193Y115533D02*
X1136527D01*
G01X1145060Y112200D02*
Y117200D01*
G01Y114700D02*
X1145477Y115200D01*
X1145977Y115450D01*
X1146477Y115533D01*
X1147227Y115367D01*
X1147727Y115033D01*
X1148060Y114450D01*
Y113783D01*
X1147893Y113117D01*
X1147560Y112617D01*
X1146977Y112283D01*
X1146477Y112200D01*
X1145977Y112283D01*
X1145477Y112533D01*
X1145060Y112950D01*
G01X1150910Y114450D02*
X1153577D01*
X1153327Y115033D01*
X1152910Y115367D01*
X1152327Y115533D01*
X1151743Y115450D01*
X1151243Y115200D01*
X1150910Y114617D01*
X1150743Y114117D01*
Y113617D01*
X1150910Y113117D01*
X1151327Y112617D01*
X1151827Y112283D01*
X1152410Y112200D01*
X1152993Y112367D01*
X1153577Y112867D01*
G01X1161860Y112200D02*
Y117200D01*
G01Y114700D02*
X1162277Y115200D01*
X1162777Y115450D01*
X1163277Y115533D01*
X1164027Y115367D01*
X1164527Y115033D01*
X1164860Y114450D01*
Y113783D01*
X1164693Y113117D01*
X1164360Y112617D01*
X1163777Y112283D01*
X1163277Y112200D01*
X1162777Y112283D01*
X1162277Y112533D01*
X1161860Y112950D01*
G01X1167793Y112200D02*
Y115533D01*
G01Y114867D02*
X1168210Y115200D01*
X1168627Y115450D01*
X1169210Y115533D01*
X1169627Y115450D01*
X1170127Y115200D01*
G01X1174560Y112200D02*
X1174060Y112283D01*
X1173560Y112617D01*
X1173227Y113200D01*
X1173060Y113867D01*
X1173227Y114533D01*
X1173560Y115117D01*
X1174060Y115450D01*
X1174560Y115533D01*
X1175060Y115450D01*
X1175560Y115117D01*
X1175893Y114533D01*
X1175977Y113867D01*
X1175893Y113200D01*
X1175560Y112617D01*
X1175060Y112283D01*
X1174560Y112200D01*
G01X1178743D02*
Y117200D01*
G01X1181410Y115533D02*
X1178743Y113617D01*
G01X1179827Y114367D02*
X1181577Y112200D01*
G01X1184510Y114450D02*
X1187177D01*
X1186927Y115033D01*
X1186510Y115367D01*
X1185927Y115533D01*
X1185343Y115450D01*
X1184843Y115200D01*
X1184510Y114617D01*
X1184343Y114117D01*
Y113617D01*
X1184510Y113117D01*
X1184927Y112617D01*
X1185427Y112283D01*
X1186010Y112200D01*
X1186593Y112367D01*
X1187177Y112867D01*
G01X1189943Y112200D02*
Y115533D01*
G01Y114700D02*
X1190277Y115117D01*
X1190777Y115450D01*
X1191443Y115533D01*
X1192027Y115450D01*
X1192527Y115117D01*
X1192777Y114533D01*
Y112200D01*
G01X1202560D02*
Y117200D01*
G01X1209660Y112200D02*
Y115533D01*
G01Y114950D02*
X1209327Y115283D01*
X1208827Y115450D01*
X1208243Y115533D01*
X1207660Y115367D01*
X1207160Y115033D01*
X1206827Y114533D01*
X1206660Y113867D01*
X1206827Y113200D01*
X1207160Y112700D01*
X1207660Y112367D01*
X1208243Y112200D01*
X1208827Y112283D01*
X1209327Y112533D01*
X1209660Y112867D01*
G01X1212010Y110700D02*
X1212510Y110533D01*
X1213177Y110700D01*
X1213593Y111033D01*
X1213927Y111450D01*
X1214427Y112783D01*
X1215510Y115533D01*
G01X1212843D02*
X1214427Y112783D01*
G01X1218110Y114450D02*
X1220777D01*
X1220527Y115033D01*
X1220110Y115367D01*
X1219527Y115533D01*
X1218943Y115450D01*
X1218443Y115200D01*
X1218110Y114617D01*
X1217943Y114117D01*
Y113617D01*
X1218110Y113117D01*
X1218527Y112617D01*
X1219027Y112283D01*
X1219610Y112200D01*
X1220193Y112367D01*
X1220777Y112867D01*
G01X1223793Y112200D02*
Y115533D01*
G01Y114867D02*
X1224210Y115200D01*
X1224627Y115450D01*
X1225210Y115533D01*
X1225627Y115450D01*
X1226127Y115200D01*
G01X1136167Y157700D02*
Y162700D01*
X1137833D01*
X1138500Y162450D01*
X1139000Y162117D01*
X1139417Y161617D01*
X1139750Y161033D01*
X1139833Y160200D01*
X1139750Y159367D01*
X1139417Y158783D01*
X1139000Y158283D01*
X1138500Y157950D01*
X1137833Y157700D01*
X1136167D01*
G01X1142017Y161867D02*
X1142517Y162367D01*
X1143100Y162617D01*
X1143767Y162700D01*
X1144600Y162533D01*
X1145183Y162117D01*
X1145350Y161617D01*
X1145267Y161117D01*
X1144933Y160700D01*
X1143267Y159867D01*
X1142517Y159283D01*
X1142017Y158450D01*
X1141850Y157700D01*
X1145350D01*
G01X1135167Y315700D02*
Y320700D01*
X1136833D01*
X1137500Y320450D01*
X1138000Y320117D01*
X1138417Y319617D01*
X1138750Y319033D01*
X1138833Y318200D01*
X1138750Y317367D01*
X1138417Y316783D01*
X1138000Y316283D01*
X1137500Y315950D01*
X1136833Y315700D01*
X1135167D01*
G01X1142600D02*
Y320700D01*
X1141600Y319700D01*
G01Y315700D02*
X1143600D01*
G01X1136833Y619917D02*
X1136250Y620250D01*
X1135750Y620333D01*
X1135083Y620167D01*
X1134583Y619833D01*
X1134250Y619250D01*
X1134167Y618667D01*
X1134250Y618083D01*
X1134583Y617583D01*
X1135083Y617167D01*
X1135750Y617000D01*
X1136333Y617167D01*
X1136833Y617500D01*
G01X1141100Y617000D02*
X1140600Y617083D01*
X1140100Y617417D01*
X1139767Y618000D01*
X1139600Y618667D01*
X1139767Y619333D01*
X1140100Y619917D01*
X1140600Y620250D01*
X1141100Y620333D01*
X1141600Y620250D01*
X1142100Y619917D01*
X1142433Y619333D01*
X1142517Y618667D01*
X1142433Y618000D01*
X1142100Y617417D01*
X1141600Y617083D01*
X1141100Y617000D01*
G01X1145200Y615333D02*
Y620333D01*
G01Y619583D02*
X1145617Y620000D01*
X1146033Y620250D01*
X1146700Y620333D01*
X1147283Y620250D01*
X1147867Y619833D01*
X1148117Y619250D01*
X1148200Y618667D01*
X1148117Y618083D01*
X1147867Y617500D01*
X1147367Y617167D01*
X1146700Y617000D01*
X1146117Y617083D01*
X1145533Y617333D01*
X1145200Y617667D01*
G01X1150800Y615333D02*
Y620333D01*
G01Y619583D02*
X1151217Y620000D01*
X1151633Y620250D01*
X1152300Y620333D01*
X1152883Y620250D01*
X1153467Y619833D01*
X1153717Y619250D01*
X1153800Y618667D01*
X1153717Y618083D01*
X1153467Y617500D01*
X1152967Y617167D01*
X1152300Y617000D01*
X1151717Y617083D01*
X1151133Y617333D01*
X1150800Y617667D01*
G01X1156650Y619250D02*
X1159317D01*
X1159067Y619833D01*
X1158650Y620167D01*
X1158067Y620333D01*
X1157483Y620250D01*
X1156983Y620000D01*
X1156650Y619417D01*
X1156483Y618917D01*
Y618417D01*
X1156650Y617917D01*
X1157067Y617417D01*
X1157567Y617083D01*
X1158150Y617000D01*
X1158733Y617167D01*
X1159317Y617667D01*
G01X1162333Y617000D02*
Y620333D01*
G01Y619667D02*
X1162750Y620000D01*
X1163167Y620250D01*
X1163750Y620333D01*
X1164167Y620250D01*
X1164667Y620000D01*
G01X1109833Y590500D02*
Y595500D01*
X1111833D01*
X1112500Y595250D01*
X1113000Y594667D01*
X1113167Y594000D01*
X1113000Y593333D01*
X1112583Y592833D01*
X1111833Y592583D01*
X1109833D01*
G01X1117100Y590500D02*
Y595500D01*
G01X1121283Y593833D02*
Y591500D01*
X1121617Y590917D01*
X1122117Y590583D01*
X1122700Y590500D01*
X1123283Y590583D01*
X1123783Y590917D01*
X1124117Y591500D01*
G01Y590500D02*
Y593833D01*
G01X1127133Y589250D02*
X1127717Y588917D01*
X1128383Y588833D01*
X1128967Y588917D01*
X1129467Y589333D01*
X1129800Y589917D01*
Y593833D01*
G01Y593167D02*
X1129467Y593500D01*
X1128967Y593750D01*
X1128383Y593833D01*
X1127717Y593667D01*
X1127300Y593333D01*
X1126967Y592750D01*
X1126800Y592167D01*
X1126883Y591667D01*
X1127217Y591083D01*
X1127717Y590667D01*
X1128383Y590500D01*
X1128883Y590583D01*
X1129467Y590917D01*
X1129800Y591250D01*
G01X1132733Y589250D02*
X1133317Y588917D01*
X1133983Y588833D01*
X1134567Y588917D01*
X1135067Y589333D01*
X1135400Y589917D01*
Y593833D01*
G01Y593167D02*
X1135067Y593500D01*
X1134567Y593750D01*
X1133983Y593833D01*
X1133317Y593667D01*
X1132900Y593333D01*
X1132567Y592750D01*
X1132400Y592167D01*
X1132483Y591667D01*
X1132817Y591083D01*
X1133317Y590667D01*
X1133983Y590500D01*
X1134483Y590583D01*
X1135067Y590917D01*
X1135400Y591250D01*
G01X1139500Y593833D02*
Y590500D01*
G01Y595167D02*
X1139333Y595250D01*
Y595417D01*
X1139500Y595500D01*
X1139667Y595417D01*
Y595250D01*
X1139500Y595167D01*
G01X1143683Y590500D02*
Y593833D01*
G01Y593000D02*
X1144017Y593417D01*
X1144517Y593750D01*
X1145183Y593833D01*
X1145767Y593750D01*
X1146267Y593417D01*
X1146517Y592833D01*
Y590500D01*
G01X1149533Y589250D02*
X1150117Y588917D01*
X1150783Y588833D01*
X1151367Y588917D01*
X1151867Y589333D01*
X1152200Y589917D01*
Y593833D01*
G01Y593167D02*
X1151867Y593500D01*
X1151367Y593750D01*
X1150783Y593833D01*
X1150117Y593667D01*
X1149700Y593333D01*
X1149367Y592750D01*
X1149200Y592167D01*
X1149283Y591667D01*
X1149617Y591083D01*
X1150117Y590667D01*
X1150783Y590500D01*
X1151283Y590583D01*
X1151867Y590917D01*
X1152200Y591250D01*
G01X1163233Y593417D02*
X1162650Y593750D01*
X1162150Y593833D01*
X1161483Y593667D01*
X1160983Y593333D01*
X1160650Y592750D01*
X1160567Y592167D01*
X1160650Y591583D01*
X1160983Y591083D01*
X1161483Y590667D01*
X1162150Y590500D01*
X1162733Y590667D01*
X1163233Y591000D01*
G01X1166333Y590500D02*
Y593833D01*
G01Y593167D02*
X1166750Y593500D01*
X1167167Y593750D01*
X1167750Y593833D01*
X1168167Y593750D01*
X1168667Y593500D01*
G01X1173100Y593833D02*
Y590500D01*
G01Y595167D02*
X1172933Y595250D01*
Y595417D01*
X1173100Y595500D01*
X1173267Y595417D01*
Y595250D01*
X1173100Y595167D01*
G01X1178700Y595500D02*
Y590500D01*
G01X1177533Y593833D02*
X1179867D01*
G01X1183050Y592750D02*
X1185717D01*
X1185467Y593333D01*
X1185050Y593667D01*
X1184467Y593833D01*
X1183883Y593750D01*
X1183383Y593500D01*
X1183050Y592917D01*
X1182883Y592417D01*
Y591917D01*
X1183050Y591417D01*
X1183467Y590917D01*
X1183967Y590583D01*
X1184550Y590500D01*
X1185133Y590667D01*
X1185717Y591167D01*
G01X1188733Y590500D02*
Y593833D01*
G01Y593167D02*
X1189150Y593500D01*
X1189567Y593750D01*
X1190150Y593833D01*
X1190567Y593750D01*
X1191067Y593500D01*
G01X1195500Y593833D02*
Y590500D01*
G01Y595167D02*
X1195333Y595250D01*
Y595417D01*
X1195500Y595500D01*
X1195667Y595417D01*
Y595250D01*
X1195500Y595167D01*
G01X1202600Y590500D02*
Y593833D01*
G01Y593250D02*
X1202267Y593583D01*
X1201767Y593750D01*
X1201183Y593833D01*
X1200600Y593667D01*
X1200100Y593333D01*
X1199767Y592833D01*
X1199600Y592167D01*
X1199767Y591500D01*
X1200100Y591000D01*
X1200600Y590667D01*
X1201183Y590500D01*
X1201767Y590583D01*
X1202267Y590833D01*
X1202600Y591167D01*
G01X1106417Y735500D02*
X1108500Y730500D01*
X1110583Y735500D01*
G01X1113100D02*
X1115100D01*
G01X1114100D02*
Y730500D01*
G01X1113100D02*
X1115100D01*
G01X1118033D02*
Y735500D01*
X1120033D01*
X1120700Y735250D01*
X1121200Y734667D01*
X1121367Y734000D01*
X1121200Y733333D01*
X1120783Y732833D01*
X1120033Y732583D01*
X1118033D01*
G01X1184667Y150367D02*
X1185000Y150617D01*
X1185250Y151033D01*
X1185417Y151617D01*
X1185250Y152117D01*
X1184917Y152450D01*
X1184333Y152700D01*
X1182083D01*
Y147700D01*
X1184833D01*
X1185417Y148033D01*
X1185750Y148533D01*
X1185917Y149117D01*
X1185750Y149700D01*
X1185250Y150200D01*
X1184667Y150367D01*
X1182083D01*
G01X1187517Y147700D02*
X1189600Y152700D01*
X1191683Y147700D01*
G01X1190933Y149450D02*
X1188267D01*
G01X1197033Y152283D02*
X1196533Y152533D01*
X1195950Y152700D01*
X1195283D01*
X1194533Y152450D01*
X1193950Y152033D01*
X1193533Y151533D01*
X1193200Y150700D01*
X1193117Y149950D01*
X1193283Y149200D01*
X1193533Y148700D01*
X1194033Y148200D01*
X1194617Y147867D01*
X1195200Y147700D01*
X1195783D01*
X1196367Y147867D01*
X1196867Y148117D01*
X1197283Y148450D01*
G01X1198967Y147700D02*
Y152700D01*
G01X1202133D02*
X1198967Y149617D01*
G01X1202633Y147700D02*
X1200383Y151033D01*
G01X1210167Y147700D02*
Y152700D01*
X1211833D01*
X1212500Y152450D01*
X1213000Y152117D01*
X1213417Y151617D01*
X1213750Y151033D01*
X1213833Y150200D01*
X1213750Y149367D01*
X1213417Y148783D01*
X1213000Y148283D01*
X1212500Y147950D01*
X1211833Y147700D01*
X1210167D01*
G01X1215933D02*
Y152700D01*
X1218017D01*
X1218683Y152450D01*
X1219100Y152117D01*
X1219267Y151450D01*
X1219100Y150783D01*
X1218600Y150367D01*
X1218017Y150117D01*
X1215933D01*
G01X1218017D02*
X1219267Y147700D01*
G01X1222200Y152700D02*
X1224200D01*
G01X1223200D02*
Y147700D01*
G01X1222200D02*
X1224200D01*
G01X1227133Y152700D02*
Y147700D01*
X1230467D01*
G01X1232733Y152700D02*
Y147700D01*
X1236067D01*
G01X1259900D02*
Y151033D01*
G01Y150117D02*
X1260150Y150533D01*
X1260567Y150867D01*
X1261150Y151033D01*
X1261733Y150867D01*
X1262150Y150533D01*
X1262400Y150117D01*
Y147700D01*
G01Y150117D02*
X1262650Y150533D01*
X1263067Y150867D01*
X1263650Y151033D01*
X1264233Y150867D01*
X1264650Y150533D01*
X1264900Y150033D01*
Y147700D01*
G01X1268000Y151033D02*
Y147700D01*
G01Y152367D02*
X1267833Y152450D01*
Y152617D01*
X1268000Y152700D01*
X1268167Y152617D01*
Y152450D01*
X1268000Y152367D01*
G01X1273600Y147700D02*
Y152700D01*
G01X1277950Y148283D02*
X1278367Y147950D01*
X1278950Y147700D01*
X1279450D01*
X1279950Y147867D01*
X1280283Y148117D01*
X1280450Y148450D01*
X1280367Y148950D01*
X1280033Y149200D01*
X1278533Y149700D01*
X1278200Y150283D01*
X1278367Y150700D01*
X1278700Y150950D01*
X1279200Y151033D01*
X1279700Y150950D01*
X1280200Y150700D01*
G01X1284383Y146033D02*
X1283550Y146867D01*
X1283133Y147700D01*
Y151033D01*
X1283550Y151867D01*
X1284383Y152700D01*
G01X1288483Y147700D02*
Y152700D01*
X1292317Y147700D01*
Y152700D01*
G01X1294333Y147700D02*
Y152700D01*
X1296333D01*
X1297000Y152450D01*
X1297500Y151867D01*
X1297667Y151200D01*
X1297500Y150533D01*
X1297083Y150033D01*
X1296333Y149783D01*
X1294333D01*
G01X1301600Y152700D02*
Y147700D01*
G01X1299683Y152700D02*
X1303517D01*
G01X1305450Y147700D02*
Y152700D01*
G01X1308950D02*
Y147700D01*
G01Y150200D02*
X1305450D01*
G01X1313217Y146033D02*
X1314050Y146867D01*
X1314467Y147700D01*
Y151033D01*
X1314050Y151867D01*
X1313217Y152700D01*
G01X1210333Y218700D02*
Y213700D01*
X1213667D01*
G01X1216350Y217033D02*
X1218850Y213700D01*
G01Y217033D02*
X1216350Y213700D01*
G01X1207333Y260500D02*
Y255500D01*
X1210667D01*
G01X1213183D02*
Y258833D01*
G01Y258000D02*
X1213517Y258417D01*
X1214017Y258750D01*
X1214683Y258833D01*
X1215267Y258750D01*
X1215767Y258417D01*
X1216017Y257833D01*
Y255500D01*
G01X1218250Y281583D02*
X1218667Y281250D01*
X1219250Y281000D01*
X1219750D01*
X1220250Y281167D01*
X1220583Y281417D01*
X1220750Y281750D01*
X1220667Y282250D01*
X1220333Y282500D01*
X1218833Y283000D01*
X1218500Y283583D01*
X1218667Y284000D01*
X1219000Y284250D01*
X1219500Y284333D01*
X1220000Y284250D01*
X1220500Y284000D01*
G01X1225100Y286000D02*
Y281000D01*
G01X1223933Y284333D02*
X1226267D01*
G01X1229283D02*
Y282000D01*
X1229617Y281417D01*
X1230117Y281083D01*
X1230700Y281000D01*
X1231283Y281083D01*
X1231783Y281417D01*
X1232117Y282000D01*
G01Y281000D02*
Y284333D01*
G01X1234800Y281000D02*
Y286000D01*
G01Y283500D02*
X1235217Y284000D01*
X1235717Y284250D01*
X1236217Y284333D01*
X1236967Y284167D01*
X1237467Y283833D01*
X1237800Y283250D01*
Y282583D01*
X1237633Y281917D01*
X1237300Y281417D01*
X1236717Y281083D01*
X1236217Y281000D01*
X1235717Y281083D01*
X1235217Y281333D01*
X1234800Y281750D01*
G01X1247500Y281000D02*
Y286000D01*
G01X1251850Y283250D02*
X1254517D01*
X1254267Y283833D01*
X1253850Y284167D01*
X1253267Y284333D01*
X1252683Y284250D01*
X1252183Y284000D01*
X1251850Y283417D01*
X1251683Y282917D01*
Y282417D01*
X1251850Y281917D01*
X1252267Y281417D01*
X1252767Y281083D01*
X1253350Y281000D01*
X1253933Y281167D01*
X1254517Y281667D01*
G01X1257283Y281000D02*
Y284333D01*
G01Y283500D02*
X1257617Y283917D01*
X1258117Y284250D01*
X1258783Y284333D01*
X1259367Y284250D01*
X1259867Y283917D01*
X1260117Y283333D01*
Y281000D01*
G01X1263133Y279750D02*
X1263717Y279417D01*
X1264383Y279333D01*
X1264967Y279417D01*
X1265467Y279833D01*
X1265800Y280417D01*
Y284333D01*
G01Y283667D02*
X1265467Y284000D01*
X1264967Y284250D01*
X1264383Y284333D01*
X1263717Y284167D01*
X1263300Y283833D01*
X1262967Y283250D01*
X1262800Y282667D01*
X1262883Y282167D01*
X1263217Y281583D01*
X1263717Y281167D01*
X1264383Y281000D01*
X1264883Y281083D01*
X1265467Y281417D01*
X1265800Y281750D01*
G01X1269900Y286000D02*
Y281000D01*
G01X1268733Y284333D02*
X1271067D01*
G01X1274083Y281000D02*
Y286000D01*
G01Y283583D02*
X1274500Y284000D01*
X1274917Y284250D01*
X1275583Y284333D01*
X1276083Y284250D01*
X1276667Y283917D01*
X1276917Y283417D01*
Y281000D01*
G01X1280017Y281917D02*
X1282183D01*
G01Y283417D02*
X1280017D01*
G01X1285117Y283083D02*
X1285700Y283667D01*
X1286200Y284000D01*
X1286867Y284167D01*
X1287450Y284000D01*
X1287867Y283667D01*
X1288200Y283167D01*
X1288283Y282583D01*
X1288200Y282083D01*
X1287867Y281583D01*
X1287367Y281167D01*
X1286783Y281000D01*
X1286117Y281167D01*
X1285533Y281667D01*
X1285200Y282417D01*
X1285117Y283250D01*
X1285283Y284333D01*
X1285533Y284917D01*
X1285950Y285500D01*
X1286533Y285917D01*
X1287117Y286000D01*
X1287700Y285833D01*
X1288117Y285417D01*
G01X1291383Y282667D02*
X1293383D01*
G01X1292300Y283750D02*
Y281583D01*
G01X1296400Y280833D02*
X1299400Y286000D01*
G01X1302417Y282667D02*
X1304583D01*
G01X1307267Y281750D02*
X1307767Y281333D01*
X1308350Y281083D01*
X1309100Y281000D01*
X1309850Y281167D01*
X1310433Y281500D01*
X1310850Y282083D01*
X1310933Y282750D01*
X1310767Y283417D01*
X1310350Y283833D01*
X1309767Y284167D01*
X1309183Y284250D01*
X1308600Y284167D01*
X1307850Y283833D01*
X1308100Y286000D01*
X1310350D01*
G01X1312200Y281000D02*
Y284333D01*
G01Y283417D02*
X1312450Y283833D01*
X1312867Y284167D01*
X1313450Y284333D01*
X1314033Y284167D01*
X1314450Y283833D01*
X1314700Y283417D01*
Y281000D01*
G01Y283417D02*
X1314950Y283833D01*
X1315367Y284167D01*
X1315950Y284333D01*
X1316533Y284167D01*
X1316950Y283833D01*
X1317200Y283333D01*
Y281000D01*
G01X1320300Y284333D02*
Y281000D01*
G01Y285667D02*
X1320133Y285750D01*
Y285917D01*
X1320300Y286000D01*
X1320467Y285917D01*
Y285750D01*
X1320300Y285667D01*
G01X1325900Y281000D02*
Y286000D01*
G01X1178750Y315500D02*
Y320500D01*
G01X1182250D02*
Y315500D01*
G01Y318000D02*
X1178750D01*
G01X1186100Y315500D02*
X1185433Y315583D01*
X1184850Y315917D01*
X1184350Y316417D01*
X1184017Y317000D01*
X1183850Y317667D01*
Y318333D01*
X1184017Y319000D01*
X1184350Y319583D01*
X1184850Y320083D01*
X1185433Y320417D01*
X1186100Y320500D01*
X1186767Y320417D01*
X1187350Y320083D01*
X1187850Y319583D01*
X1188183Y319000D01*
X1188350Y318333D01*
Y317667D01*
X1188183Y317000D01*
X1187850Y316417D01*
X1187350Y315917D01*
X1186767Y315583D01*
X1186100Y315500D01*
G01X1190033Y320500D02*
Y315500D01*
X1193367D01*
G01X1198967D02*
X1195633D01*
Y320500D01*
X1198967D01*
G01X1197633Y318083D02*
X1195633D01*
G01X1222800Y315500D02*
Y318833D01*
G01Y317917D02*
X1223050Y318333D01*
X1223467Y318667D01*
X1224050Y318833D01*
X1224633Y318667D01*
X1225050Y318333D01*
X1225300Y317917D01*
Y315500D01*
G01Y317917D02*
X1225550Y318333D01*
X1225967Y318667D01*
X1226550Y318833D01*
X1227133Y318667D01*
X1227550Y318333D01*
X1227800Y317833D01*
Y315500D01*
G01X1230900Y318833D02*
Y315500D01*
G01Y320167D02*
X1230733Y320250D01*
Y320417D01*
X1230900Y320500D01*
X1231067Y320417D01*
Y320250D01*
X1230900Y320167D01*
G01X1236500Y315500D02*
Y320500D01*
G01X1240850Y316083D02*
X1241267Y315750D01*
X1241850Y315500D01*
X1242350D01*
X1242850Y315667D01*
X1243183Y315917D01*
X1243350Y316250D01*
X1243267Y316750D01*
X1242933Y317000D01*
X1241433Y317500D01*
X1241100Y318083D01*
X1241267Y318500D01*
X1241600Y318750D01*
X1242100Y318833D01*
X1242600Y318750D01*
X1243100Y318500D01*
G01X1247283Y313833D02*
X1246450Y314667D01*
X1246033Y315500D01*
Y318833D01*
X1246450Y319667D01*
X1247283Y320500D01*
G01X1251633Y315500D02*
Y320500D01*
X1253633D01*
X1254300Y320250D01*
X1254800Y319667D01*
X1254967Y319000D01*
X1254800Y318333D01*
X1254383Y317833D01*
X1253633Y317583D01*
X1251633D01*
G01X1258900Y320500D02*
Y315500D01*
G01X1256983Y320500D02*
X1260817D01*
G01X1262750Y315500D02*
Y320500D01*
G01X1266250D02*
Y315500D01*
G01Y318000D02*
X1262750D01*
G01X1270517Y313833D02*
X1271350Y314667D01*
X1271767Y315500D01*
Y318833D01*
X1271350Y319667D01*
X1270517Y320500D01*
G01X1180417Y734500D02*
X1182500Y729500D01*
X1184583Y734500D01*
G01X1188100Y729500D02*
X1187433Y729583D01*
X1186850Y729917D01*
X1186350Y730417D01*
X1186017Y731000D01*
X1185850Y731667D01*
Y732333D01*
X1186017Y733000D01*
X1186350Y733583D01*
X1186850Y734083D01*
X1187433Y734417D01*
X1188100Y734500D01*
X1188767Y734417D01*
X1189350Y734083D01*
X1189850Y733583D01*
X1190183Y733000D01*
X1190350Y732333D01*
Y731667D01*
X1190183Y731000D01*
X1189850Y730417D01*
X1189350Y729917D01*
X1188767Y729583D01*
X1188100Y729500D01*
G01X1192033D02*
Y734500D01*
X1194033D01*
X1194700Y734250D01*
X1195200Y733667D01*
X1195367Y733000D01*
X1195200Y732333D01*
X1194783Y731833D01*
X1194033Y731583D01*
X1192033D01*
G01X1241083Y841667D02*
X1243083D01*
G01X1242000Y842750D02*
Y840583D01*
G01X1246100Y839833D02*
X1249100Y845000D01*
G01X1252117Y841667D02*
X1254283D01*
G01X1256967Y840750D02*
X1257467Y840333D01*
X1258050Y840083D01*
X1258800Y840000D01*
X1259550Y840167D01*
X1260133Y840500D01*
X1260550Y841083D01*
X1260633Y841750D01*
X1260467Y842417D01*
X1260050Y842833D01*
X1259467Y843167D01*
X1258883Y843250D01*
X1258300Y843167D01*
X1257550Y842833D01*
X1257800Y845000D01*
X1260050D01*
G01X1261900Y840000D02*
Y843333D01*
G01Y842417D02*
X1262150Y842833D01*
X1262567Y843167D01*
X1263150Y843333D01*
X1263733Y843167D01*
X1264150Y842833D01*
X1264400Y842417D01*
Y840000D01*
G01Y842417D02*
X1264650Y842833D01*
X1265067Y843167D01*
X1265650Y843333D01*
X1266233Y843167D01*
X1266650Y842833D01*
X1266900Y842333D01*
Y840000D01*
G01X1270000Y843333D02*
Y840000D01*
G01Y844667D02*
X1269833Y844750D01*
Y844917D01*
X1270000Y845000D01*
X1270167Y844917D01*
Y844750D01*
X1270000Y844667D01*
G01X1275600Y840000D02*
Y845000D01*
G01X1241083Y826667D02*
X1243083D01*
G01X1242000Y827750D02*
Y825583D01*
G01X1246100Y824833D02*
X1249100Y830000D01*
G01X1252117Y826667D02*
X1254283D01*
G01X1256967Y825750D02*
X1257467Y825333D01*
X1258050Y825083D01*
X1258800Y825000D01*
X1259550Y825167D01*
X1260133Y825500D01*
X1260550Y826083D01*
X1260633Y826750D01*
X1260467Y827417D01*
X1260050Y827833D01*
X1259467Y828167D01*
X1258883Y828250D01*
X1258300Y828167D01*
X1257550Y827833D01*
X1257800Y830000D01*
X1260050D01*
G01X1261900Y825000D02*
Y828333D01*
G01Y827417D02*
X1262150Y827833D01*
X1262567Y828167D01*
X1263150Y828333D01*
X1263733Y828167D01*
X1264150Y827833D01*
X1264400Y827417D01*
Y825000D01*
G01Y827417D02*
X1264650Y827833D01*
X1265067Y828167D01*
X1265650Y828333D01*
X1266233Y828167D01*
X1266650Y827833D01*
X1266900Y827333D01*
Y825000D01*
G01X1270000Y828333D02*
Y825000D01*
G01Y829667D02*
X1269833Y829750D01*
Y829917D01*
X1270000Y830000D01*
X1270167Y829917D01*
Y829750D01*
X1270000Y829667D01*
G01X1275600Y825000D02*
Y830000D01*
G01X1241083Y811667D02*
X1243083D01*
G01X1242000Y812750D02*
Y810583D01*
G01X1246100Y809833D02*
X1249100Y815000D01*
G01X1252117Y811667D02*
X1254283D01*
G01X1257217Y814167D02*
X1257717Y814667D01*
X1258300Y814917D01*
X1258967Y815000D01*
X1259800Y814833D01*
X1260383Y814417D01*
X1260550Y813917D01*
X1260467Y813417D01*
X1260133Y813000D01*
X1258467Y812167D01*
X1257717Y811583D01*
X1257217Y810750D01*
X1257050Y810000D01*
X1260550D01*
G01X1261900D02*
Y813333D01*
G01Y812417D02*
X1262150Y812833D01*
X1262567Y813167D01*
X1263150Y813333D01*
X1263733Y813167D01*
X1264150Y812833D01*
X1264400Y812417D01*
Y810000D01*
G01Y812417D02*
X1264650Y812833D01*
X1265067Y813167D01*
X1265650Y813333D01*
X1266233Y813167D01*
X1266650Y812833D01*
X1266900Y812333D01*
Y810000D01*
G01X1270000Y813333D02*
Y810000D01*
G01Y814667D02*
X1269833Y814750D01*
Y814917D01*
X1270000Y815000D01*
X1270167Y814917D01*
Y814750D01*
X1270000Y814667D01*
G01X1275600Y810000D02*
Y815000D01*
G01X1242793Y785443D02*
X1241960Y786277D01*
X1241543Y787110D01*
Y790443D01*
X1241960Y791277D01*
X1242793Y792110D01*
G01X1248810Y787110D02*
Y792110D01*
X1247810Y791110D01*
G01Y787110D02*
X1249810D01*
G01X1254410Y786943D02*
X1254243Y787027D01*
Y787193D01*
X1254410Y787277D01*
X1254577Y787193D01*
Y787027D01*
X1254410Y786943D01*
G01X1258427Y791277D02*
X1258927Y791777D01*
X1259510Y792027D01*
X1260177Y792110D01*
X1261010Y791943D01*
X1261593Y791527D01*
X1261760Y791027D01*
X1261677Y790527D01*
X1261343Y790110D01*
X1259677Y789277D01*
X1258927Y788693D01*
X1258427Y787860D01*
X1258260Y787110D01*
X1261760D01*
G01X1263110D02*
Y790443D01*
G01Y789527D02*
X1263360Y789943D01*
X1263777Y790277D01*
X1264360Y790443D01*
X1264943Y790277D01*
X1265360Y789943D01*
X1265610Y789527D01*
Y787110D01*
G01Y789527D02*
X1265860Y789943D01*
X1266277Y790277D01*
X1266860Y790443D01*
X1267443Y790277D01*
X1267860Y789943D01*
X1268110Y789443D01*
Y787110D01*
G01X1268710D02*
Y790443D01*
G01Y789527D02*
X1268960Y789943D01*
X1269377Y790277D01*
X1269960Y790443D01*
X1270543Y790277D01*
X1270960Y789943D01*
X1271210Y789527D01*
Y787110D01*
G01Y789527D02*
X1271460Y789943D01*
X1271877Y790277D01*
X1272460Y790443D01*
X1273043Y790277D01*
X1273460Y789943D01*
X1273710Y789443D01*
Y787110D01*
G01X1280243D02*
Y792110D01*
X1282410Y787943D01*
X1284577Y792110D01*
Y787110D01*
G01X1289510D02*
Y790443D01*
G01Y789860D02*
X1289177Y790193D01*
X1288677Y790360D01*
X1288093Y790443D01*
X1287510Y790277D01*
X1287010Y789943D01*
X1286677Y789443D01*
X1286510Y788777D01*
X1286677Y788110D01*
X1287010Y787610D01*
X1287510Y787277D01*
X1288093Y787110D01*
X1288677Y787193D01*
X1289177Y787443D01*
X1289510Y787777D01*
G01X1292360Y790443D02*
X1294860Y787110D01*
G01Y790443D02*
X1292360Y787110D01*
G01X1299627Y785443D02*
X1300460Y786277D01*
X1300877Y787110D01*
Y790443D01*
X1300460Y791277D01*
X1299627Y792110D01*
G01X1244877Y797230D02*
X1241543Y798897D01*
X1244877Y800563D01*
G01X1247727Y798147D02*
X1249893D01*
G01Y799647D02*
X1247727D01*
G01X1254410Y802230D02*
X1253743Y802063D01*
X1253243Y801647D01*
X1252910Y801147D01*
X1252660Y800480D01*
X1252577Y799730D01*
X1252660Y798980D01*
X1252910Y798313D01*
X1253243Y797813D01*
X1253743Y797397D01*
X1254410Y797230D01*
X1255077Y797397D01*
X1255577Y797813D01*
X1255910Y798313D01*
X1256160Y798980D01*
X1256243Y799730D01*
X1256160Y800480D01*
X1255910Y801147D01*
X1255577Y801647D01*
X1255077Y802063D01*
X1254410Y802230D01*
G01X1260010Y797063D02*
X1259843Y797147D01*
Y797313D01*
X1260010Y797397D01*
X1260177Y797313D01*
Y797147D01*
X1260010Y797063D01*
G01X1265443Y797230D02*
X1265610Y798313D01*
X1265860Y799230D01*
X1266193Y800063D01*
X1266610Y800980D01*
X1267277Y802230D01*
X1263943D01*
G01X1269377Y797980D02*
X1269877Y797563D01*
X1270460Y797313D01*
X1271210Y797230D01*
X1271960Y797397D01*
X1272543Y797730D01*
X1272960Y798313D01*
X1273043Y798980D01*
X1272877Y799647D01*
X1272460Y800063D01*
X1271877Y800397D01*
X1271293Y800480D01*
X1270710Y800397D01*
X1269960Y800063D01*
X1270210Y802230D01*
X1272460D01*
G01X1275310Y797063D02*
X1278310Y802230D01*
G01X1275310D02*
X1274810Y802063D01*
X1274560Y801813D01*
X1274393Y801313D01*
X1274560Y800813D01*
X1274810Y800563D01*
X1275310Y800397D01*
X1275810Y800563D01*
X1276060Y800813D01*
X1276227Y801313D01*
X1276060Y801813D01*
X1275810Y802063D01*
X1275310Y802230D01*
G01X1278310Y798897D02*
X1277810Y798730D01*
X1277560Y798480D01*
X1277393Y797980D01*
X1277560Y797480D01*
X1277810Y797230D01*
X1278310Y797063D01*
X1278810Y797230D01*
X1279060Y797480D01*
X1279227Y797980D01*
X1279060Y798480D01*
X1278810Y798730D01*
X1278310Y798897D01*
G01X1234540Y850500D02*
Y782000D01*
G01X1343000Y850610D02*
Y782110D01*
G54D12*
G01X857602Y628479D02*
X872727D01*
G01X857602Y635354D02*
Y628479D01*
G01X865852Y635354D02*
X843852D01*
G01D02*
Y712354D01*
G01X857602Y721979D02*
Y715104D01*
G01X872727Y721979D02*
X857602D01*
G01X843852Y712354D02*
X865852D01*
G01X898852D02*
Y635354D01*
G01D02*
X942852D01*
G01X907102Y628479D02*
Y635354D01*
G01X891977Y628479D02*
X907102D01*
G01X891977Y721979D02*
Y628479D01*
G01X865852Y712354D02*
Y635354D01*
G01X872727Y628479D02*
Y721979D01*
G01X942852Y712354D02*
X898852D01*
G01X907102Y715104D02*
Y721979D01*
G01D02*
X891977D01*
G01X984102Y628479D02*
Y635354D01*
G01X975852Y712354D02*
Y635354D01*
G01D02*
X1019852D01*
G01X968977Y628479D02*
X984102D01*
G01X968977Y721979D02*
Y628479D01*
G01X949727D02*
Y721979D01*
G01X934602Y628479D02*
X949727D01*
G01X934602Y635354D02*
Y628479D01*
G01X942852Y635354D02*
Y712354D01*
G01X984102Y715104D02*
Y721979D01*
G01X1019852Y712354D02*
X975852D01*
G01X984102Y721979D02*
X968977D01*
G01X934602D02*
Y715104D01*
G01X949727Y721979D02*
X934602D01*
G01X1061102Y628479D02*
Y635354D01*
G01X1045977Y628479D02*
X1061102D01*
G01X1045977Y719229D02*
Y628479D01*
G01X1052852Y712354D02*
Y635354D01*
G01D02*
X1096852D01*
G01X1026727Y628479D02*
Y719229D01*
G01X1019852Y635354D02*
Y712354D01*
G01X1011602Y628479D02*
X1026727D01*
G01X1011602Y635354D02*
Y628479D01*
G01X1061102Y719229D02*
X1045977D01*
G01X1061102Y712354D02*
Y719229D01*
G01X1096852Y712354D02*
X1052852D01*
G01X1011602Y719229D02*
Y712354D01*
G01X1026727Y719229D02*
X1011602D01*
G01X1129852Y712354D02*
Y635354D01*
G01D02*
X1173852D01*
G01X1138102Y628479D02*
Y635354D01*
G01X1122977Y628479D02*
X1138102D01*
G01X1096852Y635354D02*
Y712354D01*
G01X1088602Y628479D02*
X1122977D01*
G01X1088602Y635354D02*
Y628479D01*
G01X1173852Y712354D02*
X1129852D01*
G01X1138102D02*
Y719229D01*
G01D02*
X1103727D01*
G01X1088602D02*
Y712354D01*
G01X1103727Y719229D02*
X1088602D01*
G01X1215102Y628479D02*
Y635354D01*
G01X1206852Y712354D02*
Y635354D01*
G01D02*
X1250852D01*
G01X1199977Y628479D02*
X1215102D01*
G01X1199977Y719229D02*
Y628479D01*
G01X1180727D02*
Y719229D01*
G01X1165602Y628479D02*
X1180727D01*
G01X1165602Y635354D02*
Y628479D01*
G01X1173852Y635354D02*
Y712354D01*
G01X1215102D02*
Y719229D01*
G01X1250852Y712354D02*
X1206852D01*
G01X1215102Y719229D02*
X1199977D01*
G01X1165602D02*
Y712354D01*
G01X1180727Y719229D02*
X1165602D01*
G01X1250852Y635354D02*
Y712354D01*
G54D13*
G01X341590Y319830D02*
Y303830D01*
G01X303090Y319830D02*
Y303830D01*
G01X352590Y340830D02*
Y357830D01*
G01X292090Y340830D02*
Y357830D01*
G01X356482Y330153D02*
X352452Y324663D01*
X356652Y324643D01*
G01X345680Y327680D02*
G02X350362Y319860I-4190J-7820D01*
G01X348190Y321780D01*
X351420Y321950D01*
X350460Y319850D01*
G01X439562Y301543D02*
X435532Y296053D01*
X439732Y296033D01*
G54D14*
G01X856340Y725829D02*
X872925D01*
G01X864151Y719229D02*
X857551Y725829D01*
G01X861818Y719229D02*
X855779Y725267D01*
G01X859485Y719229D02*
X854613Y724101D01*
G01X857327Y719053D02*
X853752Y722628D01*
G01X857327Y716720D02*
X853752Y720295D01*
G01X857327Y714387D02*
X853752Y717961D01*
G01X856750Y712629D02*
X853752Y715628D01*
G01X854417Y712629D02*
X853752Y713295D01*
G01X855058Y712629D02*
X857327Y714899D01*
G01X853752Y713657D02*
X857327Y717232D01*
G01X853752Y715991D02*
X863590Y725829D01*
G01X853752Y718324D02*
X861257Y725829D01*
G01X853752Y720657D02*
X858923Y725829D01*
G01X853752Y722991D02*
X856590Y725829D01*
G01X853752Y723240D02*
X856340Y725829D01*
G01X853752Y712629D02*
Y723240D01*
G01X857327Y712629D02*
X853752D01*
G01X857327Y719504D02*
Y712629D01*
G01X857602Y719229D02*
X857327Y719504D01*
G01X873002Y719229D02*
X857602D01*
G01X891702Y708014D02*
X880607Y719107D01*
G01X891702Y675345D02*
X891096Y675951D01*
G01X890957Y676193D02*
X891702Y676936D01*
G01X889988Y677557D02*
X891702Y679270D01*
G01X888823Y678725D02*
X891702Y681604D01*
G01X887462Y679697D02*
X891702Y683937D01*
G01X885887Y680455D02*
X891702Y686270D01*
G01X884054Y680956D02*
X891702Y688604D01*
G01X881854Y681089D02*
X891702Y690937D01*
G01Y674644D02*
X891701Y674645D01*
G01X891702Y719229D02*
Y674644D01*
G01Y705679D02*
X876553Y720829D01*
G01X891702Y703346D02*
X869219Y725829D01*
G01X891702Y701013D02*
X866886Y725829D01*
G01X891702Y698679D02*
X873002Y717379D01*
G01X891702Y696346D02*
X873002Y715046D01*
G01X891702Y694013D02*
X873002Y712712D01*
G01X891702Y691679D02*
X873002Y710379D01*
G01X891702Y689346D02*
X873002Y708046D01*
G01X891702Y687012D02*
X873002Y705711D01*
G01X891702Y684678D02*
X873002Y703378D01*
G01X891702Y682345D02*
X873002Y701045D01*
G01X891702Y680012D02*
X873002Y698711D01*
G01Y690905D02*
X891702Y709604D01*
G01X873002Y693238D02*
X891702Y711938D01*
G01X873002Y695572D02*
X891702Y714272D01*
G01X873002Y697906D02*
X891702Y716605D01*
G01X873002Y700239D02*
X891702Y718939D01*
G01X873002Y702572D02*
X896258Y725829D01*
G01X873002Y704906D02*
X893925Y725829D01*
G01X873002Y707239D02*
X885106Y719344D01*
G01X891702Y677678D02*
X873002Y696378D01*
G01X887198Y679848D02*
X873002Y694045D01*
G01X883703Y681010D02*
X873002Y691711D01*
G01X881330Y681049D02*
X873002Y689377D01*
G01X879392Y680653D02*
X873002Y687044D01*
G01X877738Y679974D02*
X873002Y684711D01*
G01X876310Y679069D02*
X873002Y682377D01*
G01X875080Y677966D02*
X873002Y680044D01*
G01X874045Y676668D02*
X873002Y677711D01*
G01X873215Y675163D02*
X873002Y675377D01*
G01X878929Y680497D02*
X891702Y693270D01*
G01X873002Y676905D02*
X891702Y695603D01*
G01X873002Y679238D02*
X891702Y697938D01*
G01X873002Y681571D02*
X891702Y700271D01*
G01X873002Y683905D02*
X891702Y702604D01*
G01X873002Y686238D02*
X891702Y704938D01*
G01X873002Y688571D02*
X891702Y707271D01*
G01X873002Y674644D02*
Y719229D01*
G01Y674645D02*
Y674644D01*
G01X891701Y674645D02*
G03X873003I-9349J-3541D01*
G01X936213Y719504D02*
X929888Y725829D01*
G01X934327Y719058D02*
X927555Y725829D01*
G01X934327Y716725D02*
X925222Y725829D01*
G01X934327Y714390D02*
X922888Y725829D01*
G01X933755Y712629D02*
X920555Y725829D01*
G01X931422Y712629D02*
X918222Y725829D01*
G01X929088Y712629D02*
X915888Y725829D01*
G01X926754Y712629D02*
X913554Y725829D01*
G01X929728Y712629D02*
X934327Y717228D01*
G01X927395Y712629D02*
X940595Y725829D01*
G01X925062Y712629D02*
X938260Y725829D01*
G01X922727Y712629D02*
X935927Y725829D01*
G01X920394Y712629D02*
X933594Y725829D01*
G01X918061Y712629D02*
X931260Y725829D01*
G01X915727Y712629D02*
X928927Y725829D01*
G01X913394Y712629D02*
X926593Y725828D01*
G01X924420Y712629D02*
X911221Y725829D01*
G01X891779D02*
X949925D01*
G01X922087Y712629D02*
X908887Y725829D01*
G01X919754Y712629D02*
X906554Y725829D01*
G01X917420Y712629D02*
X904221Y725829D01*
G01X915087Y712629D02*
X901887Y725829D01*
G01X912754Y712629D02*
X907377Y718006D01*
G01X905840Y719543D02*
X899554Y725829D01*
G01X910421Y712629D02*
X907377Y715673D01*
G01X903507Y719543D02*
X897221Y725829D01*
G01X908086Y712629D02*
X907377Y713339D01*
G01X901173Y719543D02*
X894886Y725829D01*
G01X898840Y719543D02*
X892553Y725829D01*
G01X896507Y719543D02*
X891342Y724707D01*
G01X894172Y719543D02*
X890494Y723221D01*
G01X891927Y719455D02*
X889440Y721942D01*
G01X891702Y717347D02*
X888191Y720857D01*
G01X891702Y715014D02*
X886738Y719977D01*
G01X891702Y712680D02*
X885053Y719328D01*
G01X891702Y710347D02*
X883070Y718978D01*
G01X911061Y712629D02*
X924260Y725829D01*
G01X908727Y712629D02*
X921927Y725829D01*
G01X907377Y713613D02*
X919592Y725828D01*
G01X907377Y715946D02*
X917259Y725829D01*
G01X907377Y718280D02*
X914926Y725829D01*
G01X906307Y719543D02*
X912592Y725828D01*
G01X903972Y719543D02*
X910259Y725829D01*
G01X901639Y719543D02*
X907926Y725829D01*
G01X899306Y719543D02*
X905593Y725829D01*
G01X896972Y719543D02*
X903258Y725829D01*
G01X894639Y719543D02*
X900925Y725829D01*
G01X892306Y719543D02*
X898592Y725829D01*
G01X892015Y719543D02*
X891702Y719229D01*
G01X907157Y719543D02*
X892015D01*
G01X907377Y719504D02*
X907157Y719543D01*
G01X907377Y712629D02*
Y719504D01*
G01X934327Y712629D02*
X907377D01*
G01X874327Y723054D02*
X871552Y725829D01*
G01X871152Y719229D02*
X864552Y725829D01*
G01X868819Y719229D02*
X862219Y725829D01*
G01X866485Y719229D02*
X859885Y725829D01*
G01X873002Y709572D02*
X882382Y718952D01*
G01X873002Y711907D02*
X880270Y719174D01*
G01X873002Y714240D02*
X878496Y719734D01*
G01X873002Y716573D02*
X876971Y720542D01*
G01X873002Y718907D02*
X875655Y721560D01*
G01X870991Y719229D02*
X874536Y722775D01*
G01X868658Y719229D02*
X873618Y724189D01*
G01X866324Y719229D02*
X872924Y725829D01*
G01X863991Y719229D02*
X870591Y725829D01*
G01X861658Y719229D02*
X868258Y725829D01*
G01X859323Y719229D02*
X865923Y725829D01*
G01X872925D02*
G03X891779I9427J3024D01*
G01X987952Y632764D02*
X985637Y635078D01*
G01X987952Y630431D02*
X984377Y634006D01*
G01X987952Y628098D02*
X984377Y631673D01*
G01X987225Y626490D02*
X984377Y629338D01*
G01X986058Y625324D02*
X983178Y628204D01*
G01X984377Y629605D02*
X987952Y633180D01*
G01X984377Y631938D02*
X987517Y635079D01*
G01X984377Y634272D02*
X985184Y635079D01*
G01X987952D02*
Y627218D01*
G01X984377Y635079D02*
X987952D01*
G01X984377Y628204D02*
Y635079D01*
G01X984420Y624629D02*
X980845Y628204D01*
G01X984069Y624629D02*
X987952Y628512D01*
G01X981735Y624629D02*
X987952Y630845D01*
G01X979402Y624629D02*
X982977Y628204D01*
G01X987952Y627218D02*
X985362Y624629D01*
G01X982086D02*
X978512Y628204D01*
G01X979752Y624629D02*
X976177Y628204D01*
G01X968702Y635680D02*
X950002Y654380D01*
G01X968702Y633347D02*
X950002Y652047D01*
G01X968702Y631014D02*
X950002Y649713D01*
G01X968702Y628679D02*
X950002Y647379D01*
G01Y630232D02*
X968702Y648932D01*
G01X950002Y632565D02*
X968702Y651265D01*
G01X950002Y634898D02*
X968702Y653598D01*
G01X950002Y637232D02*
X968702Y655931D01*
G01Y628204D02*
X984377D01*
G01X968702Y719504D02*
Y628204D01*
G01X950002D02*
Y719504D01*
G01X977419Y624629D02*
X973844Y628204D01*
G01X975085Y624629D02*
X971511Y628204D01*
G01X972752Y624629D02*
X969177Y628204D01*
G01X970419Y624629D02*
X950002Y645046D01*
G01X968086Y624629D02*
X950002Y642712D01*
G01X965752Y624629D02*
X950002Y640379D01*
G01X963419Y624629D02*
X950002Y638046D01*
G01X961085Y624629D02*
X950002Y635712D01*
G01X958751Y624629D02*
X950002Y633379D01*
G01X956418Y624629D02*
X950002Y631046D01*
G01X954085Y624629D02*
X950002Y628711D01*
G01X951751Y624629D02*
X948176Y628204D01*
G01X977068Y624629D02*
X980642Y628204D01*
G01X974734Y624629D02*
X978309Y628204D01*
G01X972401Y624629D02*
X975976Y628204D01*
G01X970068Y624629D02*
X973643Y628204D01*
G01X967734Y624629D02*
X971309Y628204D01*
G01X965401Y624629D02*
X968976Y628204D01*
G01X963068Y624629D02*
X968702Y630263D01*
G01X960733Y624629D02*
X968702Y632597D01*
G01X958400Y624629D02*
X968702Y634931D01*
G01X956067Y624629D02*
X968702Y637264D01*
G01X953733Y624629D02*
X968702Y639597D01*
G01X951400Y624629D02*
X968702Y641931D01*
G01X949067Y624629D02*
X968702Y644264D01*
G01X946733Y624629D02*
X968702Y646597D01*
G01X949418Y624629D02*
X945843Y628204D01*
G01X947085Y624629D02*
X943510Y628204D01*
G01X934327Y635053D02*
X934300Y635079D01*
G01X934327Y632720D02*
X931967Y635079D01*
G01X934327Y630387D02*
X930752Y633961D01*
G01X933037Y624933D02*
X936307Y628204D01*
G01X931869Y626100D02*
X934327Y628556D01*
G01X930752Y627315D02*
X934327Y630890D01*
G01X930752Y629649D02*
X934327Y633224D01*
G01X930752Y631983D02*
X933848Y635079D01*
G01X930752Y634316D02*
X931515Y635079D01*
G01X934327Y628204D02*
X950002D01*
G01X934327Y635079D02*
Y628204D01*
G01X930752Y635079D02*
X934327D01*
G01X930752Y627218D02*
Y635079D01*
G01X944750Y624629D02*
X941175Y628204D01*
G01X942417Y624629D02*
X938842Y628204D01*
G01X940084Y624629D02*
X936509Y628204D01*
G01X937750Y624629D02*
X930752Y631627D01*
G01X935417Y624629D02*
X930752Y629294D01*
G01X944400Y624629D02*
X947975Y628204D01*
G01X942066Y624629D02*
X945640Y628203D01*
G01X939733Y624629D02*
X943307Y628204D01*
G01X937399Y624629D02*
X940974Y628203D01*
G01X935066Y624629D02*
X938640Y628203D01*
G01X985362Y624629D02*
X933340D01*
G01D02*
X930752Y627218D01*
G01X968702Y708017D02*
X957613Y719106D01*
G01X968702Y705684D02*
X953567Y720819D01*
G01X968702Y698683D02*
X950002Y717383D01*
G01X968702Y696350D02*
X950002Y715049D01*
G01X968702Y694016D02*
X950002Y712716D01*
G01X968702Y691683D02*
X950002Y710383D01*
G01Y690901D02*
X968702Y709601D01*
G01X950002Y693234D02*
X968702Y711934D01*
G01X950002Y695568D02*
X968702Y714267D01*
G01X950002Y697901D02*
X968702Y716601D01*
G01X950002Y700234D02*
X968702Y718934D01*
G01X950002Y702569D02*
X973262Y725828D01*
G01X950002Y704902D02*
X970929Y725829D01*
G01X950002Y707235D02*
X962112Y719345D01*
G01X968702Y689350D02*
X950002Y708049D01*
G01X968702Y687016D02*
X950002Y705716D01*
G01X968702Y684683D02*
X950002Y703383D01*
G01X968702Y682350D02*
X950002Y701048D01*
G01X968702Y680015D02*
X950002Y698715D01*
G01X968702Y677682D02*
X950002Y696382D01*
G01X968702Y675349D02*
X950002Y694048D01*
G01X968702Y673015D02*
X950002Y691715D01*
G01X968702Y670682D02*
X950002Y689382D01*
G01X968702Y668349D02*
X950002Y687048D01*
G01X968702Y666015D02*
X950002Y684715D01*
G01X968702Y663681D02*
X950002Y682381D01*
G01X968702Y661348D02*
X950002Y680047D01*
G01X968702Y659014D02*
X950002Y677714D01*
G01Y658233D02*
X968702Y676932D01*
G01X950002Y660566D02*
X968702Y679266D01*
G01X950002Y662899D02*
X968702Y681599D01*
G01X950002Y665234D02*
X968702Y683932D01*
G01X950002Y667567D02*
X968702Y686267D01*
G01X950002Y669900D02*
X968702Y688600D01*
G01X950002Y672234D02*
X968702Y690933D01*
G01X950002Y674567D02*
X968702Y693267D01*
G01X950002Y676900D02*
X968702Y695600D01*
G01X950002Y679233D02*
X968702Y697933D01*
G01X950002Y681567D02*
X968702Y700267D01*
G01X950002Y683901D02*
X968702Y702601D01*
G01X950002Y686234D02*
X968702Y704934D01*
G01X950002Y688568D02*
X968702Y707268D01*
G01Y656681D02*
X950002Y675381D01*
G01X968702Y654348D02*
X950002Y673048D01*
G01X968702Y652014D02*
X950002Y670714D01*
G01X968702Y649681D02*
X950002Y668381D01*
G01X968702Y647348D02*
X950002Y666048D01*
G01X968702Y645013D02*
X950002Y663713D01*
G01X968702Y642680D02*
X950002Y661380D01*
G01X968702Y640347D02*
X950002Y659047D01*
G01X968702Y638014D02*
X950002Y656713D01*
G01Y639565D02*
X968702Y658265D01*
G01X950002Y641898D02*
X968702Y660598D01*
G01X950002Y644232D02*
X968702Y662931D01*
G01X950002Y646565D02*
X968702Y665265D01*
G01X950002Y648899D02*
X968702Y667599D01*
G01X950002Y651233D02*
X968702Y669932D01*
G01X950002Y653566D02*
X968702Y672266D01*
G01X950002Y655899D02*
X968702Y674599D01*
G01Y703350D02*
X946222Y725829D01*
G01X968702Y701017D02*
X943889Y725829D01*
G01X987952Y721436D02*
X983558Y725829D01*
G01X987952Y719102D02*
X981224Y725829D01*
G01X987952Y714435D02*
X984377Y718009D01*
G01X987424Y712629D02*
X984377Y715676D01*
G01X985091Y712629D02*
X984377Y713343D01*
G01X985731Y712629D02*
X987952Y714850D01*
G01X984377Y713608D02*
X987952Y717183D01*
G01X984377Y715942D02*
X987952Y719517D01*
G01X984377Y718276D02*
X987952Y721851D01*
G01X983271Y719504D02*
X987480Y723712D01*
G01X980938Y719504D02*
X986313Y724879D01*
G01X984377Y712629D02*
Y719504D01*
G01X987952Y712629D02*
X984377D01*
G01X987952Y723240D02*
Y712629D01*
G01X985362Y725829D02*
X987952Y723240D01*
G01Y716769D02*
X978891Y725829D01*
G01X968779D02*
X985362D01*
G01X982883Y719504D02*
X976558Y725829D01*
G01X980549Y719504D02*
X974224Y725829D01*
G01X978216Y719504D02*
X971891Y725829D01*
G01X975883Y719504D02*
X969558Y725829D01*
G01X973548Y719504D02*
X968343Y724709D01*
G01X971215Y719504D02*
X967496Y723223D01*
G01X968882Y719504D02*
X966442Y721943D01*
G01X968702Y717350D02*
X965193Y720859D01*
G01X968702Y715017D02*
X963741Y719978D01*
G01X968702Y712684D02*
X962057Y719329D01*
G01X968702Y710350D02*
X960073Y718978D01*
G01X951317Y723067D02*
X948556Y725829D01*
G01X978605Y719504D02*
X984930Y725829D01*
G01X976271Y719504D02*
X982596Y725829D01*
G01X973938Y719504D02*
X980263Y725829D01*
G01X971605Y719504D02*
X977930Y725829D01*
G01X969271Y719504D02*
X975596Y725829D01*
G01X950002Y709569D02*
X959386Y718952D01*
G01X950002Y711902D02*
X957273Y719173D01*
G01X950002Y714235D02*
X955499Y719733D01*
G01X950002Y716569D02*
X953974Y720540D01*
G01X950002Y718903D02*
X952657Y721558D01*
G01X948269Y719504D02*
X951539Y722772D01*
G01X984377Y719504D02*
X968702D01*
G01X949925Y725829D02*
G03X968779I9427J3024D01*
G01X947881Y719504D02*
X941556Y725829D01*
G01X945548Y719504D02*
X939223Y725829D01*
G01X943214Y719504D02*
X936889Y725829D01*
G01X940881Y719504D02*
X934556Y725829D01*
G01X938546Y719504D02*
X932223Y725829D01*
G01X945936Y719504D02*
X950619Y724187D01*
G01X943603Y719504D02*
X949925Y725826D01*
G01X941270Y719504D02*
X947595Y725829D01*
G01X932061Y712629D02*
X934327Y714894D01*
G01X938936Y719504D02*
X945261Y725829D01*
G01X936603Y719504D02*
X942928Y725829D01*
G01X934327Y719504D02*
Y712629D01*
G01X950002Y719504D02*
X934327D01*
G01X1120658Y632879D02*
X1122702Y634922D01*
G01X1118325Y632879D02*
X1122702Y637256D01*
G01X1115991Y632879D02*
X1122702Y639589D01*
G01X1113658Y632879D02*
X1122702Y641922D01*
G01X1111325Y632879D02*
X1122702Y644257D01*
G01Y714829D02*
Y632879D01*
G01X1108990D02*
X1122702Y646590D01*
G01X1106657Y632879D02*
X1122702Y648923D01*
G01X1104324Y632879D02*
X1122702Y651257D01*
G01X1104002Y634890D02*
X1122702Y653590D01*
G01X1104002Y637224D02*
X1122702Y655923D01*
G01Y635688D02*
X1104002Y654388D01*
G01X1122702Y633354D02*
X1104002Y652054D01*
G01X1120844Y632879D02*
X1104002Y649720D01*
G01X1118510Y632879D02*
X1104002Y647387D01*
G01X1116177Y632879D02*
X1104002Y645054D01*
G01X1113844Y632879D02*
X1104002Y642720D01*
G01X1111509Y632879D02*
X1104002Y640387D01*
G01X1109176Y632879D02*
X1104002Y638054D01*
G01X1106843Y632879D02*
X1104002Y635721D01*
G01X1104509Y632879D02*
X1104002Y633386D01*
G01X1122702Y632879D02*
X1104002D01*
G01D02*
Y714829D01*
G01X1122702Y708025D02*
X1115897Y714829D01*
G01X1122702Y705692D02*
X1113564Y714829D01*
G01X1104002Y690893D02*
X1122702Y709593D01*
G01X1104002Y693226D02*
X1122702Y711926D01*
G01X1104002Y695561D02*
X1122702Y714259D01*
G01X1104002Y697894D02*
X1120937Y714829D01*
G01X1104002Y700227D02*
X1118604Y714829D01*
G01X1104002Y702561D02*
X1116270Y714829D01*
G01X1104002Y704894D02*
X1113937Y714829D01*
G01X1104002Y707227D02*
X1111604Y714829D01*
G01X1122702Y703358D02*
X1111231Y714829D01*
G01X1122702Y701024D02*
X1108897Y714829D01*
G01X1122702Y698691D02*
X1106564Y714829D01*
G01X1122702Y696358D02*
X1104231Y714829D01*
G01X1122702Y694024D02*
X1104002Y712724D01*
G01X1122702Y691691D02*
X1104002Y710391D01*
G01X1122702Y689358D02*
X1104002Y708057D01*
G01X1122702Y687023D02*
X1104002Y705723D01*
G01X1122702Y684690D02*
X1104002Y703390D01*
G01X1122702Y682357D02*
X1104002Y701056D01*
G01X1122702Y680023D02*
X1104002Y698723D01*
G01Y658224D02*
X1122702Y676924D01*
G01X1104002Y660559D02*
X1122702Y679259D01*
G01X1104002Y662892D02*
X1122702Y681592D01*
G01X1104002Y665225D02*
X1122702Y683925D01*
G01X1104002Y667559D02*
X1122702Y686258D01*
G01X1104002Y669892D02*
X1122702Y688592D01*
G01X1104002Y672225D02*
X1122702Y690925D01*
G01X1104002Y674559D02*
X1122702Y693258D01*
G01X1104002Y676892D02*
X1122702Y695592D01*
G01X1104002Y679226D02*
X1122702Y697926D01*
G01X1104002Y681560D02*
X1122702Y700259D01*
G01X1104002Y683893D02*
X1122702Y702593D01*
G01X1104002Y686226D02*
X1122702Y704926D01*
G01X1104002Y688560D02*
X1122702Y707259D01*
G01Y677690D02*
X1104002Y696390D01*
G01X1122702Y675357D02*
X1104002Y694057D01*
G01X1122702Y673023D02*
X1104002Y691723D01*
G01X1122702Y670690D02*
X1104002Y689390D01*
G01X1122702Y668356D02*
X1104002Y687056D01*
G01X1122702Y666022D02*
X1104002Y684722D01*
G01X1122702Y663689D02*
X1104002Y682389D01*
G01X1122702Y661356D02*
X1104002Y680056D01*
G01X1122702Y659023D02*
X1104002Y677722D01*
G01X1122702Y656689D02*
X1104002Y675389D01*
G01X1122702Y654356D02*
X1104002Y673056D01*
G01X1122702Y652023D02*
X1104002Y670721D01*
G01X1122702Y649688D02*
X1104002Y668388D01*
G01X1122702Y647355D02*
X1104002Y666055D01*
G01Y639557D02*
X1122702Y658257D01*
G01X1104002Y641890D02*
X1122702Y660590D01*
G01X1104002Y644225D02*
X1122702Y662924D01*
G01X1104002Y646558D02*
X1122702Y665258D01*
G01X1104002Y648891D02*
X1122702Y667591D01*
G01X1104002Y651225D02*
X1122702Y669924D01*
G01X1104002Y653558D02*
X1122702Y672258D01*
G01X1104002Y655891D02*
X1122702Y674591D01*
G01Y645022D02*
X1104002Y663721D01*
G01X1122702Y642688D02*
X1104002Y661388D01*
G01X1122702Y640355D02*
X1104002Y659055D01*
G01X1122702Y638022D02*
X1104002Y656721D01*
G01X1122702Y712692D02*
X1120565Y714829D01*
G01X1122702Y710359D02*
X1118231Y714829D01*
G01X1104002Y709561D02*
X1109270Y714829D01*
G01X1104002Y711894D02*
X1106937Y714829D01*
G01X1104002Y714228D02*
X1104604Y714829D01*
G01X1104002D02*
X1122702D01*
G01X1197662Y632879D02*
X1199702Y634919D01*
G01X1195328Y632879D02*
X1199702Y637252D01*
G01X1192995Y632879D02*
X1199702Y639586D01*
G01X1190662Y632879D02*
X1199702Y641919D01*
G01X1188328Y632879D02*
X1199702Y644252D01*
G01X1185995Y632879D02*
X1199702Y646585D01*
G01X1183662Y632879D02*
X1199702Y648919D01*
G01X1181327Y632879D02*
X1199702Y651253D01*
G01X1181002Y634887D02*
X1199702Y653586D01*
G01X1181002Y637220D02*
X1199702Y655920D01*
G01Y635692D02*
X1181002Y654392D01*
G01X1199702Y633359D02*
X1181002Y652058D01*
G01X1197847Y632879D02*
X1181002Y649725D01*
G01X1195514Y632879D02*
X1181002Y647392D01*
G01X1193181Y632879D02*
X1181002Y645057D01*
G01X1190847Y632879D02*
X1181002Y642724D01*
G01X1188514Y632879D02*
X1181002Y640391D01*
G01X1186181Y632879D02*
X1181002Y638057D01*
G01X1183846Y632879D02*
X1181002Y635724D01*
G01X1181513Y632879D02*
X1181002Y633391D01*
G01X1199702Y632879D02*
X1181002D01*
G01X1199702Y714829D02*
Y632879D01*
G01X1181002D02*
Y714829D01*
G01Y690889D02*
X1199702Y709589D01*
G01X1181002Y693223D02*
X1199702Y711922D01*
G01X1181002Y695556D02*
X1199702Y714256D01*
G01X1181002Y697889D02*
X1197941Y714829D01*
G01X1181002Y700223D02*
X1195608Y714829D01*
G01X1181002Y702557D02*
X1193275Y714829D01*
G01X1181002Y704890D02*
X1190940Y714829D01*
G01X1181002Y707224D02*
X1188607Y714829D01*
G01X1199702Y708029D02*
X1192902Y714829D01*
G01X1199702Y705696D02*
X1190569Y714829D01*
G01X1199702Y703362D02*
X1188234Y714829D01*
G01X1199702Y701029D02*
X1185901Y714829D01*
G01X1199702Y698696D02*
X1183568Y714829D01*
G01X1199702Y696361D02*
X1181234Y714829D01*
G01X1199702Y694028D02*
X1181002Y712728D01*
G01X1199702Y691695D02*
X1181002Y710394D01*
G01Y658221D02*
X1199702Y676921D01*
G01X1181002Y660554D02*
X1199702Y679254D01*
G01X1181002Y662888D02*
X1199702Y681587D01*
G01X1181002Y665221D02*
X1199702Y683921D01*
G01X1181002Y667555D02*
X1199702Y686255D01*
G01X1181002Y669888D02*
X1199702Y688588D01*
G01X1181002Y672222D02*
X1199702Y690922D01*
G01X1181002Y674555D02*
X1199702Y693255D01*
G01X1181002Y676888D02*
X1199702Y695588D01*
G01X1181002Y679222D02*
X1199702Y697922D01*
G01X1181002Y681555D02*
X1199702Y700255D01*
G01X1181002Y683888D02*
X1199702Y702588D01*
G01X1181002Y686223D02*
X1199702Y704922D01*
G01X1181002Y688556D02*
X1199702Y707256D01*
G01Y689361D02*
X1181002Y708061D01*
G01X1199702Y687028D02*
X1181002Y705728D01*
G01X1199702Y684695D02*
X1181002Y703394D01*
G01X1199702Y682361D02*
X1181002Y701061D01*
G01X1199702Y680027D02*
X1181002Y698727D01*
G01X1199702Y677694D02*
X1181002Y696393D01*
G01X1199702Y675360D02*
X1181002Y694060D01*
G01X1199702Y673027D02*
X1181002Y691727D01*
G01X1199702Y670694D02*
X1181002Y689393D01*
G01X1199702Y668360D02*
X1181002Y687060D01*
G01X1199702Y666027D02*
X1181002Y684727D01*
G01X1199702Y663694D02*
X1181002Y682392D01*
G01X1199702Y661359D02*
X1181002Y680059D01*
G01X1199702Y659026D02*
X1181002Y677726D01*
G01Y639553D02*
X1199702Y658253D01*
G01X1181002Y641887D02*
X1199702Y660586D01*
G01X1181002Y644220D02*
X1199702Y662920D01*
G01X1181002Y646553D02*
X1199702Y665253D01*
G01X1181002Y648888D02*
X1199702Y667586D01*
G01X1181002Y651221D02*
X1199702Y669921D01*
G01X1181002Y653554D02*
X1199702Y672254D01*
G01X1181002Y655888D02*
X1199702Y674587D01*
G01Y656693D02*
X1181002Y675393D01*
G01X1199702Y654359D02*
X1181002Y673059D01*
G01X1199702Y652026D02*
X1181002Y670726D01*
G01X1199702Y649693D02*
X1181002Y668393D01*
G01X1199702Y647360D02*
X1181002Y666059D01*
G01X1199702Y645025D02*
X1181002Y663725D01*
G01X1199702Y642692D02*
X1181002Y661392D01*
G01X1199702Y640359D02*
X1181002Y659058D01*
G01X1199702Y638025D02*
X1181002Y656725D01*
G01Y709557D02*
X1186274Y714829D01*
G01X1181002Y711890D02*
X1183940Y714829D01*
G01X1181002Y714224D02*
X1181607Y714829D01*
G01X1199702Y712695D02*
X1197568Y714829D01*
G01X1199702Y710362D02*
X1195235Y714829D01*
G01X1181002D02*
X1199702D01*
M02*
